FILE_TYPE=EXPANDEDPARTLIST;
{ Allegro Design Entry HDL run on 09:53:44 Monday, April 27, 2020 }
DIRECTIVES
 PST_VERSION='PST_HDL_CENTRIC_VERSION_0';
 ROOT_DRAWING='S9S_MB_2U';
 POST_TIME='09:53:44 Monday, April 27, 2020';
 SOURCE_TOOL='PACKAGER_XL';
 VAR_0_ONSEMI = '' ;
 VAR_DEF_ONSEMI = '' ;
 VDES_ONSEMI = '*' ;
 VDNI_ONSEMI = 'DNI' ;
 VPROP_ONSEMI = 'VARIANT' ;
 ALTERNATE_VALUE = '3' ;
END_DIRECTIVES;

PART_NAME
 U103 'MAX9634TEUK-MAX9634TEUK+,SMLF,A':;

SECTION_NUMBER 1
 '@S9S_MB_2U_LIB.S9S_MB_2U(SCH_1):PAGE625_I12@PURE_QUANTA.MAX9634TEUK(CHIPS)':
 C_PATH='@s9s_mb_2u_lib.s9s_mb_2u(sch_1):page625_i12@pure_quanta.max9634teuk(chips~
)';

PART_NAME
 U102 'MAX9634TEUK-MAX9634TEUK+,SMLF,A':;

SECTION_NUMBER 1
 '@S9S_MB_2U_LIB.S9S_MB_2U(SCH_1):PAGE625_I17@PURE_QUANTA.MAX9634TEUK(CHIPS)':
 C_PATH='@s9s_mb_2u_lib.s9s_mb_2u(sch_1):page625_i17@pure_quanta.max9634teuk(chips~
)';

PART_NAME
 R1838 'Q_RES_4P_12-0.001,1%,3W,SMLF,CA':;

SECTION_NUMBER 1
 '@S9S_MB_2U_LIB.S9S_MB_2U(SCH_1):PAGE625_I5@PURE_QUANTA.Q_RES_4P_12(CHIPS)':
 C_PATH='@s9s_mb_a_lib.s9s_mb_a(sch_1):page625_i5@pure_quanta.q_res_4p_12(chips)~
';

PART_NAME
 R1837 'Q_RES_4P_12-0.001,1%,3W,SMLF,CA':;

SECTION_NUMBER 1
 '@S9S_MB_2U_LIB.S9S_MB_2U(SCH_1):PAGE625_I1@PURE_QUANTA.Q_RES_4P_12(CHIPS)':
 C_PATH='@s9s_mb_a_lib.s9s_mb_a(sch_1):page625_i1@pure_quanta.q_res_4p_12(chips)~
';

PART_NAME
 R1681 'Q_RES_0402LF-10K,1%,1/16W,CHIPA':;

SECTION_NUMBER 1
 '@S9S_MB_2U_LIB.S9S_MB_2U(SCH_1):PAGE543_I130@PURE_QUANTA.Q_RES(CHIPS)':
 C_PATH='@s9s_mb_2u_lib.s9s_mb_2u(sch_1):page543_i130@pure_quanta.q_res(chips)';

PART_NAME
 R1503 'Q_RES_0402LF-10K,1%,1/16W,EMPTA':;

SECTION_NUMBER 1
 '@S9S_MB_2U_LIB.S9S_MB_2U(SCH_1):PAGE15_I35@PURE_QUANTA.Q_RES(CHIPS)':
 C_PATH='@s9s_mb_2u_lib.s9s_mb_2u(sch_1):page15_i35@pure_quanta.q_res(chips)';

PART_NAME
 R1931 'Q_RES_0402LF-0,5%,1/16W,CHIP,CA':;

SECTION_NUMBER 1
 '@S9S_MB_2U_LIB.S9S_MB_2U(SCH_1):PAGE541_I92@PURE_QUANTA.Q_RES(CHIPS)':
 C_PATH='@s9s_mb_2u_lib.s9s_mb_2u(sch_1):page541_i92@pure_quanta.q_res(chips)';

PART_NAME
 R1853 'Q_RES_0402LF-0,5%,1/16W,CHIP,CA':;

SECTION_NUMBER 1
 '@S9S_MB_2U_LIB.S9S_MB_2U(SCH_1):PAGE541_I84@PURE_QUANTA.Q_RES(CHIPS)':
 C_PATH='@s9s_mb_2u_lib.s9s_mb_2u(sch_1):page541_i84@pure_quanta.q_res(chips)';

PART_NAME
 R1606 'Q_RES_0402LF-0,5%,1/16W,CHIP,CA':;

SECTION_NUMBER 1
 '@S9S_MB_2U_LIB.S9S_MB_2U(SCH_1):PAGE541_I71@PURE_QUANTA.Q_RES(CHIPS)':
 C_PATH='@s9s_mb_2u_lib.s9s_mb_2u(sch_1):page541_i71@pure_quanta.q_res(chips)';

PART_NAME
 R1556 'Q_RES_0402LF-0,5%,1/16W,EMPTY,A':;

SECTION_NUMBER 1
 '@S9S_MB_2U_LIB.S9S_MB_2U(SCH_1):PAGE541_I75@PURE_QUANTA.Q_RES(CHIPS)':
 C_PATH='@s9s_mb_2u_lib.s9s_mb_2u(sch_1):page541_i75@pure_quanta.q_res(chips)';

PART_NAME
 R1551 'Q_RES_0402LF-4.7K,1%,1/16W,EMPA':;

SECTION_NUMBER 1
 '@S9S_MB_2U_LIB.S9S_MB_2U(SCH_1):PAGE541_I55@PURE_QUANTA.Q_RES(CHIPS)':
 C_PATH='@s9s_mb_2u_lib.s9s_mb_2u(sch_1):page541_i55@pure_quanta.q_res(chips)';

PART_NAME
 R1547 'Q_RES_0402LF-0,5%,1/16W,CHIP,CA':;

SECTION_NUMBER 1
 '@S9S_MB_2U_LIB.S9S_MB_2U(SCH_1):PAGE541_I73@PURE_QUANTA.Q_RES(CHIPS)':
 C_PATH='@s9s_mb_2u_lib.s9s_mb_2u(sch_1):page541_i73@pure_quanta.q_res(chips)';

PART_NAME
 R1467 'Q_RES_0402LF-4.7K,1%,1/16W,EMPA':;

SECTION_NUMBER 1
 '@S9S_MB_2U_LIB.S9S_MB_2U(SCH_1):PAGE541_I56@PURE_QUANTA.Q_RES(CHIPS)':
 C_PATH='@s9s_mb_2u_lib.s9s_mb_2u(sch_1):page541_i56@pure_quanta.q_res(chips)';

PART_NAME
 R1465 'Q_RES_0402LF-10K,1%,1/16W,EMPTA':;

SECTION_NUMBER 1
 '@S9S_MB_2U_LIB.S9S_MB_2U(SCH_1):PAGE541_I51@PURE_QUANTA.Q_RES(CHIPS)':
 C_PATH='@s9s_mb_2u_lib.s9s_mb_2u(sch_1):page541_i51@pure_quanta.q_res(chips)';

PART_NAME
 R1245 'Q_RES_0402LF-0,5%,1/16W,CHIP,CA':;

SECTION_NUMBER 1
 '@S9S_MB_2U_LIB.S9S_MB_2U(SCH_1):PAGE479_I10@PURE_QUANTA.Q_RES(CHIPS)':
 C_PATH='@s9s_mb_2u_lib.s9s_mb_2u(sch_1):page479_i10@pure_quanta.q_res(chips)';

PART_NAME
 R1244 'Q_RES_0402LF-301,1%,1/16W,CHIPA':;

SECTION_NUMBER 1
 '@S9S_MB_2U_LIB.S9S_MB_2U(SCH_1):PAGE479_I16@PURE_QUANTA.Q_RES(CHIPS)':
 C_PATH='@s9s_mb_2u_lib.s9s_mb_2u(sch_1):page479_i16@pure_quanta.q_res(chips)';

PART_NAME
 R1243 'Q_RES_0402LF-249,1%,1/16W,CHIPA':;

SECTION_NUMBER 1
 '@S9S_MB_2U_LIB.S9S_MB_2U(SCH_1):PAGE479_I19@PURE_QUANTA.Q_RES(CHIPS)':
 C_PATH='@s9s_mb_2u_lib.s9s_mb_2u(sch_1):page479_i19@pure_quanta.q_res(chips)';

PART_NAME
 R1242 'Q_RES_0402LF-301,1%,1/16W,CHIPA':;

SECTION_NUMBER 1
 '@S9S_MB_2U_LIB.S9S_MB_2U(SCH_1):PAGE479_I13@PURE_QUANTA.Q_RES(CHIPS)':
 C_PATH='@s9s_mb_2u_lib.s9s_mb_2u(sch_1):page479_i13@pure_quanta.q_res(chips)';

PART_NAME
 R1241 'Q_RES_0402LF-249,1%,1/16W,CHIPA':;

SECTION_NUMBER 1
 '@S9S_MB_2U_LIB.S9S_MB_2U(SCH_1):PAGE479_I17@PURE_QUANTA.Q_RES(CHIPS)':
 C_PATH='@s9s_mb_2u_lib.s9s_mb_2u(sch_1):page479_i17@pure_quanta.q_res(chips)';

PART_NAME
 R1240 'Q_RES_0402LF-0,5%,1/16W,CHIP,CA':;

SECTION_NUMBER 1
 '@S9S_MB_2U_LIB.S9S_MB_2U(SCH_1):PAGE479_I9@PURE_QUANTA.Q_RES(CHIPS)':
 C_PATH='@s9s_mb_2u_lib.s9s_mb_2u(sch_1):page479_i9@pure_quanta.q_res(chips)';

PART_NAME
 R1023 'Q_RES_0402LF-0,5%,1/16W,CHIP,CA':;

SECTION_NUMBER 1
 '@S9S_MB_2U_LIB.S9S_MB_2U(SCH_1):PAGE537_I8@PURE_QUANTA.Q_RES(CHIPS)':
 C_PATH='@s9s_mb_2u_lib.s9s_mb_2u(sch_1):page537_i8@pure_quanta.q_res(chips)';

PART_NAME
 R1022 'Q_RES_0402LF-0,5%,1/16W,CHIP,CA':;

SECTION_NUMBER 1
 '@S9S_MB_2U_LIB.S9S_MB_2U(SCH_1):PAGE537_I7@PURE_QUANTA.Q_RES(CHIPS)':
 C_PATH='@s9s_mb_2u_lib.s9s_mb_2u(sch_1):page537_i7@pure_quanta.q_res(chips)';

PART_NAME
 R1021 'Q_RES_0402LF-0,5%,1/16W,CHIP,CA':;

SECTION_NUMBER 1
 '@S9S_MB_2U_LIB.S9S_MB_2U(SCH_1):PAGE537_I6@PURE_QUANTA.Q_RES(CHIPS)':
 C_PATH='@s9s_mb_2u_lib.s9s_mb_2u(sch_1):page537_i6@pure_quanta.q_res(chips)';

PART_NAME
 R1020 'Q_RES_0402LF-0,5%,1/16W,CHIP,CA':;

SECTION_NUMBER 1
 '@S9S_MB_2U_LIB.S9S_MB_2U(SCH_1):PAGE537_I5@PURE_QUANTA.Q_RES(CHIPS)':
 C_PATH='@s9s_mb_2u_lib.s9s_mb_2u(sch_1):page537_i5@pure_quanta.q_res(chips)';

PART_NAME
 R1019 'Q_RES_0402LF-0,5%,1/16W,EMPTY,A':;

SECTION_NUMBER 1
 '@S9S_MB_2U_LIB.S9S_MB_2U(SCH_1):PAGE537_I21@PURE_QUANTA.Q_RES(CHIPS)':
 C_PATH='@s9s_mb_2u_lib.s9s_mb_2u(sch_1):page537_i21@pure_quanta.q_res(chips)';

PART_NAME
 R1018 'Q_RES_0402LF-0,5%,1/16W,CHIP,CA':;

SECTION_NUMBER 1
 '@S9S_MB_2U_LIB.S9S_MB_2U(SCH_1):PAGE537_I20@PURE_QUANTA.Q_RES(CHIPS)':
 C_PATH='@s9s_mb_2u_lib.s9s_mb_2u(sch_1):page537_i20@pure_quanta.q_res(chips)';

PART_NAME
 R1017 'Q_RES_0402LF-0,5%,1/16W,EMPTY,A':;

SECTION_NUMBER 1
 '@S9S_MB_2U_LIB.S9S_MB_2U(SCH_1):PAGE537_I19@PURE_QUANTA.Q_RES(CHIPS)':
 C_PATH='@s9s_mb_2u_lib.s9s_mb_2u(sch_1):page537_i19@pure_quanta.q_res(chips)';

PART_NAME
 R1016 'Q_RES_0402LF-0,5%,1/16W,CHIP,CA':;

SECTION_NUMBER 1
 '@S9S_MB_2U_LIB.S9S_MB_2U(SCH_1):PAGE537_I18@PURE_QUANTA.Q_RES(CHIPS)':
 C_PATH='@s9s_mb_2u_lib.s9s_mb_2u(sch_1):page537_i18@pure_quanta.q_res(chips)';

PART_NAME
 R1015 'Q_RES_0402LF-0,5%,1/16W,EMPTY,A':;

SECTION_NUMBER 1
 '@S9S_MB_2U_LIB.S9S_MB_2U(SCH_1):PAGE537_I12@PURE_QUANTA.Q_RES(CHIPS)':
 C_PATH='@s9s_mb_2u_lib.s9s_mb_2u(sch_1):page537_i12@pure_quanta.q_res(chips)';

PART_NAME
 R1014 'Q_RES_0402LF-0,5%,1/16W,CHIP,CA':;

SECTION_NUMBER 1
 '@S9S_MB_2U_LIB.S9S_MB_2U(SCH_1):PAGE537_I13@PURE_QUANTA.Q_RES(CHIPS)':
 C_PATH='@s9s_mb_2u_lib.s9s_mb_2u(sch_1):page537_i13@pure_quanta.q_res(chips)';

PART_NAME
 R1013 'Q_RES_0402LF-0,5%,1/16W,EMPTY,A':;

SECTION_NUMBER 1
 '@S9S_MB_2U_LIB.S9S_MB_2U(SCH_1):PAGE537_I11@PURE_QUANTA.Q_RES(CHIPS)':
 C_PATH='@s9s_mb_2u_lib.s9s_mb_2u(sch_1):page537_i11@pure_quanta.q_res(chips)';

PART_NAME
 R1012 'Q_RES_0402LF-0,5%,1/16W,CHIP,CA':;

SECTION_NUMBER 1
 '@S9S_MB_2U_LIB.S9S_MB_2U(SCH_1):PAGE537_I10@PURE_QUANTA.Q_RES(CHIPS)':
 C_PATH='@s9s_mb_2u_lib.s9s_mb_2u(sch_1):page537_i10@pure_quanta.q_res(chips)';

PART_NAME
 R1011 'Q_RES_0402LF-0,5%,1/16W,CHIP,CA':;

SECTION_NUMBER 1
 '@S9S_MB_2U_LIB.S9S_MB_2U(SCH_1):PAGE537_I29@PURE_QUANTA.Q_RES(CHIPS)':
 C_PATH='@s9s_mb_2u_lib.s9s_mb_2u(sch_1):page537_i29@pure_quanta.q_res(chips)';

PART_NAME
 R1010 'Q_RES_0402LF-0,5%,1/16W,CHIP,CA':;

SECTION_NUMBER 1
 '@S9S_MB_2U_LIB.S9S_MB_2U(SCH_1):PAGE537_I22@PURE_QUANTA.Q_RES(CHIPS)':
 C_PATH='@s9s_mb_2u_lib.s9s_mb_2u(sch_1):page537_i22@pure_quanta.q_res(chips)';

PART_NAME
 R1919 'Q_RES_0402LF-33.2,1%,1/16W,CHIA':;

SECTION_NUMBER 1
 '@S9S_MB_2U_LIB.S9S_MB_2U(SCH_1):PAGE549_I127@PURE_QUANTA.Q_RES(CHIPS)':
 C_PATH='@s9s_mb_2u_lib.s9s_mb_2u(sch_1):page549_i127@pure_quanta.q_res(chips)';

PART_NAME
 R1844 'Q_RES_0402LF-33.2,1%,1/16W,CHIA':;

SECTION_NUMBER 1
 '@S9S_MB_2U_LIB.S9S_MB_2U(SCH_1):PAGE549_I123@PURE_QUANTA.Q_RES(CHIPS)':
 C_PATH='@s9s_mb_2u_lib.s9s_mb_2u(sch_1):page549_i123@pure_quanta.q_res(chips)';

PART_NAME
 R1843 'Q_RES_0402LF-33.2,1%,1/16W,CHIA':;

SECTION_NUMBER 1
 '@S9S_MB_2U_LIB.S9S_MB_2U(SCH_1):PAGE549_I122@PURE_QUANTA.Q_RES(CHIPS)':
 C_PATH='@s9s_mb_2u_lib.s9s_mb_2u(sch_1):page549_i122@pure_quanta.q_res(chips)';

PART_NAME
 R1842 'Q_RES_0402LF-33.2,1%,1/16W,CHIA':;

SECTION_NUMBER 1
 '@S9S_MB_2U_LIB.S9S_MB_2U(SCH_1):PAGE549_I115@PURE_QUANTA.Q_RES(CHIPS)':
 C_PATH='@s9s_mb_2u_lib.s9s_mb_2u(sch_1):page549_i115@pure_quanta.q_res(chips)';

PART_NAME
 R1812 'Q_RES_0402LF-33.2,1%,1/16W,CHIA':;

SECTION_NUMBER 1
 '@S9S_MB_2U_LIB.S9S_MB_2U(SCH_1):PAGE549_I111@PURE_QUANTA.Q_RES(CHIPS)':
 C_PATH='@s9s_mb_2u_lib.s9s_mb_2u(sch_1):page549_i111@pure_quanta.q_res(chips)';

PART_NAME
 R1811 'Q_RES_0402LF-33.2,1%,1/16W,CHIA':;

SECTION_NUMBER 1
 '@S9S_MB_2U_LIB.S9S_MB_2U(SCH_1):PAGE549_I110@PURE_QUANTA.Q_RES(CHIPS)':
 C_PATH='@s9s_mb_2u_lib.s9s_mb_2u(sch_1):page549_i110@pure_quanta.q_res(chips)';

PART_NAME
 R1758 'Q_RES_0402LF-33.2,1%,1/16W,CHIA':;

SECTION_NUMBER 1
 '@S9S_MB_2U_LIB.S9S_MB_2U(SCH_1):PAGE549_I91@PURE_QUANTA.Q_RES(CHIPS)':
 C_PATH='@s9s_mb_2u_lib.s9s_mb_2u(sch_1):page549_i91@pure_quanta.q_res(chips)';

PART_NAME
 R1757 'Q_RES_0402LF-33.2,1%,1/16W,CHIA':;

SECTION_NUMBER 1
 '@S9S_MB_2U_LIB.S9S_MB_2U(SCH_1):PAGE549_I99@PURE_QUANTA.Q_RES(CHIPS)':
 C_PATH='@s9s_mb_2u_lib.s9s_mb_2u(sch_1):page549_i99@pure_quanta.q_res(chips)';

PART_NAME
 R1756 'Q_RES_0402LF-33.2,1%,1/16W,CHIA':;

SECTION_NUMBER 1
 '@S9S_MB_2U_LIB.S9S_MB_2U(SCH_1):PAGE549_I98@PURE_QUANTA.Q_RES(CHIPS)':
 C_PATH='@s9s_mb_2u_lib.s9s_mb_2u(sch_1):page549_i98@pure_quanta.q_res(chips)';

PART_NAME
 R1755 'Q_RES_0402LF-33.2,1%,1/16W,CHIA':;

SECTION_NUMBER 1
 '@S9S_MB_2U_LIB.S9S_MB_2U(SCH_1):PAGE549_I96@PURE_QUANTA.Q_RES(CHIPS)':
 C_PATH='@s9s_mb_2u_lib.s9s_mb_2u(sch_1):page549_i96@pure_quanta.q_res(chips)';

PART_NAME
 R1754 'Q_RES_0402LF-33.2,1%,1/16W,CHIA':;

SECTION_NUMBER 1
 '@S9S_MB_2U_LIB.S9S_MB_2U(SCH_1):PAGE549_I88@PURE_QUANTA.Q_RES(CHIPS)':
 C_PATH='@s9s_mb_2u_lib.s9s_mb_2u(sch_1):page549_i88@pure_quanta.q_res(chips)';

PART_NAME
 R1753 'Q_RES_0402LF-33.2,1%,1/16W,CHIA':;

SECTION_NUMBER 1
 '@S9S_MB_2U_LIB.S9S_MB_2U(SCH_1):PAGE549_I84@PURE_QUANTA.Q_RES(CHIPS)':
 C_PATH='@s9s_mb_2u_lib.s9s_mb_2u(sch_1):page549_i84@pure_quanta.q_res(chips)';

PART_NAME
 R1752 'Q_RES_0402LF-33.2,1%,1/16W,CHIA':;

SECTION_NUMBER 1
 '@S9S_MB_2U_LIB.S9S_MB_2U(SCH_1):PAGE549_I82@PURE_QUANTA.Q_RES(CHIPS)':
 C_PATH='@s9s_mb_2u_lib.s9s_mb_2u(sch_1):page549_i82@pure_quanta.q_res(chips)';

PART_NAME
 R1751 'Q_RES_0402LF-33.2,1%,1/16W,CHIA':;

SECTION_NUMBER 1
 '@S9S_MB_2U_LIB.S9S_MB_2U(SCH_1):PAGE549_I81@PURE_QUANTA.Q_RES(CHIPS)':
 C_PATH='@s9s_mb_2u_lib.s9s_mb_2u(sch_1):page549_i81@pure_quanta.q_res(chips)';

PART_NAME
 R1448 'Q_RES_0402LF-33.2,1%,1/16W,CHIA':;

SECTION_NUMBER 1
 '@S9S_MB_2U_LIB.S9S_MB_2U(SCH_1):PAGE549_I62@PURE_QUANTA.Q_RES(CHIPS)':
 C_PATH='@s9s_mb_2u_lib.s9s_mb_2u(sch_1):page549_i62@pure_quanta.q_res(chips)';

PART_NAME
 R1447 'Q_RES_0402LF-33.2,1%,1/16W,CHIA':;

SECTION_NUMBER 1
 '@S9S_MB_2U_LIB.S9S_MB_2U(SCH_1):PAGE549_I68@PURE_QUANTA.Q_RES(CHIPS)':
 C_PATH='@s9s_mb_2u_lib.s9s_mb_2u(sch_1):page549_i68@pure_quanta.q_res(chips)';

PART_NAME
 R1446 'Q_RES_0402LF-33.2,1%,1/16W,CHIA':;

SECTION_NUMBER 1
 '@S9S_MB_2U_LIB.S9S_MB_2U(SCH_1):PAGE549_I61@PURE_QUANTA.Q_RES(CHIPS)':
 C_PATH='@s9s_mb_2u_lib.s9s_mb_2u(sch_1):page549_i61@pure_quanta.q_res(chips)';

PART_NAME
 R1444 'Q_RES_0402LF-33.2,1%,1/16W,CHIA':;

SECTION_NUMBER 1
 '@S9S_MB_2U_LIB.S9S_MB_2U(SCH_1):PAGE549_I54@PURE_QUANTA.Q_RES(CHIPS)':
 C_PATH='@s9s_mb_2u_lib.s9s_mb_2u(sch_1):page549_i54@pure_quanta.q_res(chips)';

PART_NAME
 R1443 'Q_RES_0402LF-33.2,1%,1/16W,CHIA':;

SECTION_NUMBER 1
 '@S9S_MB_2U_LIB.S9S_MB_2U(SCH_1):PAGE549_I49@PURE_QUANTA.Q_RES(CHIPS)':
 C_PATH='@s9s_mb_2u_lib.s9s_mb_2u(sch_1):page549_i49@pure_quanta.q_res(chips)';

PART_NAME
 R1442 'Q_RES_0402LF-33.2,1%,1/16W,CHIA':;

SECTION_NUMBER 1
 '@S9S_MB_2U_LIB.S9S_MB_2U(SCH_1):PAGE549_I48@PURE_QUANTA.Q_RES(CHIPS)':
 C_PATH='@s9s_mb_2u_lib.s9s_mb_2u(sch_1):page549_i48@pure_quanta.q_res(chips)';

PART_NAME
 R1423 'Q_RES_0402LF-33.2,1%,1/16W,CHIA':;

SECTION_NUMBER 1
 '@S9S_MB_2U_LIB.S9S_MB_2U(SCH_1):PAGE549_I44@PURE_QUANTA.Q_RES(CHIPS)':
 C_PATH='@s9s_mb_2u_lib.s9s_mb_2u(sch_1):page549_i44@pure_quanta.q_res(chips)';

PART_NAME
 R1101 'Q_RES_0402LF-200,1%,1/16W,CHIPA':;

SECTION_NUMBER 1
 '@S9S_MB_2U_LIB.S9S_MB_2U(SCH_1):PAGE549_I74@PURE_QUANTA.Q_RES(CHIPS)':
 C_PATH='@s9s_mb_2u_lib.s9s_mb_2u(sch_1):page549_i74@pure_quanta.q_res(chips)';

PART_NAME
 R988 'Q_RES_0402LF-33,5%,1/16W,CHIP,A':;

SECTION_NUMBER 1
 '@S9S_MB_2U_LIB.S9S_MB_2U(SCH_1):PAGE549_I23@PURE_QUANTA.Q_RES(CHIPS)':
 C_PATH='@s9s_mb_2u_lib.s9s_mb_2u(sch_1):page549_i23@pure_quanta.q_res(chips)';

PART_NAME
 R987 'Q_RES_0402LF-33,5%,1/16W,CHIP,A':;

SECTION_NUMBER 1
 '@S9S_MB_2U_LIB.S9S_MB_2U(SCH_1):PAGE549_I24@PURE_QUANTA.Q_RES(CHIPS)':
 C_PATH='@s9s_mb_2u_lib.s9s_mb_2u(sch_1):page549_i24@pure_quanta.q_res(chips)';

PART_NAME
 R986 'Q_RES_0402LF-33,5%,1/16W,CHIP,A':;

SECTION_NUMBER 1
 '@S9S_MB_2U_LIB.S9S_MB_2U(SCH_1):PAGE549_I25@PURE_QUANTA.Q_RES(CHIPS)':
 C_PATH='@s9s_mb_2u_lib.s9s_mb_2u(sch_1):page549_i25@pure_quanta.q_res(chips)';

PART_NAME
 R985 'Q_RES_0402LF-33,5%,1/16W,CHIP,A':;

SECTION_NUMBER 1
 '@S9S_MB_2U_LIB.S9S_MB_2U(SCH_1):PAGE549_I21@PURE_QUANTA.Q_RES(CHIPS)':
 C_PATH='@s9s_mb_2u_lib.s9s_mb_2u(sch_1):page549_i21@pure_quanta.q_res(chips)';

PART_NAME
 R984 'Q_RES_0402LF-33,5%,1/16W,CHIP,A':;

SECTION_NUMBER 1
 '@S9S_MB_2U_LIB.S9S_MB_2U(SCH_1):PAGE549_I15@PURE_QUANTA.Q_RES(CHIPS)':
 C_PATH='@s9s_mb_2u_lib.s9s_mb_2u(sch_1):page549_i15@pure_quanta.q_res(chips)';

PART_NAME
 R983 'Q_RES_0402LF-33,5%,1/16W,CHIP,A':;

SECTION_NUMBER 1
 '@S9S_MB_2U_LIB.S9S_MB_2U(SCH_1):PAGE549_I13@PURE_QUANTA.Q_RES(CHIPS)':
 C_PATH='@s9s_mb_2u_lib.s9s_mb_2u(sch_1):page549_i13@pure_quanta.q_res(chips)';

PART_NAME
 R982 'Q_RES_0402LF-33,5%,1/16W,CHIP,A':;

SECTION_NUMBER 1
 '@S9S_MB_2U_LIB.S9S_MB_2U(SCH_1):PAGE549_I10@PURE_QUANTA.Q_RES(CHIPS)':
 C_PATH='@s9s_mb_2u_lib.s9s_mb_2u(sch_1):page549_i10@pure_quanta.q_res(chips)';

PART_NAME
 R981 'Q_RES_0402LF-33,5%,1/16W,CHIP,A':;

SECTION_NUMBER 1
 '@S9S_MB_2U_LIB.S9S_MB_2U(SCH_1):PAGE549_I9@PURE_QUANTA.Q_RES(CHIPS)':
 C_PATH='@s9s_mb_2u_lib.s9s_mb_2u(sch_1):page549_i9@pure_quanta.q_res(chips)';

PART_NAME
 R947 'Q_RES_0402LF-1K,1%,1/16W,CHIP,A':;

SECTION_NUMBER 1
 '@S9S_MB_2U_LIB.S9S_MB_2U(SCH_1):PAGE476_I157@PURE_QUANTA.Q_RES(CHIPS)':
 C_PATH='@s9s_mb_2u_lib.s9s_mb_2u(sch_1):page476_i157@pure_quanta.q_res(chips)';

PART_NAME
 R946 'Q_RES_0402LF-1K,1%,1/16W,CHIP,A':;

SECTION_NUMBER 1
 '@S9S_MB_2U_LIB.S9S_MB_2U(SCH_1):PAGE476_I156@PURE_QUANTA.Q_RES(CHIPS)':
 C_PATH='@s9s_mb_2u_lib.s9s_mb_2u(sch_1):page476_i156@pure_quanta.q_res(chips)';

PART_NAME
 R945 'Q_RES_0402LF-1K,1%,1/16W,CHIP,A':;

SECTION_NUMBER 1
 '@S9S_MB_2U_LIB.S9S_MB_2U(SCH_1):PAGE476_I154@PURE_QUANTA.Q_RES(CHIPS)':
 C_PATH='@s9s_mb_2u_lib.s9s_mb_2u(sch_1):page476_i154@pure_quanta.q_res(chips)';

PART_NAME
 R944 'Q_RES_0402LF-1K,1%,1/16W,CHIP,A':;

SECTION_NUMBER 1
 '@S9S_MB_2U_LIB.S9S_MB_2U(SCH_1):PAGE476_I153@PURE_QUANTA.Q_RES(CHIPS)':
 C_PATH='@s9s_mb_2u_lib.s9s_mb_2u(sch_1):page476_i153@pure_quanta.q_res(chips)';

PART_NAME
 R943 'Q_RES_0402LF-1K,1%,1/16W,CHIP,A':;

SECTION_NUMBER 1
 '@S9S_MB_2U_LIB.S9S_MB_2U(SCH_1):PAGE476_I148@PURE_QUANTA.Q_RES(CHIPS)':
 C_PATH='@s9s_mb_2u_lib.s9s_mb_2u(sch_1):page476_i148@pure_quanta.q_res(chips)';

PART_NAME
 R942 'Q_RES_0402LF-1K,1%,1/16W,CHIP,A':;

SECTION_NUMBER 1
 '@S9S_MB_2U_LIB.S9S_MB_2U(SCH_1):PAGE476_I147@PURE_QUANTA.Q_RES(CHIPS)':
 C_PATH='@s9s_mb_2u_lib.s9s_mb_2u(sch_1):page476_i147@pure_quanta.q_res(chips)';

PART_NAME
 R941 'Q_RES_0402LF-1K,1%,1/16W,CHIP,A':;

SECTION_NUMBER 1
 '@S9S_MB_2U_LIB.S9S_MB_2U(SCH_1):PAGE476_I146@PURE_QUANTA.Q_RES(CHIPS)':
 C_PATH='@s9s_mb_2u_lib.s9s_mb_2u(sch_1):page476_i146@pure_quanta.q_res(chips)';

PART_NAME
 R940 'Q_RES_0402LF-1K,1%,1/16W,CHIP,A':;

SECTION_NUMBER 1
 '@S9S_MB_2U_LIB.S9S_MB_2U(SCH_1):PAGE476_I145@PURE_QUANTA.Q_RES(CHIPS)':
 C_PATH='@s9s_mb_2u_lib.s9s_mb_2u(sch_1):page476_i145@pure_quanta.q_res(chips)';

PART_NAME
 R908 'Q_RES_0402LF-33,5%,1/16W,CHIP,A':;

SECTION_NUMBER 1
 '@S9S_MB_2U_LIB.S9S_MB_2U(SCH_1):PAGE476_I119@PURE_QUANTA.Q_RES(CHIPS)':
 C_PATH='@s9s_mb_2u_lib.s9s_mb_2u(sch_1):page476_i119@pure_quanta.q_res(chips)';

PART_NAME
 R907 'Q_RES_0402LF-33,5%,1/16W,CHIP,A':;

SECTION_NUMBER 1
 '@S9S_MB_2U_LIB.S9S_MB_2U(SCH_1):PAGE476_I118@PURE_QUANTA.Q_RES(CHIPS)':
 C_PATH='@s9s_mb_2u_lib.s9s_mb_2u(sch_1):page476_i118@pure_quanta.q_res(chips)';

PART_NAME
 R906 'Q_RES_0402LF-33,5%,1/16W,CHIP,A':;

SECTION_NUMBER 1
 '@S9S_MB_2U_LIB.S9S_MB_2U(SCH_1):PAGE476_I117@PURE_QUANTA.Q_RES(CHIPS)':
 C_PATH='@s9s_mb_2u_lib.s9s_mb_2u(sch_1):page476_i117@pure_quanta.q_res(chips)';

PART_NAME
 R905 'Q_RES_0402LF-33,5%,1/16W,CHIP,A':;

SECTION_NUMBER 1
 '@S9S_MB_2U_LIB.S9S_MB_2U(SCH_1):PAGE476_I116@PURE_QUANTA.Q_RES(CHIPS)':
 C_PATH='@s9s_mb_2u_lib.s9s_mb_2u(sch_1):page476_i116@pure_quanta.q_res(chips)';

PART_NAME
 R904 'Q_RES_0402LF-33,5%,1/16W,CHIP,A':;

SECTION_NUMBER 1
 '@S9S_MB_2U_LIB.S9S_MB_2U(SCH_1):PAGE476_I115@PURE_QUANTA.Q_RES(CHIPS)':
 C_PATH='@s9s_mb_2u_lib.s9s_mb_2u(sch_1):page476_i115@pure_quanta.q_res(chips)';

PART_NAME
 R903 'Q_RES_0402LF-33,5%,1/16W,CHIP,A':;

SECTION_NUMBER 1
 '@S9S_MB_2U_LIB.S9S_MB_2U(SCH_1):PAGE476_I114@PURE_QUANTA.Q_RES(CHIPS)':
 C_PATH='@s9s_mb_2u_lib.s9s_mb_2u(sch_1):page476_i114@pure_quanta.q_res(chips)';

PART_NAME
 R902 'Q_RES_0402LF-33,5%,1/16W,CHIP,A':;

SECTION_NUMBER 1
 '@S9S_MB_2U_LIB.S9S_MB_2U(SCH_1):PAGE476_I113@PURE_QUANTA.Q_RES(CHIPS)':
 C_PATH='@s9s_mb_2u_lib.s9s_mb_2u(sch_1):page476_i113@pure_quanta.q_res(chips)';

PART_NAME
 R901 'Q_RES_0402LF-33,5%,1/16W,CHIP,A':;

SECTION_NUMBER 1
 '@S9S_MB_2U_LIB.S9S_MB_2U(SCH_1):PAGE476_I112@PURE_QUANTA.Q_RES(CHIPS)':
 C_PATH='@s9s_mb_2u_lib.s9s_mb_2u(sch_1):page476_i112@pure_quanta.q_res(chips)';

PART_NAME
 R900 'Q_RES_0402LF-33,5%,1/16W,CHIP,A':;

SECTION_NUMBER 1
 '@S9S_MB_2U_LIB.S9S_MB_2U(SCH_1):PAGE476_I111@PURE_QUANTA.Q_RES(CHIPS)':
 C_PATH='@s9s_mb_2u_lib.s9s_mb_2u(sch_1):page476_i111@pure_quanta.q_res(chips)';

PART_NAME
 R899 'Q_RES_0402LF-33,5%,1/16W,CHIP,A':;

SECTION_NUMBER 1
 '@S9S_MB_2U_LIB.S9S_MB_2U(SCH_1):PAGE476_I110@PURE_QUANTA.Q_RES(CHIPS)':
 C_PATH='@s9s_mb_2u_lib.s9s_mb_2u(sch_1):page476_i110@pure_quanta.q_res(chips)';

PART_NAME
 R898 'Q_RES_0402LF-33,5%,1/16W,CHIP,A':;

SECTION_NUMBER 1
 '@S9S_MB_2U_LIB.S9S_MB_2U(SCH_1):PAGE476_I108@PURE_QUANTA.Q_RES(CHIPS)':
 C_PATH='@s9s_mb_2u_lib.s9s_mb_2u(sch_1):page476_i108@pure_quanta.q_res(chips)';

PART_NAME
 R897 'Q_RES_0402LF-33,5%,1/16W,CHIP,A':;

SECTION_NUMBER 1
 '@S9S_MB_2U_LIB.S9S_MB_2U(SCH_1):PAGE476_I109@PURE_QUANTA.Q_RES(CHIPS)':
 C_PATH='@s9s_mb_2u_lib.s9s_mb_2u(sch_1):page476_i109@pure_quanta.q_res(chips)';

PART_NAME
 R896 'Q_RES_0402LF-33,5%,1/16W,CHIP,A':;

SECTION_NUMBER 1
 '@S9S_MB_2U_LIB.S9S_MB_2U(SCH_1):PAGE476_I107@PURE_QUANTA.Q_RES(CHIPS)':
 C_PATH='@s9s_mb_2u_lib.s9s_mb_2u(sch_1):page476_i107@pure_quanta.q_res(chips)';

PART_NAME
 R895 'Q_RES_0402LF-33,5%,1/16W,CHIP,A':;

SECTION_NUMBER 1
 '@S9S_MB_2U_LIB.S9S_MB_2U(SCH_1):PAGE476_I106@PURE_QUANTA.Q_RES(CHIPS)':
 C_PATH='@s9s_mb_2u_lib.s9s_mb_2u(sch_1):page476_i106@pure_quanta.q_res(chips)';

PART_NAME
 R894 'Q_RES_0402LF-33,5%,1/16W,CHIP,A':;

SECTION_NUMBER 1
 '@S9S_MB_2U_LIB.S9S_MB_2U(SCH_1):PAGE476_I105@PURE_QUANTA.Q_RES(CHIPS)':
 C_PATH='@s9s_mb_2u_lib.s9s_mb_2u(sch_1):page476_i105@pure_quanta.q_res(chips)';

PART_NAME
 R893 'Q_RES_0402LF-33,5%,1/16W,CHIP,A':;

SECTION_NUMBER 1
 '@S9S_MB_2U_LIB.S9S_MB_2U(SCH_1):PAGE476_I104@PURE_QUANTA.Q_RES(CHIPS)':
 C_PATH='@s9s_mb_2u_lib.s9s_mb_2u(sch_1):page476_i104@pure_quanta.q_res(chips)';

PART_NAME
 R892 'Q_RES_0402LF-33,5%,1/16W,CHIP,A':;

SECTION_NUMBER 1
 '@S9S_MB_2U_LIB.S9S_MB_2U(SCH_1):PAGE476_I76@PURE_QUANTA.Q_RES(CHIPS)':
 C_PATH='@s9s_mb_2u_lib.s9s_mb_2u(sch_1):page476_i76@pure_quanta.q_res(chips)';

PART_NAME
 R891 'Q_RES_0402LF-33,5%,1/16W,CHIP,A':;

SECTION_NUMBER 1
 '@S9S_MB_2U_LIB.S9S_MB_2U(SCH_1):PAGE476_I87@PURE_QUANTA.Q_RES(CHIPS)':
 C_PATH='@s9s_mb_2u_lib.s9s_mb_2u(sch_1):page476_i87@pure_quanta.q_res(chips)';

PART_NAME
 R890 'Q_RES_0402LF-33,5%,1/16W,CHIP,A':;

SECTION_NUMBER 1
 '@S9S_MB_2U_LIB.S9S_MB_2U(SCH_1):PAGE476_I85@PURE_QUANTA.Q_RES(CHIPS)':
 C_PATH='@s9s_mb_2u_lib.s9s_mb_2u(sch_1):page476_i85@pure_quanta.q_res(chips)';

PART_NAME
 R889 'Q_RES_0402LF-33,5%,1/16W,CHIP,A':;

SECTION_NUMBER 1
 '@S9S_MB_2U_LIB.S9S_MB_2U(SCH_1):PAGE476_I86@PURE_QUANTA.Q_RES(CHIPS)':
 C_PATH='@s9s_mb_2u_lib.s9s_mb_2u(sch_1):page476_i86@pure_quanta.q_res(chips)';

PART_NAME
 R888 'Q_RES_0402LF-33,5%,1/16W,CHIP,A':;

SECTION_NUMBER 1
 '@S9S_MB_2U_LIB.S9S_MB_2U(SCH_1):PAGE476_I84@PURE_QUANTA.Q_RES(CHIPS)':
 C_PATH='@s9s_mb_2u_lib.s9s_mb_2u(sch_1):page476_i84@pure_quanta.q_res(chips)';

PART_NAME
 R887 'Q_RES_0402LF-33,5%,1/16W,CHIP,A':;

SECTION_NUMBER 1
 '@S9S_MB_2U_LIB.S9S_MB_2U(SCH_1):PAGE476_I83@PURE_QUANTA.Q_RES(CHIPS)':
 C_PATH='@s9s_mb_2u_lib.s9s_mb_2u(sch_1):page476_i83@pure_quanta.q_res(chips)';

PART_NAME
 R886 'Q_RES_0402LF-33,5%,1/16W,CHIP,A':;

SECTION_NUMBER 1
 '@S9S_MB_2U_LIB.S9S_MB_2U(SCH_1):PAGE476_I82@PURE_QUANTA.Q_RES(CHIPS)':
 C_PATH='@s9s_mb_2u_lib.s9s_mb_2u(sch_1):page476_i82@pure_quanta.q_res(chips)';

PART_NAME
 R885 'Q_RES_0402LF-33,5%,1/16W,CHIP,A':;

SECTION_NUMBER 1
 '@S9S_MB_2U_LIB.S9S_MB_2U(SCH_1):PAGE476_I81@PURE_QUANTA.Q_RES(CHIPS)':
 C_PATH='@s9s_mb_2u_lib.s9s_mb_2u(sch_1):page476_i81@pure_quanta.q_res(chips)';

PART_NAME
 R884 'Q_RES_0402LF-33,5%,1/16W,CHIP,A':;

SECTION_NUMBER 1
 '@S9S_MB_2U_LIB.S9S_MB_2U(SCH_1):PAGE476_I74@PURE_QUANTA.Q_RES(CHIPS)':
 C_PATH='@s9s_mb_2u_lib.s9s_mb_2u(sch_1):page476_i74@pure_quanta.q_res(chips)';

PART_NAME
 R883 'Q_RES_0402LF-33,5%,1/16W,CHIP,A':;

SECTION_NUMBER 1
 '@S9S_MB_2U_LIB.S9S_MB_2U(SCH_1):PAGE476_I73@PURE_QUANTA.Q_RES(CHIPS)':
 C_PATH='@s9s_mb_2u_lib.s9s_mb_2u(sch_1):page476_i73@pure_quanta.q_res(chips)';

PART_NAME
 R882 'Q_RES_0402LF-33,5%,1/16W,CHIP,A':;

SECTION_NUMBER 1
 '@S9S_MB_2U_LIB.S9S_MB_2U(SCH_1):PAGE476_I72@PURE_QUANTA.Q_RES(CHIPS)':
 C_PATH='@s9s_mb_2u_lib.s9s_mb_2u(sch_1):page476_i72@pure_quanta.q_res(chips)';

PART_NAME
 R881 'Q_RES_0402LF-33,5%,1/16W,CHIP,A':;

SECTION_NUMBER 1
 '@S9S_MB_2U_LIB.S9S_MB_2U(SCH_1):PAGE476_I71@PURE_QUANTA.Q_RES(CHIPS)':
 C_PATH='@s9s_mb_2u_lib.s9s_mb_2u(sch_1):page476_i71@pure_quanta.q_res(chips)';

PART_NAME
 R880 'Q_RES_0402LF-33,5%,1/16W,CHIP,A':;

SECTION_NUMBER 1
 '@S9S_MB_2U_LIB.S9S_MB_2U(SCH_1):PAGE476_I61@PURE_QUANTA.Q_RES(CHIPS)':
 C_PATH='@s9s_mb_2u_lib.s9s_mb_2u(sch_1):page476_i61@pure_quanta.q_res(chips)';

PART_NAME
 R879 'Q_RES_0402LF-33,5%,1/16W,CHIP,A':;

SECTION_NUMBER 1
 '@S9S_MB_2U_LIB.S9S_MB_2U(SCH_1):PAGE476_I63@PURE_QUANTA.Q_RES(CHIPS)':
 C_PATH='@s9s_mb_2u_lib.s9s_mb_2u(sch_1):page476_i63@pure_quanta.q_res(chips)';

PART_NAME
 R878 'Q_RES_0402LF-33,5%,1/16W,CHIP,A':;

SECTION_NUMBER 1
 '@S9S_MB_2U_LIB.S9S_MB_2U(SCH_1):PAGE476_I59@PURE_QUANTA.Q_RES(CHIPS)':
 C_PATH='@s9s_mb_2u_lib.s9s_mb_2u(sch_1):page476_i59@pure_quanta.q_res(chips)';

PART_NAME
 R877 'Q_RES_0402LF-33,5%,1/16W,CHIP,A':;

SECTION_NUMBER 1
 '@S9S_MB_2U_LIB.S9S_MB_2U(SCH_1):PAGE476_I34@PURE_QUANTA.Q_RES(CHIPS)':
 C_PATH='@s9s_mb_2u_lib.s9s_mb_2u(sch_1):page476_i34@pure_quanta.q_res(chips)';

PART_NAME
 R1817 'Q_RES_0402LF-0,5%,1/16W,CHIP,CA':;

SECTION_NUMBER 1
 '@S9S_MB_2U_LIB.S9S_MB_2U(SCH_1):PAGE530_I34@PURE_QUANTA.Q_RES(CHIPS)':
 C_PATH='@s9s_mb_2u_lib.s9s_mb_2u(sch_1):page530_i34@pure_quanta.q_res(chips)';

PART_NAME
 R1456 'Q_RES_0402LF-49.9     ,1%  ,1/A':;

SECTION_NUMBER 1
 '@S9S_MB_2U_LIB.S9S_MB_2U(SCH_1):PAGE530_I28@PURE_QUANTA.Q_RES(CHIPS)':
 C_PATH='@s9s_mb_2u_lib.s9s_mb_2u(sch_1):page530_i28@pure_quanta.q_res(chips)';

PART_NAME
 R1455 'Q_RES_0402LF-49.9     ,1%  ,1/A':;

SECTION_NUMBER 1
 '@S9S_MB_2U_LIB.S9S_MB_2U(SCH_1):PAGE530_I27@PURE_QUANTA.Q_RES(CHIPS)':
 C_PATH='@s9s_mb_2u_lib.s9s_mb_2u(sch_1):page530_i27@pure_quanta.q_res(chips)';

PART_NAME
 R1313 'Q_RES_0402LF-33.2,1%,1/16W,CHIA':;

SECTION_NUMBER 1
 '@S9S_MB_2U_LIB.S9S_MB_2U(SCH_1):PAGE530_I21@PURE_QUANTA.Q_RES(CHIPS)':
 C_PATH='@s9s_mb_2u_lib.s9s_mb_2u(sch_1):page530_i21@pure_quanta.q_res(chips)';

PART_NAME
 R1310 'Q_RES_0402LF-33.2,1%,1/16W,CHIA':;

SECTION_NUMBER 1
 '@S9S_MB_2U_LIB.S9S_MB_2U(SCH_1):PAGE530_I20@PURE_QUANTA.Q_RES(CHIPS)':
 C_PATH='@s9s_mb_2u_lib.s9s_mb_2u(sch_1):page530_i20@pure_quanta.q_res(chips)';

PART_NAME
 R1309 'Q_RES_0402LF-33.2,1%,1/16W,CHIA':;

SECTION_NUMBER 1
 '@S9S_MB_2U_LIB.S9S_MB_2U(SCH_1):PAGE530_I10@PURE_QUANTA.Q_RES(CHIPS)':
 C_PATH='@s9s_mb_2u_lib.s9s_mb_2u(sch_1):page530_i10@pure_quanta.q_res(chips)';

PART_NAME
 R1307 'Q_RES_0402LF-33.2,1%,1/16W,CHIA':;

SECTION_NUMBER 1
 '@S9S_MB_2U_LIB.S9S_MB_2U(SCH_1):PAGE530_I3@PURE_QUANTA.Q_RES(CHIPS)':
 C_PATH='@s9s_mb_2u_lib.s9s_mb_2u(sch_1):page530_i3@pure_quanta.q_res(chips)';

PART_NAME
 R1306 'Q_RES_0402LF-33.2,1%,1/16W,CHIA':;

SECTION_NUMBER 1
 '@S9S_MB_2U_LIB.S9S_MB_2U(SCH_1):PAGE530_I13@PURE_QUANTA.Q_RES(CHIPS)':
 C_PATH='@s9s_mb_2u_lib.s9s_mb_2u(sch_1):page530_i13@pure_quanta.q_res(chips)';

PART_NAME
 R1300 'Q_RES_0402LF-33.2,1%,1/16W,CHIA':;

SECTION_NUMBER 1
 '@S9S_MB_2U_LIB.S9S_MB_2U(SCH_1):PAGE530_I5@PURE_QUANTA.Q_RES(CHIPS)':
 C_PATH='@s9s_mb_2u_lib.s9s_mb_2u(sch_1):page530_i5@pure_quanta.q_res(chips)';

PART_NAME
 R698 'Q_RES_0402LF-49.9     ,1%  ,1/A':;

SECTION_NUMBER 1
 '@S9S_MB_2U_LIB.S9S_MB_2U(SCH_1):PAGE530_I32@PURE_QUANTA.Q_RES(CHIPS)':
 C_PATH='@s9s_mb_2u_lib.s9s_mb_2u(sch_1):page530_i32@pure_quanta.q_res(chips)';

PART_NAME
 R624 'Q_RES_0402LF-10K,1%,1/16W,CHIPA':;

SECTION_NUMBER 1
 '@S9S_MB_2U_LIB.S9S_MB_2U(SCH_1):PAGE466_I14@PURE_QUANTA.Q_RES(CHIPS)':
 C_PATH='@s9s_mb_2u_lib.s9s_mb_2u(sch_1):page466_i14@pure_quanta.q_res(chips)';

PART_NAME
 R623 'Q_RES_0402LF-1K,5%,1/16W,EMPTYA':;

SECTION_NUMBER 1
 '@S9S_MB_2U_LIB.S9S_MB_2U(SCH_1):PAGE466_I13@PURE_QUANTA.Q_RES(CHIPS)':
 C_PATH='@s9s_mb_2u_lib.s9s_mb_2u(sch_1):page466_i13@pure_quanta.q_res(chips)';

PART_NAME
 R622 'Q_RES_0402LF-1K,5%,1/16W,CHIP,A':;

SECTION_NUMBER 1
 '@S9S_MB_2U_LIB.S9S_MB_2U(SCH_1):PAGE466_I56@PURE_QUANTA.Q_RES(CHIPS)':
 C_PATH='@s9s_mb_2u_lib.s9s_mb_2u(sch_1):page466_i56@pure_quanta.q_res(chips)';

PART_NAME
 R621 'Q_RES_0402LF-1K,5%,1/16W,EMPTYA':;

SECTION_NUMBER 1
 '@S9S_MB_2U_LIB.S9S_MB_2U(SCH_1):PAGE466_I55@PURE_QUANTA.Q_RES(CHIPS)':
 C_PATH='@s9s_mb_2u_lib.s9s_mb_2u(sch_1):page466_i55@pure_quanta.q_res(chips)';

PART_NAME
 R619 'Q_RES_0402LF-10K,1%,1/16W,CHIPA':;

SECTION_NUMBER 1
 '@S9S_MB_2U_LIB.S9S_MB_2U(SCH_1):PAGE466_I48@PURE_QUANTA.Q_RES(CHIPS)':
 C_PATH='@s9s_mb_2u_lib.s9s_mb_2u(sch_1):page466_i48@pure_quanta.q_res(chips)';

PART_NAME
 R618 'Q_RES_0402LF-10K,1%,1/16W,CHIPA':;

SECTION_NUMBER 1
 '@S9S_MB_2U_LIB.S9S_MB_2U(SCH_1):PAGE466_I53@PURE_QUANTA.Q_RES(CHIPS)':
 C_PATH='@s9s_mb_2u_lib.s9s_mb_2u(sch_1):page466_i53@pure_quanta.q_res(chips)';

PART_NAME
 R617 'Q_RES_0402LF-1K,5%,1/16W,EMPTYA':;

SECTION_NUMBER 1
 '@S9S_MB_2U_LIB.S9S_MB_2U(SCH_1):PAGE466_I54@PURE_QUANTA.Q_RES(CHIPS)':
 C_PATH='@s9s_mb_2u_lib.s9s_mb_2u(sch_1):page466_i54@pure_quanta.q_res(chips)';

PART_NAME
 R615 'Q_RES_0402LF-1K,5%,1/16W,CHIP,A':;

SECTION_NUMBER 1
 '@S9S_MB_2U_LIB.S9S_MB_2U(SCH_1):PAGE466_I51@PURE_QUANTA.Q_RES(CHIPS)':
 C_PATH='@s9s_mb_2u_lib.s9s_mb_2u(sch_1):page466_i51@pure_quanta.q_res(chips)';

PART_NAME
 R614 'Q_RES_0402LF-1K,5%,1/16W,EMPTYA':;

SECTION_NUMBER 1
 '@S9S_MB_2U_LIB.S9S_MB_2U(SCH_1):PAGE466_I23@PURE_QUANTA.Q_RES(CHIPS)':
 C_PATH='@s9s_mb_2u_lib.s9s_mb_2u(sch_1):page466_i23@pure_quanta.q_res(chips)';

PART_NAME
 R613 'Q_RES_0402LF-10K,1%,1/16W,CHIPA':;

SECTION_NUMBER 1
 '@S9S_MB_2U_LIB.S9S_MB_2U(SCH_1):PAGE466_I18@PURE_QUANTA.Q_RES(CHIPS)':
 C_PATH='@s9s_mb_2u_lib.s9s_mb_2u(sch_1):page466_i18@pure_quanta.q_res(chips)';

PART_NAME
 R612 'Q_RES_0402LF-10K,1%,1/16W,EMPTA':;

SECTION_NUMBER 1
 '@S9S_MB_2U_LIB.S9S_MB_2U(SCH_1):PAGE466_I44@PURE_QUANTA.Q_RES(CHIPS)':
 C_PATH='@s9s_mb_2u_lib.s9s_mb_2u(sch_1):page466_i44@pure_quanta.q_res(chips)';

PART_NAME
 R611 'Q_RES_0402LF-1K,5%,1/16W,CHIP,A':;

SECTION_NUMBER 1
 '@S9S_MB_2U_LIB.S9S_MB_2U(SCH_1):PAGE466_I43@PURE_QUANTA.Q_RES(CHIPS)':
 C_PATH='@s9s_mb_2u_lib.s9s_mb_2u(sch_1):page466_i43@pure_quanta.q_res(chips)';

PART_NAME
 R610 'Q_RES_0402LF-10K,1%,1/16W,CHIPA':;

SECTION_NUMBER 1
 '@S9S_MB_2U_LIB.S9S_MB_2U(SCH_1):PAGE466_I40@PURE_QUANTA.Q_RES(CHIPS)':
 C_PATH='@s9s_mb_2u_lib.s9s_mb_2u(sch_1):page466_i40@pure_quanta.q_res(chips)';

PART_NAME
 R609 'Q_RES_0402LF-1K,5%,1/16W,EMPTYA':;

SECTION_NUMBER 1
 '@S9S_MB_2U_LIB.S9S_MB_2U(SCH_1):PAGE466_I39@PURE_QUANTA.Q_RES(CHIPS)':
 C_PATH='@s9s_mb_2u_lib.s9s_mb_2u(sch_1):page466_i39@pure_quanta.q_res(chips)';

PART_NAME
 R608 'Q_RES_0402LF-10K,1%,1/16W,CHIPA':;

SECTION_NUMBER 1
 '@S9S_MB_2U_LIB.S9S_MB_2U(SCH_1):PAGE466_I36@PURE_QUANTA.Q_RES(CHIPS)':
 C_PATH='@s9s_mb_2u_lib.s9s_mb_2u(sch_1):page466_i36@pure_quanta.q_res(chips)';

PART_NAME
 R607 'Q_RES_0402LF-1K,5%,1/16W,EMPTYA':;

SECTION_NUMBER 1
 '@S9S_MB_2U_LIB.S9S_MB_2U(SCH_1):PAGE466_I21@PURE_QUANTA.Q_RES(CHIPS)':
 C_PATH='@s9s_mb_2u_lib.s9s_mb_2u(sch_1):page466_i21@pure_quanta.q_res(chips)';

PART_NAME
 R1364 'Q_RES_0402LF-0,5%,1/16W,CHIP,CA':;

SECTION_NUMBER 1
 '@S9S_MB_2U_LIB.S9S_MB_2U(SCH_1):PAGE533_I161@PURE_QUANTA.Q_RES(CHIPS)':
 C_PATH='@s9s_mb_2u_lib.s9s_mb_2u(sch_1):page533_i161@pure_quanta.q_res(chips)';

PART_NAME
 R1363 'Q_RES_0402LF-0,5%,1/16W,CHIP,CA':;

SECTION_NUMBER 1
 '@S9S_MB_2U_LIB.S9S_MB_2U(SCH_1):PAGE533_I164@PURE_QUANTA.Q_RES(CHIPS)':
 C_PATH='@s9s_mb_2u_lib.s9s_mb_2u(sch_1):page533_i164@pure_quanta.q_res(chips)';

PART_NAME
 R1362 'Q_RES_0402LF-0,5%,1/16W,CHIP,CA':;

SECTION_NUMBER 1
 '@S9S_MB_2U_LIB.S9S_MB_2U(SCH_1):PAGE533_I159@PURE_QUANTA.Q_RES(CHIPS)':
 C_PATH='@s9s_mb_2u_lib.s9s_mb_2u(sch_1):page533_i159@pure_quanta.q_res(chips)';

PART_NAME
 R1361 'Q_RES_0402LF-0,5%,1/16W,CHIP,CA':;

SECTION_NUMBER 1
 '@S9S_MB_2U_LIB.S9S_MB_2U(SCH_1):PAGE533_I160@PURE_QUANTA.Q_RES(CHIPS)':
 C_PATH='@s9s_mb_2u_lib.s9s_mb_2u(sch_1):page533_i160@pure_quanta.q_res(chips)';

PART_NAME
 R1360 'Q_RES_0402LF-0,5%,1/16W,CHIP,CA':;

SECTION_NUMBER 1
 '@S9S_MB_2U_LIB.S9S_MB_2U(SCH_1):PAGE533_I167@PURE_QUANTA.Q_RES(CHIPS)':
 C_PATH='@s9s_mb_2u_lib.s9s_mb_2u(sch_1):page533_i167@pure_quanta.q_res(chips)';

PART_NAME
 R1359 'Q_RES_0402LF-0,5%,1/16W,CHIP,CA':;

SECTION_NUMBER 1
 '@S9S_MB_2U_LIB.S9S_MB_2U(SCH_1):PAGE533_I175@PURE_QUANTA.Q_RES(CHIPS)':
 C_PATH='@s9s_mb_2u_lib.s9s_mb_2u(sch_1):page533_i175@pure_quanta.q_res(chips)';

PART_NAME
 R1358 'Q_RES_0402LF-0,5%,1/16W,CHIP,CA':;

SECTION_NUMBER 1
 '@S9S_MB_2U_LIB.S9S_MB_2U(SCH_1):PAGE533_I174@PURE_QUANTA.Q_RES(CHIPS)':
 C_PATH='@s9s_mb_2u_lib.s9s_mb_2u(sch_1):page533_i174@pure_quanta.q_res(chips)';

PART_NAME
 R1357 'Q_RES_0402LF-0,5%,1/16W,CHIP,CA':;

SECTION_NUMBER 1
 '@S9S_MB_2U_LIB.S9S_MB_2U(SCH_1):PAGE533_I173@PURE_QUANTA.Q_RES(CHIPS)':
 C_PATH='@s9s_mb_2u_lib.s9s_mb_2u(sch_1):page533_i173@pure_quanta.q_res(chips)';

PART_NAME
 R1288 'Q_RES_0402LF-0,5%,1/16W,CHIP,CA':;

SECTION_NUMBER 1
 '@S9S_MB_2U_LIB.S9S_MB_2U(SCH_1):PAGE533_I149@PURE_QUANTA.Q_RES(CHIPS)':
 C_PATH='@s9s_mb_2u_lib.s9s_mb_2u(sch_1):page533_i149@pure_quanta.q_res(chips)';

PART_NAME
 R1287 'Q_RES_0402LF-0,5%,1/16W,CHIP,CA':;

SECTION_NUMBER 1
 '@S9S_MB_2U_LIB.S9S_MB_2U(SCH_1):PAGE533_I150@PURE_QUANTA.Q_RES(CHIPS)':
 C_PATH='@s9s_mb_2u_lib.s9s_mb_2u(sch_1):page533_i150@pure_quanta.q_res(chips)';

PART_NAME
 R1286 'Q_RES_0402LF-0,5%,1/16W,CHIP,CA':;

SECTION_NUMBER 1
 '@S9S_MB_2U_LIB.S9S_MB_2U(SCH_1):PAGE533_I151@PURE_QUANTA.Q_RES(CHIPS)':
 C_PATH='@s9s_mb_2u_lib.s9s_mb_2u(sch_1):page533_i151@pure_quanta.q_res(chips)';

PART_NAME
 R1285 'Q_RES_0402LF-0,5%,1/16W,CHIP,CA':;

SECTION_NUMBER 1
 '@S9S_MB_2U_LIB.S9S_MB_2U(SCH_1):PAGE533_I152@PURE_QUANTA.Q_RES(CHIPS)':
 C_PATH='@s9s_mb_2u_lib.s9s_mb_2u(sch_1):page533_i152@pure_quanta.q_res(chips)';

PART_NAME
 R554 'Q_RES_0402LF-0,5%,1/16W,CHIP,CA':;

SECTION_NUMBER 1
 '@S9S_MB_2U_LIB.S9S_MB_2U(SCH_1):PAGE533_I110@PURE_QUANTA.Q_RES(CHIPS)':
 C_PATH='@s9s_mb_2u_lib.s9s_mb_2u(sch_1):page533_i110@pure_quanta.q_res(chips)';

PART_NAME
 R553 'Q_RES_0402LF-0,5%,1/16W,CHIP,CA':;

SECTION_NUMBER 1
 '@S9S_MB_2U_LIB.S9S_MB_2U(SCH_1):PAGE533_I109@PURE_QUANTA.Q_RES(CHIPS)':
 C_PATH='@s9s_mb_2u_lib.s9s_mb_2u(sch_1):page533_i109@pure_quanta.q_res(chips)';

PART_NAME
 R535 'Q_RES_0402LF-0,5%,1/16W,CHIP,CA':;

SECTION_NUMBER 1
 '@S9S_MB_2U_LIB.S9S_MB_2U(SCH_1):PAGE533_I113@PURE_QUANTA.Q_RES(CHIPS)':
 C_PATH='@s9s_mb_2u_lib.s9s_mb_2u(sch_1):page533_i113@pure_quanta.q_res(chips)';

PART_NAME
 R534 'Q_RES_0402LF-0,5%,1/16W,CHIP,CA':;

SECTION_NUMBER 1
 '@S9S_MB_2U_LIB.S9S_MB_2U(SCH_1):PAGE533_I114@PURE_QUANTA.Q_RES(CHIPS)':
 C_PATH='@s9s_mb_2u_lib.s9s_mb_2u(sch_1):page533_i114@pure_quanta.q_res(chips)';

PART_NAME
 R533 'Q_RES_0402LF-0,5%,1/16W,CHIP,CA':;

SECTION_NUMBER 1
 '@S9S_MB_2U_LIB.S9S_MB_2U(SCH_1):PAGE533_I115@PURE_QUANTA.Q_RES(CHIPS)':
 C_PATH='@s9s_mb_2u_lib.s9s_mb_2u(sch_1):page533_i115@pure_quanta.q_res(chips)';

PART_NAME
 R532 'Q_RES_0402LF-0,5%,1/16W,CHIP,CA':;

SECTION_NUMBER 1
 '@S9S_MB_2U_LIB.S9S_MB_2U(SCH_1):PAGE533_I116@PURE_QUANTA.Q_RES(CHIPS)':
 C_PATH='@s9s_mb_2u_lib.s9s_mb_2u(sch_1):page533_i116@pure_quanta.q_res(chips)';

PART_NAME
 R531 'Q_RES_0402LF-0,5%,1/16W,CHIP,CA':;

SECTION_NUMBER 1
 '@S9S_MB_2U_LIB.S9S_MB_2U(SCH_1):PAGE533_I127@PURE_QUANTA.Q_RES(CHIPS)':
 C_PATH='@s9s_mb_2u_lib.s9s_mb_2u(sch_1):page533_i127@pure_quanta.q_res(chips)';

PART_NAME
 R530 'Q_RES_0402LF-0,5%,1/16W,CHIP,CA':;

SECTION_NUMBER 1
 '@S9S_MB_2U_LIB.S9S_MB_2U(SCH_1):PAGE533_I126@PURE_QUANTA.Q_RES(CHIPS)':
 C_PATH='@s9s_mb_2u_lib.s9s_mb_2u(sch_1):page533_i126@pure_quanta.q_res(chips)';

PART_NAME
 R529 'Q_RES_0402LF-0,5%,1/16W,CHIP,CA':;

SECTION_NUMBER 1
 '@S9S_MB_2U_LIB.S9S_MB_2U(SCH_1):PAGE533_I125@PURE_QUANTA.Q_RES(CHIPS)':
 C_PATH='@s9s_mb_2u_lib.s9s_mb_2u(sch_1):page533_i125@pure_quanta.q_res(chips)';

PART_NAME
 R528 'Q_RES_0402LF-0,5%,1/16W,CHIP,CA':;

SECTION_NUMBER 1
 '@S9S_MB_2U_LIB.S9S_MB_2U(SCH_1):PAGE533_I124@PURE_QUANTA.Q_RES(CHIPS)':
 C_PATH='@s9s_mb_2u_lib.s9s_mb_2u(sch_1):page533_i124@pure_quanta.q_res(chips)';

PART_NAME
 R1284 'Q_RES_0402LF-0,5%,1/16W,CHIP,CA':;

SECTION_NUMBER 1
 '@S9S_MB_2U_LIB.S9S_MB_2U(SCH_1):PAGE535_I193@PURE_QUANTA.Q_RES(CHIPS)':
 C_PATH='@s9s_mb_2u_lib.s9s_mb_2u(sch_1):page535_i193@pure_quanta.q_res(chips)';

PART_NAME
 R1283 'Q_RES_0402LF-0,5%,1/16W,CHIP,CA':;

SECTION_NUMBER 1
 '@S9S_MB_2U_LIB.S9S_MB_2U(SCH_1):PAGE535_I200@PURE_QUANTA.Q_RES(CHIPS)':
 C_PATH='@s9s_mb_2u_lib.s9s_mb_2u(sch_1):page535_i200@pure_quanta.q_res(chips)';

PART_NAME
 R1282 'Q_RES_0402LF-0,5%,1/16W,CHIP,CA':;

SECTION_NUMBER 1
 '@S9S_MB_2U_LIB.S9S_MB_2U(SCH_1):PAGE535_I199@PURE_QUANTA.Q_RES(CHIPS)':
 C_PATH='@s9s_mb_2u_lib.s9s_mb_2u(sch_1):page535_i199@pure_quanta.q_res(chips)';

PART_NAME
 R1281 'Q_RES_0402LF-0,5%,1/16W,CHIP,CA':;

SECTION_NUMBER 1
 '@S9S_MB_2U_LIB.S9S_MB_2U(SCH_1):PAGE535_I198@PURE_QUANTA.Q_RES(CHIPS)':
 C_PATH='@s9s_mb_2u_lib.s9s_mb_2u(sch_1):page535_i198@pure_quanta.q_res(chips)';

PART_NAME
 R1280 'Q_RES_0402LF-0,5%,1/16W,CHIP,CA':;

SECTION_NUMBER 1
 '@S9S_MB_2U_LIB.S9S_MB_2U(SCH_1):PAGE535_I187@PURE_QUANTA.Q_RES(CHIPS)':
 C_PATH='@s9s_mb_2u_lib.s9s_mb_2u(sch_1):page535_i187@pure_quanta.q_res(chips)';

PART_NAME
 R1279 'Q_RES_0402LF-0,5%,1/16W,CHIP,CA':;

SECTION_NUMBER 1
 '@S9S_MB_2U_LIB.S9S_MB_2U(SCH_1):PAGE535_I190@PURE_QUANTA.Q_RES(CHIPS)':
 C_PATH='@s9s_mb_2u_lib.s9s_mb_2u(sch_1):page535_i190@pure_quanta.q_res(chips)';

PART_NAME
 R1278 'Q_RES_0402LF-0,5%,1/16W,CHIP,CA':;

SECTION_NUMBER 1
 '@S9S_MB_2U_LIB.S9S_MB_2U(SCH_1):PAGE535_I185@PURE_QUANTA.Q_RES(CHIPS)':
 C_PATH='@s9s_mb_2u_lib.s9s_mb_2u(sch_1):page535_i185@pure_quanta.q_res(chips)';

PART_NAME
 R1277 'Q_RES_0402LF-0,5%,1/16W,CHIP,CA':;

SECTION_NUMBER 1
 '@S9S_MB_2U_LIB.S9S_MB_2U(SCH_1):PAGE535_I186@PURE_QUANTA.Q_RES(CHIPS)':
 C_PATH='@s9s_mb_2u_lib.s9s_mb_2u(sch_1):page535_i186@pure_quanta.q_res(chips)';

PART_NAME
 R1276 'Q_RES_0402LF-0,5%,1/16W,CHIP,CA':;

SECTION_NUMBER 1
 '@S9S_MB_2U_LIB.S9S_MB_2U(SCH_1):PAGE535_I163@PURE_QUANTA.Q_RES(CHIPS)':
 C_PATH='@s9s_mb_2u_lib.s9s_mb_2u(sch_1):page535_i163@pure_quanta.q_res(chips)';

PART_NAME
 R1275 'Q_RES_0402LF-0,5%,1/16W,CHIP,CA':;

SECTION_NUMBER 1
 '@S9S_MB_2U_LIB.S9S_MB_2U(SCH_1):PAGE535_I164@PURE_QUANTA.Q_RES(CHIPS)':
 C_PATH='@s9s_mb_2u_lib.s9s_mb_2u(sch_1):page535_i164@pure_quanta.q_res(chips)';

PART_NAME
 R1274 'Q_RES_0402LF-0,5%,1/16W,CHIP,CA':;

SECTION_NUMBER 1
 '@S9S_MB_2U_LIB.S9S_MB_2U(SCH_1):PAGE535_I165@PURE_QUANTA.Q_RES(CHIPS)':
 C_PATH='@s9s_mb_2u_lib.s9s_mb_2u(sch_1):page535_i165@pure_quanta.q_res(chips)';

PART_NAME
 R1273 'Q_RES_0402LF-0,5%,1/16W,CHIP,CA':;

SECTION_NUMBER 1
 '@S9S_MB_2U_LIB.S9S_MB_2U(SCH_1):PAGE535_I166@PURE_QUANTA.Q_RES(CHIPS)':
 C_PATH='@s9s_mb_2u_lib.s9s_mb_2u(sch_1):page535_i166@pure_quanta.q_res(chips)';

PART_NAME
 R566 'Q_RES_0402LF-0,5%,1/16W,CHIP,CA':;

SECTION_NUMBER 1
 '@S9S_MB_2U_LIB.S9S_MB_2U(SCH_1):PAGE535_I168@PURE_QUANTA.Q_RES(CHIPS)':
 C_PATH='@s9s_mb_2u_lib.s9s_mb_2u(sch_1):page535_i168@pure_quanta.q_res(chips)';

PART_NAME
 R565 'Q_RES_0402LF-0,5%,1/16W,CHIP,CA':;

SECTION_NUMBER 1
 '@S9S_MB_2U_LIB.S9S_MB_2U(SCH_1):PAGE535_I167@PURE_QUANTA.Q_RES(CHIPS)':
 C_PATH='@s9s_mb_2u_lib.s9s_mb_2u(sch_1):page535_i167@pure_quanta.q_res(chips)';

PART_NAME
 R564 'Q_RES_0402LF-0,5%,1/16W,CHIP,CA':;

SECTION_NUMBER 1
 '@S9S_MB_2U_LIB.S9S_MB_2U(SCH_1):PAGE535_I170@PURE_QUANTA.Q_RES(CHIPS)':
 C_PATH='@s9s_mb_2u_lib.s9s_mb_2u(sch_1):page535_i170@pure_quanta.q_res(chips)';

PART_NAME
 R563 'Q_RES_0402LF-0,5%,1/16W,CHIP,CA':;

SECTION_NUMBER 1
 '@S9S_MB_2U_LIB.S9S_MB_2U(SCH_1):PAGE535_I169@PURE_QUANTA.Q_RES(CHIPS)':
 C_PATH='@s9s_mb_2u_lib.s9s_mb_2u(sch_1):page535_i169@pure_quanta.q_res(chips)';

PART_NAME
 R552 'Q_RES_0402LF-0,5%,1/16W,CHIP,CA':;

SECTION_NUMBER 1
 '@S9S_MB_2U_LIB.S9S_MB_2U(SCH_1):PAGE535_I219@PURE_QUANTA.Q_RES(CHIPS)':
 C_PATH='@s9s_mb_2u_lib.s9s_mb_2u(sch_1):page535_i219@pure_quanta.q_res(chips)';

PART_NAME
 R551 'Q_RES_0402LF-0,5%,1/16W,CHIP,CA':;

SECTION_NUMBER 1
 '@S9S_MB_2U_LIB.S9S_MB_2U(SCH_1):PAGE535_I220@PURE_QUANTA.Q_RES(CHIPS)':
 C_PATH='@s9s_mb_2u_lib.s9s_mb_2u(sch_1):page535_i220@pure_quanta.q_res(chips)';

PART_NAME
 R550 'Q_RES_0402LF-0,5%,1/16W,CHIP,CA':;

SECTION_NUMBER 1
 '@S9S_MB_2U_LIB.S9S_MB_2U(SCH_1):PAGE535_I218@PURE_QUANTA.Q_RES(CHIPS)':
 C_PATH='@s9s_mb_2u_lib.s9s_mb_2u(sch_1):page535_i218@pure_quanta.q_res(chips)';

PART_NAME
 R549 'Q_RES_0402LF-0,5%,1/16W,CHIP,CA':;

SECTION_NUMBER 1
 '@S9S_MB_2U_LIB.S9S_MB_2U(SCH_1):PAGE535_I217@PURE_QUANTA.Q_RES(CHIPS)':
 C_PATH='@s9s_mb_2u_lib.s9s_mb_2u(sch_1):page535_i217@pure_quanta.q_res(chips)';

PART_NAME
 R527 'Q_RES_0402LF-0,5%,1/16W,CHIP,CA':;

SECTION_NUMBER 1
 '@S9S_MB_2U_LIB.S9S_MB_2U(SCH_1):PAGE535_I138@PURE_QUANTA.Q_RES(CHIPS)':
 C_PATH='@s9s_mb_2u_lib.s9s_mb_2u(sch_1):page535_i138@pure_quanta.q_res(chips)';

PART_NAME
 R526 'Q_RES_0402LF-0,5%,1/16W,CHIP,CA':;

SECTION_NUMBER 1
 '@S9S_MB_2U_LIB.S9S_MB_2U(SCH_1):PAGE535_I137@PURE_QUANTA.Q_RES(CHIPS)':
 C_PATH='@s9s_mb_2u_lib.s9s_mb_2u(sch_1):page535_i137@pure_quanta.q_res(chips)';

PART_NAME
 R525 'Q_RES_0402LF-0,5%,1/16W,CHIP,CA':;

SECTION_NUMBER 1
 '@S9S_MB_2U_LIB.S9S_MB_2U(SCH_1):PAGE535_I135@PURE_QUANTA.Q_RES(CHIPS)':
 C_PATH='@s9s_mb_2u_lib.s9s_mb_2u(sch_1):page535_i135@pure_quanta.q_res(chips)';

PART_NAME
 R524 'Q_RES_0402LF-0,5%,1/16W,CHIP,CA':;

SECTION_NUMBER 1
 '@S9S_MB_2U_LIB.S9S_MB_2U(SCH_1):PAGE535_I136@PURE_QUANTA.Q_RES(CHIPS)':
 C_PATH='@s9s_mb_2u_lib.s9s_mb_2u(sch_1):page535_i136@pure_quanta.q_res(chips)';

PART_NAME
 R523 'Q_RES_0402LF-0,5%,1/16W,CHIP,CA':;

SECTION_NUMBER 1
 '@S9S_MB_2U_LIB.S9S_MB_2U(SCH_1):PAGE535_I128@PURE_QUANTA.Q_RES(CHIPS)':
 C_PATH='@s9s_mb_2u_lib.s9s_mb_2u(sch_1):page535_i128@pure_quanta.q_res(chips)';

PART_NAME
 R522 'Q_RES_0402LF-0,5%,1/16W,CHIP,CA':;

SECTION_NUMBER 1
 '@S9S_MB_2U_LIB.S9S_MB_2U(SCH_1):PAGE535_I129@PURE_QUANTA.Q_RES(CHIPS)':
 C_PATH='@s9s_mb_2u_lib.s9s_mb_2u(sch_1):page535_i129@pure_quanta.q_res(chips)';

PART_NAME
 R521 'Q_RES_0402LF-0,5%,1/16W,CHIP,CA':;

SECTION_NUMBER 1
 '@S9S_MB_2U_LIB.S9S_MB_2U(SCH_1):PAGE535_I123@PURE_QUANTA.Q_RES(CHIPS)':
 C_PATH='@s9s_mb_2u_lib.s9s_mb_2u(sch_1):page535_i123@pure_quanta.q_res(chips)';

PART_NAME
 R520 'Q_RES_0402LF-0,5%,1/16W,CHIP,CA':;

SECTION_NUMBER 1
 '@S9S_MB_2U_LIB.S9S_MB_2U(SCH_1):PAGE535_I28@PURE_QUANTA.Q_RES(CHIPS)':
 C_PATH='@s9s_mb_2u_lib.s9s_mb_2u(sch_1):page535_i28@pure_quanta.q_res(chips)';

PART_NAME
 R1395 'Q_RES_0402LF-33.2,1%,1/16W,CHIA':;

SECTION_NUMBER 1
 '@S9S_MB_2U_LIB.S9S_MB_2U(SCH_1):PAGE472_I66@PURE_QUANTA.Q_RES(CHIPS)':
 C_PATH='@s9s_mb_2u_lib.s9s_mb_2u(sch_1):page472_i66@pure_quanta.q_res(chips)';

PART_NAME
 R918 'Q_RES_0402LF-33.2,1%,1/16W,CHIA':;

SECTION_NUMBER 1
 '@S9S_MB_2U_LIB.S9S_MB_2U(SCH_1):PAGE472_I59@PURE_QUANTA.Q_RES(CHIPS)':
 C_PATH='@s9s_mb_2u_lib.s9s_mb_2u(sch_1):page472_i59@pure_quanta.q_res(chips)';

PART_NAME
 R917 'Q_RES_0402LF-33.2,1%,1/16W,CHIA':;

SECTION_NUMBER 1
 '@S9S_MB_2U_LIB.S9S_MB_2U(SCH_1):PAGE472_I60@PURE_QUANTA.Q_RES(CHIPS)':
 C_PATH='@s9s_mb_2u_lib.s9s_mb_2u(sch_1):page472_i60@pure_quanta.q_res(chips)';

PART_NAME
 R916 'Q_RES_0402LF-33.2,1%,1/16W,CHIA':;

SECTION_NUMBER 1
 '@S9S_MB_2U_LIB.S9S_MB_2U(SCH_1):PAGE472_I61@PURE_QUANTA.Q_RES(CHIPS)':
 C_PATH='@s9s_mb_2u_lib.s9s_mb_2u(sch_1):page472_i61@pure_quanta.q_res(chips)';

PART_NAME
 R915 'Q_RES_0402LF-33.2,1%,1/16W,CHIA':;

SECTION_NUMBER 1
 '@S9S_MB_2U_LIB.S9S_MB_2U(SCH_1):PAGE472_I62@PURE_QUANTA.Q_RES(CHIPS)':
 C_PATH='@s9s_mb_2u_lib.s9s_mb_2u(sch_1):page472_i62@pure_quanta.q_res(chips)';

PART_NAME
 R501 'Q_RES_0402LF-33.2,1%,1/16W,CHIA':;

SECTION_NUMBER 1
 '@S9S_MB_2U_LIB.S9S_MB_2U(SCH_1):PAGE472_I65@PURE_QUANTA.Q_RES(CHIPS)':
 C_PATH='@s9s_mb_2u_lib.s9s_mb_2u(sch_1):page472_i65@pure_quanta.q_res(chips)';

PART_NAME
 R500 'Q_RES_0402LF-33.2,1%,1/16W,CHIA':;

SECTION_NUMBER 1
 '@S9S_MB_2U_LIB.S9S_MB_2U(SCH_1):PAGE472_I63@PURE_QUANTA.Q_RES(CHIPS)':
 C_PATH='@s9s_mb_2u_lib.s9s_mb_2u(sch_1):page472_i63@pure_quanta.q_res(chips)';

PART_NAME
 R499 'Q_RES_0402LF-33.2,1%,1/16W,CHIA':;

SECTION_NUMBER 1
 '@S9S_MB_2U_LIB.S9S_MB_2U(SCH_1):PAGE472_I64@PURE_QUANTA.Q_RES(CHIPS)':
 C_PATH='@s9s_mb_2u_lib.s9s_mb_2u(sch_1):page472_i64@pure_quanta.q_res(chips)';

PART_NAME
 R497 'Q_RES_0402LF-100,1%,1/16W,CHIPA':;

SECTION_NUMBER 1
 '@S9S_MB_2U_LIB.S9S_MB_2U(SCH_1):PAGE523_I2@PURE_QUANTA.Q_RES(CHIPS)':
 C_PATH='@s9s_mb_2u_lib.s9s_mb_2u(sch_1):page523_i2@pure_quanta.q_res(chips)';

PART_NAME
 R496 'Q_RES_0402LF-113,1%,1/16W,CHIPA':;

SECTION_NUMBER 1
 '@S9S_MB_2U_LIB.S9S_MB_2U(SCH_1):PAGE516_I10@PURE_QUANTA.Q_RES(CHIPS)':
 C_PATH='@s9s_mb_2u_lib.s9s_mb_2u(sch_1):page516_i10@pure_quanta.q_res(chips)';

PART_NAME
 R1499 'Q_RES_0402LF-1K,1%,1/16W,CHIP,A':;

SECTION_NUMBER 1
 '@S9S_MB_2U_LIB.S9S_MB_2U(SCH_1):PAGE619_I77@PURE_QUANTA.Q_RES(CHIPS)':
 C_PATH='@s9s_mb_2u_lib.s9s_mb_2u(sch_1):page619_i77@pure_quanta.q_res(chips)';

PART_NAME
 R1498 'Q_RES_0402LF-1K,1%,1/16W,EMPTYA':;

SECTION_NUMBER 1
 '@S9S_MB_2U_LIB.S9S_MB_2U(SCH_1):PAGE619_I76@PURE_QUANTA.Q_RES(CHIPS)':
 C_PATH='@s9s_mb_2u_lib.s9s_mb_2u(sch_1):page619_i76@pure_quanta.q_res(chips)';

PART_NAME
 R1497 'Q_RES_0402LF-1K,1%,1/16W,EMPTYA':;

SECTION_NUMBER 1
 '@S9S_MB_2U_LIB.S9S_MB_2U(SCH_1):PAGE619_I70@PURE_QUANTA.Q_RES(CHIPS)':
 C_PATH='@s9s_mb_2u_lib.s9s_mb_2u(sch_1):page619_i70@pure_quanta.q_res(chips)';

PART_NAME
 R1496 'Q_RES_0402LF-10K,1%,1/16W,CHIPA':;

SECTION_NUMBER 1
 '@S9S_MB_2U_LIB.S9S_MB_2U(SCH_1):PAGE619_I71@PURE_QUANTA.Q_RES(CHIPS)':
 C_PATH='@s9s_mb_2u_lib.s9s_mb_2u(sch_1):page619_i71@pure_quanta.q_res(chips)';

PART_NAME
 R1478 'Q_RES_0402LF-10K,1%,1/16W,CHIPA':;

SECTION_NUMBER 1
 '@S9S_MB_2U_LIB.S9S_MB_2U(SCH_1):PAGE619_I50@PURE_QUANTA.Q_RES(CHIPS)':
 C_PATH='@s9s_mb_2u_lib.s9s_mb_2u(sch_1):page619_i50@pure_quanta.q_res(chips)';

PART_NAME
 R1477 'Q_RES_0402LF-1K,1%,1/16W,EMPTYA':;

SECTION_NUMBER 1
 '@S9S_MB_2U_LIB.S9S_MB_2U(SCH_1):PAGE619_I47@PURE_QUANTA.Q_RES(CHIPS)':
 C_PATH='@s9s_mb_2u_lib.s9s_mb_2u(sch_1):page619_i47@pure_quanta.q_res(chips)';

PART_NAME
 R1476 'Q_RES_0402LF-1K,1%,1/16W,CHIP,A':;

SECTION_NUMBER 1
 '@S9S_MB_2U_LIB.S9S_MB_2U(SCH_1):PAGE619_I43@PURE_QUANTA.Q_RES(CHIPS)':
 C_PATH='@s9s_mb_2u_lib.s9s_mb_2u(sch_1):page619_i43@pure_quanta.q_res(chips)';

PART_NAME
 R1475 'Q_RES_0402LF-1K,1%,1/16W,EMPTYA':;

SECTION_NUMBER 1
 '@S9S_MB_2U_LIB.S9S_MB_2U(SCH_1):PAGE619_I44@PURE_QUANTA.Q_RES(CHIPS)':
 C_PATH='@s9s_mb_2u_lib.s9s_mb_2u(sch_1):page619_i44@pure_quanta.q_res(chips)';

PART_NAME
 R1457 'Q_RES_0402LF-10K,1%,1/16W,CHIPA':;

SECTION_NUMBER 1
 '@S9S_MB_2U_LIB.S9S_MB_2U(SCH_1):PAGE619_I36@PURE_QUANTA.Q_RES(CHIPS)':
 C_PATH='@s9s_mb_2u_lib.s9s_mb_2u(sch_1):page619_i36@pure_quanta.q_res(chips)';

PART_NAME
 R1315 'Q_RES_0402LF-1K,5%,1/16W,EMPTYA':;

SECTION_NUMBER 1
 '@S9S_MB_2U_LIB.S9S_MB_2U(SCH_1):PAGE619_I35@PURE_QUANTA.Q_RES(CHIPS)':
 C_PATH='@s9s_mb_2u_lib.s9s_mb_2u(sch_1):page619_i35@pure_quanta.q_res(chips)';

PART_NAME
 R1311 'Q_RES_0402LF-10K,1%,1/16W,CHIPA':;

SECTION_NUMBER 1
 '@S9S_MB_2U_LIB.S9S_MB_2U(SCH_1):PAGE619_I31@PURE_QUANTA.Q_RES(CHIPS)':
 C_PATH='@s9s_mb_2u_lib.s9s_mb_2u(sch_1):page619_i31@pure_quanta.q_res(chips)';

PART_NAME
 R1299 'Q_RES_0402LF-10K,1%,1/16W,CHIPA':;

SECTION_NUMBER 1
 '@S9S_MB_2U_LIB.S9S_MB_2U(SCH_1):PAGE619_I21@PURE_QUANTA.Q_RES(CHIPS)':
 C_PATH='@s9s_mb_2u_lib.s9s_mb_2u(sch_1):page619_i21@pure_quanta.q_res(chips)';

PART_NAME
 R1298 'Q_RES_0402LF-1K,5%,1/16W,EMPTYA':;

SECTION_NUMBER 1
 '@S9S_MB_2U_LIB.S9S_MB_2U(SCH_1):PAGE619_I22@PURE_QUANTA.Q_RES(CHIPS)':
 C_PATH='@s9s_mb_2u_lib.s9s_mb_2u(sch_1):page619_i22@pure_quanta.q_res(chips)';

PART_NAME
 R1222 'Q_RES_0402LF-5.11K,1%,1/16W,CHA':;

SECTION_NUMBER 1
 '@S9S_MB_2U_LIB.S9S_MB_2U(SCH_1):PAGE619_I57@PURE_QUANTA.Q_RES(CHIPS)':
 C_PATH='@s9s_mb_2u_lib.s9s_mb_2u(sch_1):page619_i57@pure_quanta.q_res(chips)';

PART_NAME
 R1221 'Q_RES_0402LF-1K,1%,1/16W,CHIP,A':;

SECTION_NUMBER 1
 '@S9S_MB_2U_LIB.S9S_MB_2U(SCH_1):PAGE619_I64@PURE_QUANTA.Q_RES(CHIPS)':
 C_PATH='@s9s_mb_2u_lib.s9s_mb_2u(sch_1):page619_i64@pure_quanta.q_res(chips)';

PART_NAME
 R1220 'Q_RES_0402LF-1K,1%,1/16W,EMPTYA':;

SECTION_NUMBER 1
 '@S9S_MB_2U_LIB.S9S_MB_2U(SCH_1):PAGE619_I63@PURE_QUANTA.Q_RES(CHIPS)':
 C_PATH='@s9s_mb_2u_lib.s9s_mb_2u(sch_1):page619_i63@pure_quanta.q_res(chips)';

PART_NAME
 R382 'Q_RES_0402LF-1K,5%,1/16W,EMPTYA':;

SECTION_NUMBER 1
 '@S9S_MB_2U_LIB.S9S_MB_2U(SCH_1):PAGE619_I32@PURE_QUANTA.Q_RES(CHIPS)':
 C_PATH='@s9s_mb_2u_lib.s9s_mb_2u(sch_1):page619_i32@pure_quanta.q_res(chips)';

PART_NAME
 R1810 'Q_RES_0402LF-1K,5%,1/16W,EMPTYA':;

SECTION_NUMBER 1
 '@S9S_MB_2U_LIB.S9S_MB_2U(SCH_1):PAGE529_I88@PURE_QUANTA.Q_RES(CHIPS)':
 C_PATH='@s9s_mb_2u_lib.s9s_mb_2u(sch_1):page529_i88@pure_quanta.q_res(chips)';

PART_NAME
 R1809 'Q_RES_0402LF-20K,1%,1/16W,CHIPA':;

SECTION_NUMBER 1
 '@S9S_MB_2U_LIB.S9S_MB_2U(SCH_1):PAGE529_I89@PURE_QUANTA.Q_RES(CHIPS)':
 C_PATH='@s9s_mb_2u_lib.s9s_mb_2u(sch_1):page529_i89@pure_quanta.q_res(chips)';

PART_NAME
 R502 'Q_RES_0402LF-20K,5%,1/16W,CHIPA':;

SECTION_NUMBER 1
 '@S9S_MB_2U_LIB.S9S_MB_2U(SCH_1):PAGE529_I68@PURE_QUANTA.Q_RES(CHIPS)':
 C_PATH='@s9s_mb_2u_lib.s9s_mb_2u(sch_1):page529_i68@pure_quanta.q_res(chips)';

PART_NAME
 R381 'Q_RES_0402LF-10K,1%,1/16W,CHIPA':;

SECTION_NUMBER 1
 '@S9S_MB_2U_LIB.S9S_MB_2U(SCH_1):PAGE529_I81@PURE_QUANTA.Q_RES(CHIPS)':
 C_PATH='@s9s_mb_2u_lib.s9s_mb_2u(sch_1):page529_i81@pure_quanta.q_res(chips)';

PART_NAME
 R380 'Q_RES_0402LF-1K,5%,1/16W,EMPTYA':;

SECTION_NUMBER 1
 '@S9S_MB_2U_LIB.S9S_MB_2U(SCH_1):PAGE529_I78@PURE_QUANTA.Q_RES(CHIPS)':
 C_PATH='@s9s_mb_2u_lib.s9s_mb_2u(sch_1):page529_i78@pure_quanta.q_res(chips)';

PART_NAME
 R379 'Q_RES_0402LF-1K,5%,1/16W,CHIP,A':;

SECTION_NUMBER 1
 '@S9S_MB_2U_LIB.S9S_MB_2U(SCH_1):PAGE529_I76@PURE_QUANTA.Q_RES(CHIPS)':
 C_PATH='@s9s_mb_2u_lib.s9s_mb_2u(sch_1):page529_i76@pure_quanta.q_res(chips)';

PART_NAME
 R378 'Q_RES_0402LF-1K,5%,1/16W,EMPTYA':;

SECTION_NUMBER 1
 '@S9S_MB_2U_LIB.S9S_MB_2U(SCH_1):PAGE529_I77@PURE_QUANTA.Q_RES(CHIPS)':
 C_PATH='@s9s_mb_2u_lib.s9s_mb_2u(sch_1):page529_i77@pure_quanta.q_res(chips)';

PART_NAME
 R377 'Q_RES_0402LF-10K,1%,1/16W,CHIPA':;

SECTION_NUMBER 1
 '@S9S_MB_2U_LIB.S9S_MB_2U(SCH_1):PAGE529_I50@PURE_QUANTA.Q_RES(CHIPS)':
 C_PATH='@s9s_mb_2u_lib.s9s_mb_2u(sch_1):page529_i50@pure_quanta.q_res(chips)';

PART_NAME
 R376 'Q_RES_0402LF-1K,5%,1/16W,CHIP,A':;

SECTION_NUMBER 1
 '@S9S_MB_2U_LIB.S9S_MB_2U(SCH_1):PAGE529_I57@PURE_QUANTA.Q_RES(CHIPS)':
 C_PATH='@s9s_mb_2u_lib.s9s_mb_2u(sch_1):page529_i57@pure_quanta.q_res(chips)';

PART_NAME
 R375 'Q_RES_0402LF-10K,1%,1/16W,CHIPA':;

SECTION_NUMBER 1
 '@S9S_MB_2U_LIB.S9S_MB_2U(SCH_1):PAGE529_I61@PURE_QUANTA.Q_RES(CHIPS)':
 C_PATH='@s9s_mb_2u_lib.s9s_mb_2u(sch_1):page529_i61@pure_quanta.q_res(chips)';

PART_NAME
 R374 'Q_RES_0402LF-1K,5%,1/16W,EMPTYA':;

SECTION_NUMBER 1
 '@S9S_MB_2U_LIB.S9S_MB_2U(SCH_1):PAGE529_I60@PURE_QUANTA.Q_RES(CHIPS)':
 C_PATH='@s9s_mb_2u_lib.s9s_mb_2u(sch_1):page529_i60@pure_quanta.q_res(chips)';

PART_NAME
 R373 'Q_RES_0402LF-1K,5%,1/16W,EMPTYA':;

SECTION_NUMBER 1
 '@S9S_MB_2U_LIB.S9S_MB_2U(SCH_1):PAGE529_I53@PURE_QUANTA.Q_RES(CHIPS)':
 C_PATH='@s9s_mb_2u_lib.s9s_mb_2u(sch_1):page529_i53@pure_quanta.q_res(chips)';

PART_NAME
 R372 'Q_RES_0402LF-10K,1%,1/16W,CHIPA':;

SECTION_NUMBER 1
 '@S9S_MB_2U_LIB.S9S_MB_2U(SCH_1):PAGE529_I46@PURE_QUANTA.Q_RES(CHIPS)':
 C_PATH='@s9s_mb_2u_lib.s9s_mb_2u(sch_1):page529_i46@pure_quanta.q_res(chips)';

PART_NAME
 R371 'Q_RES_0402LF-1K,5%,1/16W,EMPTYA':;

SECTION_NUMBER 1
 '@S9S_MB_2U_LIB.S9S_MB_2U(SCH_1):PAGE529_I45@PURE_QUANTA.Q_RES(CHIPS)':
 C_PATH='@s9s_mb_2u_lib.s9s_mb_2u(sch_1):page529_i45@pure_quanta.q_res(chips)';

PART_NAME
 R369 'Q_RES_0402LF-1K,5%,1/16W,CHIP,A':;

SECTION_NUMBER 1
 '@S9S_MB_2U_LIB.S9S_MB_2U(SCH_1):PAGE529_I16@PURE_QUANTA.Q_RES(CHIPS)':
 C_PATH='@s9s_mb_2u_lib.s9s_mb_2u(sch_1):page529_i16@pure_quanta.q_res(chips)';

PART_NAME
 R367 'Q_RES_0402LF-1K,5%,1/16W,CHIP,A':;

SECTION_NUMBER 1
 '@S9S_MB_2U_LIB.S9S_MB_2U(SCH_1):PAGE529_I11@PURE_QUANTA.Q_RES(CHIPS)':
 C_PATH='@s9s_mb_2u_lib.s9s_mb_2u(sch_1):page529_i11@pure_quanta.q_res(chips)';

PART_NAME
 R1239 'Q_RES_0402LF-240,1%,1/16W,EMPTA':;

SECTION_NUMBER 1
 '@S9S_MB_2U_LIB.S9S_MB_2U(SCH_1):PAGE481_I163@PURE_QUANTA.Q_RES(CHIPS)':
 C_PATH='@s9s_mb_2u_lib.s9s_mb_2u(sch_1):page481_i163@pure_quanta.q_res(chips)';

PART_NAME
 R1238 'Q_RES_0402LF-240,1%,1/16W,EMPTA':;

SECTION_NUMBER 1
 '@S9S_MB_2U_LIB.S9S_MB_2U(SCH_1):PAGE481_I161@PURE_QUANTA.Q_RES(CHIPS)':
 C_PATH='@s9s_mb_2u_lib.s9s_mb_2u(sch_1):page481_i161@pure_quanta.q_res(chips)';

PART_NAME
 R1237 'Q_RES_0402LF-240,1%,1/16W,EMPTA':;

SECTION_NUMBER 1
 '@S9S_MB_2U_LIB.S9S_MB_2U(SCH_1):PAGE481_I160@PURE_QUANTA.Q_RES(CHIPS)':
 C_PATH='@s9s_mb_2u_lib.s9s_mb_2u(sch_1):page481_i160@pure_quanta.q_res(chips)';

PART_NAME
 R1236 'Q_RES_0402LF-240,1%,1/16W,EMPTA':;

SECTION_NUMBER 1
 '@S9S_MB_2U_LIB.S9S_MB_2U(SCH_1):PAGE481_I177@PURE_QUANTA.Q_RES(CHIPS)':
 C_PATH='@s9s_mb_2u_lib.s9s_mb_2u(sch_1):page481_i177@pure_quanta.q_res(chips)';

PART_NAME
 R1235 'Q_RES_0402LF-240,1%,1/16W,EMPTA':;

SECTION_NUMBER 1
 '@S9S_MB_2U_LIB.S9S_MB_2U(SCH_1):PAGE481_I176@PURE_QUANTA.Q_RES(CHIPS)':
 C_PATH='@s9s_mb_2u_lib.s9s_mb_2u(sch_1):page481_i176@pure_quanta.q_res(chips)';

PART_NAME
 R1234 'Q_RES_0402LF-240,1%,1/16W,EMPTA':;

SECTION_NUMBER 1
 '@S9S_MB_2U_LIB.S9S_MB_2U(SCH_1):PAGE481_I172@PURE_QUANTA.Q_RES(CHIPS)':
 C_PATH='@s9s_mb_2u_lib.s9s_mb_2u(sch_1):page481_i172@pure_quanta.q_res(chips)';

PART_NAME
 R1233 'Q_RES_0402LF-240,1%,1/16W,EMPTA':;

SECTION_NUMBER 1
 '@S9S_MB_2U_LIB.S9S_MB_2U(SCH_1):PAGE481_I158@PURE_QUANTA.Q_RES(CHIPS)':
 C_PATH='@s9s_mb_2u_lib.s9s_mb_2u(sch_1):page481_i158@pure_quanta.q_res(chips)';

PART_NAME
 R1232 'Q_RES_0402LF-240,1%,1/16W,EMPTA':;

SECTION_NUMBER 1
 '@S9S_MB_2U_LIB.S9S_MB_2U(SCH_1):PAGE481_I156@PURE_QUANTA.Q_RES(CHIPS)':
 C_PATH='@s9s_mb_2u_lib.s9s_mb_2u(sch_1):page481_i156@pure_quanta.q_res(chips)';

PART_NAME
 R1231 'Q_RES_0402LF-240,1%,1/16W,CHIPA':;

SECTION_NUMBER 1
 '@S9S_MB_2U_LIB.S9S_MB_2U(SCH_1):PAGE481_I154@PURE_QUANTA.Q_RES(CHIPS)':
 C_PATH='@s9s_mb_2u_lib.s9s_mb_2u(sch_1):page481_i154@pure_quanta.q_res(chips)';

PART_NAME
 R1230 'Q_RES_0402LF-240,1%,1/16W,EMPTA':;

SECTION_NUMBER 1
 '@S9S_MB_2U_LIB.S9S_MB_2U(SCH_1):PAGE481_I170@PURE_QUANTA.Q_RES(CHIPS)':
 C_PATH='@s9s_mb_2u_lib.s9s_mb_2u(sch_1):page481_i170@pure_quanta.q_res(chips)';

PART_NAME
 R1229 'Q_RES_0402LF-240,1%,1/16W,EMPTA':;

SECTION_NUMBER 1
 '@S9S_MB_2U_LIB.S9S_MB_2U(SCH_1):PAGE481_I169@PURE_QUANTA.Q_RES(CHIPS)':
 C_PATH='@s9s_mb_2u_lib.s9s_mb_2u(sch_1):page481_i169@pure_quanta.q_res(chips)';

PART_NAME
 R1228 'Q_RES_0402LF-240,1%,1/16W,CHIPA':;

SECTION_NUMBER 1
 '@S9S_MB_2U_LIB.S9S_MB_2U(SCH_1):PAGE481_I165@PURE_QUANTA.Q_RES(CHIPS)':
 C_PATH='@s9s_mb_2u_lib.s9s_mb_2u(sch_1):page481_i165@pure_quanta.q_res(chips)';

PART_NAME
 R1009 'Q_RES_0402LF-1K,1%,1/16W,EMPTYA':;

SECTION_NUMBER 1
 '@S9S_MB_2U_LIB.S9S_MB_2U(SCH_1):PAGE481_I136@PURE_QUANTA.Q_RES(CHIPS)':
 C_PATH='@s9s_mb_2u_lib.s9s_mb_2u(sch_1):page481_i136@pure_quanta.q_res(chips)';

PART_NAME
 R1008 'Q_RES_0402LF-1K,1%,1/16W,EMPTYA':;

SECTION_NUMBER 1
 '@S9S_MB_2U_LIB.S9S_MB_2U(SCH_1):PAGE481_I139@PURE_QUANTA.Q_RES(CHIPS)':
 C_PATH='@s9s_mb_2u_lib.s9s_mb_2u(sch_1):page481_i139@pure_quanta.q_res(chips)';

PART_NAME
 R295 'Q_RES_0402LF-240,1%,1/16W,EMPTA':;

SECTION_NUMBER 1
 '@S9S_MB_2U_LIB.S9S_MB_2U(SCH_1):PAGE481_I72@PURE_QUANTA.Q_RES(CHIPS)':
 C_PATH='@s9s_mb_2u_lib.s9s_mb_2u(sch_1):page481_i72@pure_quanta.q_res(chips)';

PART_NAME
 R294 'Q_RES_0402LF-240,1%,1/16W,EMPTA':;

SECTION_NUMBER 1
 '@S9S_MB_2U_LIB.S9S_MB_2U(SCH_1):PAGE481_I71@PURE_QUANTA.Q_RES(CHIPS)':
 C_PATH='@s9s_mb_2u_lib.s9s_mb_2u(sch_1):page481_i71@pure_quanta.q_res(chips)';

PART_NAME
 R293 'Q_RES_0402LF-240,1%,1/16W,EMPTA':;

SECTION_NUMBER 1
 '@S9S_MB_2U_LIB.S9S_MB_2U(SCH_1):PAGE481_I70@PURE_QUANTA.Q_RES(CHIPS)':
 C_PATH='@s9s_mb_2u_lib.s9s_mb_2u(sch_1):page481_i70@pure_quanta.q_res(chips)';

PART_NAME
 R292 'Q_RES_0402LF-240,1%,1/16W,EMPTA':;

SECTION_NUMBER 1
 '@S9S_MB_2U_LIB.S9S_MB_2U(SCH_1):PAGE481_I69@PURE_QUANTA.Q_RES(CHIPS)':
 C_PATH='@s9s_mb_2u_lib.s9s_mb_2u(sch_1):page481_i69@pure_quanta.q_res(chips)';

PART_NAME
 R291 'Q_RES_0402LF-240,1%,1/16W,EMPTA':;

SECTION_NUMBER 1
 '@S9S_MB_2U_LIB.S9S_MB_2U(SCH_1):PAGE481_I116@PURE_QUANTA.Q_RES(CHIPS)':
 C_PATH='@s9s_mb_2u_lib.s9s_mb_2u(sch_1):page481_i116@pure_quanta.q_res(chips)';

PART_NAME
 R290 'Q_RES_0402LF-240,1%,1/16W,CHIPA':;

SECTION_NUMBER 1
 '@S9S_MB_2U_LIB.S9S_MB_2U(SCH_1):PAGE481_I135@PURE_QUANTA.Q_RES(CHIPS)':
 C_PATH='@s9s_mb_2u_lib.s9s_mb_2u(sch_1):page481_i135@pure_quanta.q_res(chips)';

PART_NAME
 R289 'Q_RES_0402LF-240,1%,1/16W,EMPTA':;

SECTION_NUMBER 1
 '@S9S_MB_2U_LIB.S9S_MB_2U(SCH_1):PAGE481_I118@PURE_QUANTA.Q_RES(CHIPS)':
 C_PATH='@s9s_mb_2u_lib.s9s_mb_2u(sch_1):page481_i118@pure_quanta.q_res(chips)';

PART_NAME
 R288 'Q_RES_0402LF-240,1%,1/16W,EMPTA':;

SECTION_NUMBER 1
 '@S9S_MB_2U_LIB.S9S_MB_2U(SCH_1):PAGE481_I119@PURE_QUANTA.Q_RES(CHIPS)':
 C_PATH='@s9s_mb_2u_lib.s9s_mb_2u(sch_1):page481_i119@pure_quanta.q_res(chips)';

PART_NAME
 R287 'Q_RES_0402LF-10K,1%,1/16W,CHIPA':;

SECTION_NUMBER 1
 '@S9S_MB_2U_LIB.S9S_MB_2U(SCH_1):PAGE481_I152@PURE_QUANTA.Q_RES(CHIPS)':
 C_PATH='@s9s_mb_2u_lib.s9s_mb_2u(sch_1):page481_i152@pure_quanta.q_res(chips)';

PART_NAME
 R286 'Q_RES_0402LF-10K,1%,1/16W,CHIPA':;

SECTION_NUMBER 1
 '@S9S_MB_2U_LIB.S9S_MB_2U(SCH_1):PAGE481_I151@PURE_QUANTA.Q_RES(CHIPS)':
 C_PATH='@s9s_mb_2u_lib.s9s_mb_2u(sch_1):page481_i151@pure_quanta.q_res(chips)';

PART_NAME
 R285 'Q_RES_0402LF-10K,1%,1/16W,CHIPA':;

SECTION_NUMBER 1
 '@S9S_MB_2U_LIB.S9S_MB_2U(SCH_1):PAGE481_I150@PURE_QUANTA.Q_RES(CHIPS)':
 C_PATH='@s9s_mb_2u_lib.s9s_mb_2u(sch_1):page481_i150@pure_quanta.q_res(chips)';

PART_NAME
 R284 'Q_RES_0402LF-10K,1%,1/16W,CHIPA':;

SECTION_NUMBER 1
 '@S9S_MB_2U_LIB.S9S_MB_2U(SCH_1):PAGE481_I148@PURE_QUANTA.Q_RES(CHIPS)':
 C_PATH='@s9s_mb_2u_lib.s9s_mb_2u(sch_1):page481_i148@pure_quanta.q_res(chips)';

PART_NAME
 R283 'Q_RES_0402LF-10K,1%,1/16W,CHIPA':;

SECTION_NUMBER 1
 '@S9S_MB_2U_LIB.S9S_MB_2U(SCH_1):PAGE481_I147@PURE_QUANTA.Q_RES(CHIPS)':
 C_PATH='@s9s_mb_2u_lib.s9s_mb_2u(sch_1):page481_i147@pure_quanta.q_res(chips)';

PART_NAME
 R282 'Q_RES_0402LF-240,1%,1/16W,CHIPA':;

SECTION_NUMBER 1
 '@S9S_MB_2U_LIB.S9S_MB_2U(SCH_1):PAGE481_I53@PURE_QUANTA.Q_RES(CHIPS)':
 C_PATH='@s9s_mb_2u_lib.s9s_mb_2u(sch_1):page481_i53@pure_quanta.q_res(chips)';

PART_NAME
 R281 'Q_RES_0402LF-240,1%,1/16W,EMPTA':;

SECTION_NUMBER 1
 '@S9S_MB_2U_LIB.S9S_MB_2U(SCH_1):PAGE481_I58@PURE_QUANTA.Q_RES(CHIPS)':
 C_PATH='@s9s_mb_2u_lib.s9s_mb_2u(sch_1):page481_i58@pure_quanta.q_res(chips)';

PART_NAME
 R280 'Q_RES_0402LF-240,1%,1/16W,EMPTA':;

SECTION_NUMBER 1
 '@S9S_MB_2U_LIB.S9S_MB_2U(SCH_1):PAGE481_I57@PURE_QUANTA.Q_RES(CHIPS)':
 C_PATH='@s9s_mb_2u_lib.s9s_mb_2u(sch_1):page481_i57@pure_quanta.q_res(chips)';

PART_NAME
 R279 'Q_RES_0402LF-240,1%,1/16W,EMPTA':;

SECTION_NUMBER 1
 '@S9S_MB_2U_LIB.S9S_MB_2U(SCH_1):PAGE481_I54@PURE_QUANTA.Q_RES(CHIPS)':
 C_PATH='@s9s_mb_2u_lib.s9s_mb_2u(sch_1):page481_i54@pure_quanta.q_res(chips)';

PART_NAME
 R278 'Q_RES_0402LF-240,1%,1/16W,CHIPA':;

SECTION_NUMBER 1
 '@S9S_MB_2U_LIB.S9S_MB_2U(SCH_1):PAGE481_I61@PURE_QUANTA.Q_RES(CHIPS)':
 C_PATH='@s9s_mb_2u_lib.s9s_mb_2u(sch_1):page481_i61@pure_quanta.q_res(chips)';

PART_NAME
 R277 'Q_RES_0402LF-240,1%,1/16W,CHIPA':;

SECTION_NUMBER 1
 '@S9S_MB_2U_LIB.S9S_MB_2U(SCH_1):PAGE481_I62@PURE_QUANTA.Q_RES(CHIPS)':
 C_PATH='@s9s_mb_2u_lib.s9s_mb_2u(sch_1):page481_i62@pure_quanta.q_res(chips)';

PART_NAME
 R276 'Q_RES_0402LF-240,1%,1/16W,EMPTA':;

SECTION_NUMBER 1
 '@S9S_MB_2U_LIB.S9S_MB_2U(SCH_1):PAGE481_I66@PURE_QUANTA.Q_RES(CHIPS)':
 C_PATH='@s9s_mb_2u_lib.s9s_mb_2u(sch_1):page481_i66@pure_quanta.q_res(chips)';

PART_NAME
 R275 'Q_RES_0402LF-240,1%,1/16W,EMPTA':;

SECTION_NUMBER 1
 '@S9S_MB_2U_LIB.S9S_MB_2U(SCH_1):PAGE481_I68@PURE_QUANTA.Q_RES(CHIPS)':
 C_PATH='@s9s_mb_2u_lib.s9s_mb_2u(sch_1):page481_i68@pure_quanta.q_res(chips)';

PART_NAME
 R274 'Q_RES_0402LF-10K,1%,1/16W,CHIPA':;

SECTION_NUMBER 1
 '@S9S_MB_2U_LIB.S9S_MB_2U(SCH_1):PAGE481_I88@PURE_QUANTA.Q_RES(CHIPS)':
 C_PATH='@s9s_mb_2u_lib.s9s_mb_2u(sch_1):page481_i88@pure_quanta.q_res(chips)';

PART_NAME
 R273 'Q_RES_0402LF-10K,1%,1/16W,CHIPA':;

SECTION_NUMBER 1
 '@S9S_MB_2U_LIB.S9S_MB_2U(SCH_1):PAGE481_I89@PURE_QUANTA.Q_RES(CHIPS)':
 C_PATH='@s9s_mb_2u_lib.s9s_mb_2u(sch_1):page481_i89@pure_quanta.q_res(chips)';

PART_NAME
 R272 'Q_RES_0402LF-10K,1%,1/16W,CHIPA':;

SECTION_NUMBER 1
 '@S9S_MB_2U_LIB.S9S_MB_2U(SCH_1):PAGE481_I90@PURE_QUANTA.Q_RES(CHIPS)':
 C_PATH='@s9s_mb_2u_lib.s9s_mb_2u(sch_1):page481_i90@pure_quanta.q_res(chips)';

PART_NAME
 R271 'Q_RES_0402LF-10K,1%,1/16W,CHIPA':;

SECTION_NUMBER 1
 '@S9S_MB_2U_LIB.S9S_MB_2U(SCH_1):PAGE481_I92@PURE_QUANTA.Q_RES(CHIPS)':
 C_PATH='@s9s_mb_2u_lib.s9s_mb_2u(sch_1):page481_i92@pure_quanta.q_res(chips)';

PART_NAME
 R270 'Q_RES_0402LF-10K,1%,1/16W,CHIPA':;

SECTION_NUMBER 1
 '@S9S_MB_2U_LIB.S9S_MB_2U(SCH_1):PAGE481_I93@PURE_QUANTA.Q_RES(CHIPS)':
 C_PATH='@s9s_mb_2u_lib.s9s_mb_2u(sch_1):page481_i93@pure_quanta.q_res(chips)';

PART_NAME
 R268 'Q_RES_0402LF-240,1%,1/16W,CHIPA':;

SECTION_NUMBER 1
 '@S9S_MB_2U_LIB.S9S_MB_2U(SCH_1):PAGE481_I94@PURE_QUANTA.Q_RES(CHIPS)':
 C_PATH='@s9s_mb_2u_lib.s9s_mb_2u(sch_1):page481_i94@pure_quanta.q_res(chips)';

PART_NAME
 R267 'Q_RES_0402LF-240,1%,1/16W,EMPTA':;

SECTION_NUMBER 1
 '@S9S_MB_2U_LIB.S9S_MB_2U(SCH_1):PAGE481_I95@PURE_QUANTA.Q_RES(CHIPS)':
 C_PATH='@s9s_mb_2u_lib.s9s_mb_2u(sch_1):page481_i95@pure_quanta.q_res(chips)';

PART_NAME
 R266 'Q_RES_0402LF-240,1%,1/16W,EMPTA':;

SECTION_NUMBER 1
 '@S9S_MB_2U_LIB.S9S_MB_2U(SCH_1):PAGE481_I96@PURE_QUANTA.Q_RES(CHIPS)':
 C_PATH='@s9s_mb_2u_lib.s9s_mb_2u(sch_1):page481_i96@pure_quanta.q_res(chips)';

PART_NAME
 R265 'Q_RES_0402LF-240,1%,1/16W,CHIPA':;

SECTION_NUMBER 1
 '@S9S_MB_2U_LIB.S9S_MB_2U(SCH_1):PAGE481_I97@PURE_QUANTA.Q_RES(CHIPS)':
 C_PATH='@s9s_mb_2u_lib.s9s_mb_2u(sch_1):page481_i97@pure_quanta.q_res(chips)';

PART_NAME
 R264 'Q_RES_0402LF-240,1%,1/16W,CHIPA':;

SECTION_NUMBER 1
 '@S9S_MB_2U_LIB.S9S_MB_2U(SCH_1):PAGE481_I98@PURE_QUANTA.Q_RES(CHIPS)':
 C_PATH='@s9s_mb_2u_lib.s9s_mb_2u(sch_1):page481_i98@pure_quanta.q_res(chips)';

PART_NAME
 R263 'Q_RES_0402LF-240,1%,1/16W,EMPTA':;

SECTION_NUMBER 1
 '@S9S_MB_2U_LIB.S9S_MB_2U(SCH_1):PAGE481_I125@PURE_QUANTA.Q_RES(CHIPS)':
 C_PATH='@s9s_mb_2u_lib.s9s_mb_2u(sch_1):page481_i125@pure_quanta.q_res(chips)';

PART_NAME
 R262 'Q_RES_0402LF-240,1%,1/16W,EMPTA':;

SECTION_NUMBER 1
 '@S9S_MB_2U_LIB.S9S_MB_2U(SCH_1):PAGE481_I100@PURE_QUANTA.Q_RES(CHIPS)':
 C_PATH='@s9s_mb_2u_lib.s9s_mb_2u(sch_1):page481_i100@pure_quanta.q_res(chips)';

PART_NAME
 R261 'Q_RES_0402LF-240,1%,1/16W,EMPTA':;

SECTION_NUMBER 1
 '@S9S_MB_2U_LIB.S9S_MB_2U(SCH_1):PAGE481_I101@PURE_QUANTA.Q_RES(CHIPS)':
 C_PATH='@s9s_mb_2u_lib.s9s_mb_2u(sch_1):page481_i101@pure_quanta.q_res(chips)';

PART_NAME
 R1394 'Q_RES_0402LF-240,1%,1/16W,EMPTA':;

SECTION_NUMBER 1
 '@S9S_MB_2U_LIB.S9S_MB_2U(SCH_1):PAGE482_I67@PURE_QUANTA.Q_RES(CHIPS)':
 C_PATH='@s9s_mb_2u_lib.s9s_mb_2u(sch_1):page482_i67@pure_quanta.q_res(chips)';

PART_NAME
 R1393 'Q_RES_0402LF-240,1%,1/16W,EMPTA':;

SECTION_NUMBER 1
 '@S9S_MB_2U_LIB.S9S_MB_2U(SCH_1):PAGE482_I66@PURE_QUANTA.Q_RES(CHIPS)':
 C_PATH='@s9s_mb_2u_lib.s9s_mb_2u(sch_1):page482_i66@pure_quanta.q_res(chips)';

PART_NAME
 R1392 'Q_RES_0402LF-240,1%,1/16W,EMPTA':;

SECTION_NUMBER 1
 '@S9S_MB_2U_LIB.S9S_MB_2U(SCH_1):PAGE482_I62@PURE_QUANTA.Q_RES(CHIPS)':
 C_PATH='@s9s_mb_2u_lib.s9s_mb_2u(sch_1):page482_i62@pure_quanta.q_res(chips)';

PART_NAME
 R1391 'Q_RES_0402LF-240,1%,1/16W,EMPTA':;

SECTION_NUMBER 1
 '@S9S_MB_2U_LIB.S9S_MB_2U(SCH_1):PAGE482_I61@PURE_QUANTA.Q_RES(CHIPS)':
 C_PATH='@s9s_mb_2u_lib.s9s_mb_2u(sch_1):page482_i61@pure_quanta.q_res(chips)';

PART_NAME
 R695 'Q_RES_0402LF-240,1%,1/16W,EMPTA':;

SECTION_NUMBER 1
 '@S9S_MB_2U_LIB.S9S_MB_2U(SCH_1):PAGE482_I54@PURE_QUANTA.Q_RES(CHIPS)':
 C_PATH='@s9s_mb_2u_lib.s9s_mb_2u(sch_1):page482_i54@pure_quanta.q_res(chips)';

PART_NAME
 R517 'Q_RES_0402LF-240,1%,1/16W,EMPTA':;

SECTION_NUMBER 1
 '@S9S_MB_2U_LIB.S9S_MB_2U(SCH_1):PAGE482_I51@PURE_QUANTA.Q_RES(CHIPS)':
 C_PATH='@s9s_mb_2u_lib.s9s_mb_2u(sch_1):page482_i51@pure_quanta.q_res(chips)';

PART_NAME
 R260 'Q_RES_0402LF-240,1%,1/16W,CHIPA':;

SECTION_NUMBER 1
 '@S9S_MB_2U_LIB.S9S_MB_2U(SCH_1):PAGE482_I46@PURE_QUANTA.Q_RES(CHIPS)':
 C_PATH='@s9s_mb_2u_lib.s9s_mb_2u(sch_1):page482_i46@pure_quanta.q_res(chips)';

PART_NAME
 R259 'Q_RES_0402LF-240,1%,1/16W,CHIPA':;

SECTION_NUMBER 1
 '@S9S_MB_2U_LIB.S9S_MB_2U(SCH_1):PAGE482_I45@PURE_QUANTA.Q_RES(CHIPS)':
 C_PATH='@s9s_mb_2u_lib.s9s_mb_2u(sch_1):page482_i45@pure_quanta.q_res(chips)';

PART_NAME
 R258 'Q_RES_0402LF-240,1%,1/16W,CHIPA':;

SECTION_NUMBER 1
 '@S9S_MB_2U_LIB.S9S_MB_2U(SCH_1):PAGE482_I44@PURE_QUANTA.Q_RES(CHIPS)':
 C_PATH='@s9s_mb_2u_lib.s9s_mb_2u(sch_1):page482_i44@pure_quanta.q_res(chips)';

PART_NAME
 R257 'Q_RES_0402LF-240,1%,1/16W,EMPTA':;

SECTION_NUMBER 1
 '@S9S_MB_2U_LIB.S9S_MB_2U(SCH_1):PAGE482_I43@PURE_QUANTA.Q_RES(CHIPS)':
 C_PATH='@s9s_mb_2u_lib.s9s_mb_2u(sch_1):page482_i43@pure_quanta.q_res(chips)';

PART_NAME
 R256 'Q_RES_0402LF-240,1%,1/16W,EMPTA':;

SECTION_NUMBER 1
 '@S9S_MB_2U_LIB.S9S_MB_2U(SCH_1):PAGE482_I48@PURE_QUANTA.Q_RES(CHIPS)':
 C_PATH='@s9s_mb_2u_lib.s9s_mb_2u(sch_1):page482_i48@pure_quanta.q_res(chips)';

PART_NAME
 R255 'Q_RES_0402LF-240,1%,1/16W,EMPTA':;

SECTION_NUMBER 1
 '@S9S_MB_2U_LIB.S9S_MB_2U(SCH_1):PAGE482_I42@PURE_QUANTA.Q_RES(CHIPS)':
 C_PATH='@s9s_mb_2u_lib.s9s_mb_2u(sch_1):page482_i42@pure_quanta.q_res(chips)';

PART_NAME
 R254 'Q_RES_0402LF-240,1%,1/16W,CHIPA':;

SECTION_NUMBER 1
 '@S9S_MB_2U_LIB.S9S_MB_2U(SCH_1):PAGE482_I32@PURE_QUANTA.Q_RES(CHIPS)':
 C_PATH='@s9s_mb_2u_lib.s9s_mb_2u(sch_1):page482_i32@pure_quanta.q_res(chips)';

PART_NAME
 R253 'Q_RES_0402LF-240,1%,1/16W,CHIPA':;

SECTION_NUMBER 1
 '@S9S_MB_2U_LIB.S9S_MB_2U(SCH_1):PAGE482_I31@PURE_QUANTA.Q_RES(CHIPS)':
 C_PATH='@s9s_mb_2u_lib.s9s_mb_2u(sch_1):page482_i31@pure_quanta.q_res(chips)';

PART_NAME
 R252 'Q_RES_0402LF-240,1%,1/16W,CHIPA':;

SECTION_NUMBER 1
 '@S9S_MB_2U_LIB.S9S_MB_2U(SCH_1):PAGE482_I30@PURE_QUANTA.Q_RES(CHIPS)':
 C_PATH='@s9s_mb_2u_lib.s9s_mb_2u(sch_1):page482_i30@pure_quanta.q_res(chips)';

PART_NAME
 R251 'Q_RES_0402LF-240,1%,1/16W,EMPTA':;

SECTION_NUMBER 1
 '@S9S_MB_2U_LIB.S9S_MB_2U(SCH_1):PAGE482_I28@PURE_QUANTA.Q_RES(CHIPS)':
 C_PATH='@s9s_mb_2u_lib.s9s_mb_2u(sch_1):page482_i28@pure_quanta.q_res(chips)';

PART_NAME
 R250 'Q_RES_0402LF-240,1%,1/16W,EMPTA':;

SECTION_NUMBER 1
 '@S9S_MB_2U_LIB.S9S_MB_2U(SCH_1):PAGE482_I29@PURE_QUANTA.Q_RES(CHIPS)':
 C_PATH='@s9s_mb_2u_lib.s9s_mb_2u(sch_1):page482_i29@pure_quanta.q_res(chips)';

PART_NAME
 R249 'Q_RES_0402LF-240,1%,1/16W,EMPTA':;

SECTION_NUMBER 1
 '@S9S_MB_2U_LIB.S9S_MB_2U(SCH_1):PAGE482_I27@PURE_QUANTA.Q_RES(CHIPS)':
 C_PATH='@s9s_mb_2u_lib.s9s_mb_2u(sch_1):page482_i27@pure_quanta.q_res(chips)';

PART_NAME
 R1297 'Q_RES_0402LF-0,5%,1/16W,CHIP,CA':;

SECTION_NUMBER 1
 '@S9S_MB_2U_LIB.S9S_MB_2U(SCH_1):PAGE528_I15@PURE_QUANTA.Q_RES(CHIPS)':
 C_PATH='@s9s_mb_2u_lib.s9s_mb_2u(sch_1):page528_i15@pure_quanta.q_res(chips)';

PART_NAME
 R149 'Q_RES_0402LF-0,5%,1/16W,EMPTY,A':;

SECTION_NUMBER 1
 '@S9S_MB_2U_LIB.S9S_MB_2U(SCH_1):PAGE528_I9@PURE_QUANTA.Q_RES(CHIPS)':
 C_PATH='@s9s_mb_2u_lib.s9s_mb_2u(sch_1):page528_i9@pure_quanta.q_res(chips)';

PART_NAME
 R148 'Q_RES_0402LF-10K,1%,1/16W,CHIPA':;

SECTION_NUMBER 1
 '@S9S_MB_2U_LIB.S9S_MB_2U(SCH_1):PAGE528_I4@PURE_QUANTA.Q_RES(CHIPS)':
 C_PATH='@s9s_mb_2u_lib.s9s_mb_2u(sch_1):page528_i4@pure_quanta.q_res(chips)';

PART_NAME
 R147 'Q_RES_0402LF-348,1%,1/16W,CHIPA':;

SECTION_NUMBER 1
 '@S9S_MB_2U_LIB.S9S_MB_2U(SCH_1):PAGE528_I18@PURE_QUANTA.Q_RES(CHIPS)':
 C_PATH='@s9s_mb_2u_lib.s9s_mb_2u(sch_1):page528_i18@pure_quanta.q_res(chips)';

PART_NAME
 R146 'Q_RES_0402LF-4.75K,1%,1/16W,EMA':;

SECTION_NUMBER 1
 '@S9S_MB_2U_LIB.S9S_MB_2U(SCH_1):PAGE528_I6@PURE_QUANTA.Q_RES(CHIPS)':
 C_PATH='@s9s_mb_2u_lib.s9s_mb_2u(sch_1):page528_i6@pure_quanta.q_res(chips)';

PART_NAME
 R145 'Q_RES_0402LF-4.75K,1%,1/16W,EMA':;

SECTION_NUMBER 1
 '@S9S_MB_2U_LIB.S9S_MB_2U(SCH_1):PAGE528_I11@PURE_QUANTA.Q_RES(CHIPS)':
 C_PATH='@s9s_mb_2u_lib.s9s_mb_2u(sch_1):page528_i11@pure_quanta.q_res(chips)';

PART_NAME
 R144 'Q_RES_0402LF-10,1%,1/16W,CHIP,A':;

SECTION_NUMBER 1
 '@S9S_MB_2U_LIB.S9S_MB_2U(SCH_1):PAGE528_I2@PURE_QUANTA.Q_RES(CHIPS)':
 C_PATH='@s9s_mb_2u_lib.s9s_mb_2u(sch_1):page528_i2@pure_quanta.q_res(chips)';

PART_NAME
 R143 'Q_RES_0402LF-0,5%,1/16W,CHIP,CA':;

SECTION_NUMBER 1
 '@S9S_MB_2U_LIB.S9S_MB_2U(SCH_1):PAGE528_I16@PURE_QUANTA.Q_RES(CHIPS)':
 C_PATH='@s9s_mb_2u_lib.s9s_mb_2u(sch_1):page528_i16@pure_quanta.q_res(chips)';

PART_NAME
 U70 'MOSFET_N_SMLF-BSS138K,BSS138K,A':;

SECTION_NUMBER 1
 '@S9S_MB_2U_LIB.S9S_MB_2U(SCH_1):PAGE550_I19@PURE_QUANTA.MOSFET_N(CHIPS)':
 C_PATH='@s9s_mb_2u_lib.s9s_mb_2u(sch_1):page550_i19@pure_quanta.mosfet_n(chips)';

PART_NAME
 R1996 'Q_RES_0402LF-33,5%,1/16W,CHIP,A':;

SECTION_NUMBER 1
 '@S9S_MB_2U_LIB.S9S_MB_2U(SCH_1):PAGE550_I87@PURE_QUANTA.Q_RES(CHIPS)':
 C_PATH='@s9s_mb_2u_lib.s9s_mb_2u(sch_1):page550_i87@pure_quanta.q_res(chips)';

PART_NAME
 R1995 'Q_RES_0402LF-33,5%,1/16W,CHIP,A':;

SECTION_NUMBER 1
 '@S9S_MB_2U_LIB.S9S_MB_2U(SCH_1):PAGE550_I86@PURE_QUANTA.Q_RES(CHIPS)':
 C_PATH='@s9s_mb_2u_lib.s9s_mb_2u(sch_1):page550_i86@pure_quanta.q_res(chips)';

PART_NAME
 R1744 'Q_RES_0402LF-0,5%,1/16W,CHIP,CA':;

SECTION_NUMBER 1
 '@S9S_MB_2U_LIB.S9S_MB_2U(SCH_1):PAGE550_I94@PURE_QUANTA.Q_RES(CHIPS)':
 C_PATH='@s9s_mb_2u_lib.s9s_mb_2u(sch_1):page550_i94@pure_quanta.q_res(chips)';

PART_NAME
 R1541 'Q_RES_0402LF-100K,1%,1/16W,CHIA':;

SECTION_NUMBER 1
 '@S9S_MB_2U_LIB.S9S_MB_2U(SCH_1):PAGE550_I92@PURE_QUANTA.Q_RES(CHIPS)':
 C_PATH='@s9s_mb_2u_lib.s9s_mb_2u(sch_1):page550_i92@pure_quanta.q_res(chips)';

PART_NAME
 R1521 'Q_RES_0402LF-33.2,1%,1/16W,CHIA':;

SECTION_NUMBER 1
 '@S9S_MB_2U_LIB.S9S_MB_2U(SCH_1):PAGE550_I78@PURE_QUANTA.Q_RES(CHIPS)':
 C_PATH='@s9s_mb_2u_lib.s9s_mb_2u(sch_1):page550_i78@pure_quanta.q_res(chips)';

PART_NAME
 R1520 'Q_RES_0402LF-33.2,1%,1/16W,CHIA':;

SECTION_NUMBER 1
 '@S9S_MB_2U_LIB.S9S_MB_2U(SCH_1):PAGE550_I81@PURE_QUANTA.Q_RES(CHIPS)':
 C_PATH='@s9s_mb_2u_lib.s9s_mb_2u(sch_1):page550_i81@pure_quanta.q_res(chips)';

PART_NAME
 R1519 'Q_RES_0402LF-33.2,1%,1/16W,CHIA':;

SECTION_NUMBER 1
 '@S9S_MB_2U_LIB.S9S_MB_2U(SCH_1):PAGE550_I71@PURE_QUANTA.Q_RES(CHIPS)':
 C_PATH='@s9s_mb_2u_lib.s9s_mb_2u(sch_1):page550_i71@pure_quanta.q_res(chips)';

PART_NAME
 R1518 'Q_RES_0402LF-33.2,1%,1/16W,CHIA':;

SECTION_NUMBER 1
 '@S9S_MB_2U_LIB.S9S_MB_2U(SCH_1):PAGE550_I70@PURE_QUANTA.Q_RES(CHIPS)':
 C_PATH='@s9s_mb_2u_lib.s9s_mb_2u(sch_1):page550_i70@pure_quanta.q_res(chips)';

PART_NAME
 R1516 'Q_RES_0402LF-33.2,1%,1/16W,CHIA':;

SECTION_NUMBER 1
 '@S9S_MB_2U_LIB.S9S_MB_2U(SCH_1):PAGE550_I76@PURE_QUANTA.Q_RES(CHIPS)':
 C_PATH='@s9s_mb_2u_lib.s9s_mb_2u(sch_1):page550_i76@pure_quanta.q_res(chips)';

PART_NAME
 R1515 'Q_RES_0402LF-33.2,1%,1/16W,CHIA':;

SECTION_NUMBER 1
 '@S9S_MB_2U_LIB.S9S_MB_2U(SCH_1):PAGE550_I74@PURE_QUANTA.Q_RES(CHIPS)':
 C_PATH='@s9s_mb_2u_lib.s9s_mb_2u(sch_1):page550_i74@pure_quanta.q_res(chips)';

PART_NAME
 R1514 'Q_RES_0402LF-33.2,1%,1/16W,CHIA':;

SECTION_NUMBER 1
 '@S9S_MB_2U_LIB.S9S_MB_2U(SCH_1):PAGE550_I65@PURE_QUANTA.Q_RES(CHIPS)':
 C_PATH='@s9s_mb_2u_lib.s9s_mb_2u(sch_1):page550_i65@pure_quanta.q_res(chips)';

PART_NAME
 R1513 'Q_RES_0402LF-33.2,1%,1/16W,CHIA':;

SECTION_NUMBER 1
 '@S9S_MB_2U_LIB.S9S_MB_2U(SCH_1):PAGE550_I64@PURE_QUANTA.Q_RES(CHIPS)':
 C_PATH='@s9s_mb_2u_lib.s9s_mb_2u(sch_1):page550_i64@pure_quanta.q_res(chips)';

PART_NAME
 R1512 'Q_RES_0402LF-33.2,1%,1/16W,CHIA':;

SECTION_NUMBER 1
 '@S9S_MB_2U_LIB.S9S_MB_2U(SCH_1):PAGE550_I63@PURE_QUANTA.Q_RES(CHIPS)':
 C_PATH='@s9s_mb_2u_lib.s9s_mb_2u(sch_1):page550_i63@pure_quanta.q_res(chips)';

PART_NAME
 R1470 'Q_RES_0402LF-33.2,1%,1/16W,CHIA':;

SECTION_NUMBER 1
 '@S9S_MB_2U_LIB.S9S_MB_2U(SCH_1):PAGE550_I56@PURE_QUANTA.Q_RES(CHIPS)':
 C_PATH='@s9s_mb_2u_lib.s9s_mb_2u(sch_1):page550_i56@pure_quanta.q_res(chips)';

PART_NAME
 R1469 'Q_RES_0402LF-33.2,1%,1/16W,CHIA':;

SECTION_NUMBER 1
 '@S9S_MB_2U_LIB.S9S_MB_2U(SCH_1):PAGE550_I55@PURE_QUANTA.Q_RES(CHIPS)':
 C_PATH='@s9s_mb_2u_lib.s9s_mb_2u(sch_1):page550_i55@pure_quanta.q_res(chips)';

PART_NAME
 R1468 'Q_RES_0402LF-33.2,1%,1/16W,EMPA':;

SECTION_NUMBER 1
 '@S9S_MB_2U_LIB.S9S_MB_2U(SCH_1):PAGE550_I51@PURE_QUANTA.Q_RES(CHIPS)':
 C_PATH='@s9s_mb_2u_lib.s9s_mb_2u(sch_1):page550_i51@pure_quanta.q_res(chips)';

PART_NAME
 R1318 'Q_RES_0402LF-33.2,1%,1/16W,CHIA':;

SECTION_NUMBER 1
 '@S9S_MB_2U_LIB.S9S_MB_2U(SCH_1):PAGE550_I47@PURE_QUANTA.Q_RES(CHIPS)':
 C_PATH='@s9s_mb_2u_lib.s9s_mb_2u(sch_1):page550_i47@pure_quanta.q_res(chips)';

PART_NAME
 R1207 'Q_RES_0402LF-33,5%,1/16W,CHIP,A':;

SECTION_NUMBER 1
 '@S9S_MB_2U_LIB.S9S_MB_2U(SCH_1):PAGE550_I15@PURE_QUANTA.Q_RES(CHIPS)':
 C_PATH='@s9s_mb_2u_lib.s9s_mb_2u(sch_1):page550_i15@pure_quanta.q_res(chips)';

PART_NAME
 R1206 'Q_RES_0402LF-33,5%,1/16W,CHIP,A':;

SECTION_NUMBER 1
 '@S9S_MB_2U_LIB.S9S_MB_2U(SCH_1):PAGE550_I10@PURE_QUANTA.Q_RES(CHIPS)':
 C_PATH='@s9s_mb_2u_lib.s9s_mb_2u(sch_1):page550_i10@pure_quanta.q_res(chips)';

PART_NAME
 R1205 'Q_RES_0402LF-33,5%,1/16W,CHIP,A':;

SECTION_NUMBER 1
 '@S9S_MB_2U_LIB.S9S_MB_2U(SCH_1):PAGE550_I7@PURE_QUANTA.Q_RES(CHIPS)':
 C_PATH='@s9s_mb_2u_lib.s9s_mb_2u(sch_1):page550_i7@pure_quanta.q_res(chips)';

PART_NAME
 R269 'Q_RES_0402LF-33.2,1%,1/16W,CHIA':;

SECTION_NUMBER 1
 '@S9S_MB_2U_LIB.S9S_MB_2U(SCH_1):PAGE550_I91@PURE_QUANTA.Q_RES(CHIPS)':
 C_PATH='@s9s_mb_2u_lib.s9s_mb_2u(sch_1):page550_i91@pure_quanta.q_res(chips)';

PART_NAME
 R113 'Q_RES_0402LF-33.2,1%,1/16W,CHIA':;

SECTION_NUMBER 1
 '@S9S_MB_2U_LIB.S9S_MB_2U(SCH_1):PAGE550_I27@PURE_QUANTA.Q_RES(CHIPS)':
 C_PATH='@s9s_mb_2u_lib.s9s_mb_2u(sch_1):page550_i27@pure_quanta.q_res(chips)';

PART_NAME
 R111 'Q_RES_0402LF-10K,1%,1/16W,CHIPA':;

SECTION_NUMBER 1
 '@S9S_MB_2U_LIB.S9S_MB_2U(SCH_1):PAGE550_I24@PURE_QUANTA.Q_RES(CHIPS)':
 C_PATH='@s9s_mb_2u_lib.s9s_mb_2u(sch_1):page550_i24@pure_quanta.q_res(chips)';

PART_NAME
 R110 'Q_RES_0402LF-33.2,1%,1/16W,CHIA':;

SECTION_NUMBER 1
 '@S9S_MB_2U_LIB.S9S_MB_2U(SCH_1):PAGE550_I17@PURE_QUANTA.Q_RES(CHIPS)':
 C_PATH='@s9s_mb_2u_lib.s9s_mb_2u(sch_1):page550_i17@pure_quanta.q_res(chips)';

PART_NAME
 R109 'Q_RES_0402LF-33.2,1%,1/16W,CHIA':;

SECTION_NUMBER 1
 '@S9S_MB_2U_LIB.S9S_MB_2U(SCH_1):PAGE550_I44@PURE_QUANTA.Q_RES(CHIPS)':
 C_PATH='@s9s_mb_2u_lib.s9s_mb_2u(sch_1):page550_i44@pure_quanta.q_res(chips)';

PART_NAME
 R1762 'Q_RES_0402LF-33,5%,1/16W,CHIP,A':;

SECTION_NUMBER 1
 '@S9S_MB_2U_LIB.S9S_MB_2U(SCH_1):PAGE563_I161@PURE_QUANTA.Q_RES(CHIPS)':
 C_PATH='@s9s_mb_2u_lib.s9s_mb_2u(sch_1):page563_i161@pure_quanta.q_res(chips)';

PART_NAME
 R1761 'Q_RES_0402LF-33,5%,1/16W,CHIP,A':;

SECTION_NUMBER 1
 '@S9S_MB_2U_LIB.S9S_MB_2U(SCH_1):PAGE563_I160@PURE_QUANTA.Q_RES(CHIPS)':
 C_PATH='@s9s_mb_2u_lib.s9s_mb_2u(sch_1):page563_i160@pure_quanta.q_res(chips)';

PART_NAME
 R1734 'Q_RES_0402LF-2.2K ,5%,1/16W,CHA':;

SECTION_NUMBER 1
 '@S9S_MB_2U_LIB.S9S_MB_2U(SCH_1):PAGE563_I130@PURE_QUANTA.Q_RES(CHIPS)':
 C_PATH='@s9s_mb_2u_lib.s9s_mb_2u(sch_1):page563_i130@pure_quanta.q_res(chips)';

PART_NAME
 R1733 'Q_RES_0402LF-2.2K ,5%,1/16W,CHA':;

SECTION_NUMBER 1
 '@S9S_MB_2U_LIB.S9S_MB_2U(SCH_1):PAGE563_I131@PURE_QUANTA.Q_RES(CHIPS)':
 C_PATH='@s9s_mb_2u_lib.s9s_mb_2u(sch_1):page563_i131@pure_quanta.q_res(chips)';

PART_NAME
 R1732 'Q_RES_0402LF-2K,1%,1/16W,CHIP,A':;

SECTION_NUMBER 1
 '@S9S_MB_2U_LIB.S9S_MB_2U(SCH_1):PAGE563_I124@PURE_QUANTA.Q_RES(CHIPS)':
 C_PATH='@s9s_mb_2u_lib.s9s_mb_2u(sch_1):page563_i124@pure_quanta.q_res(chips)';

PART_NAME
 R1731 'Q_RES_0402LF-2K,1%,1/16W,CHIP,A':;

SECTION_NUMBER 1
 '@S9S_MB_2U_LIB.S9S_MB_2U(SCH_1):PAGE563_I125@PURE_QUANTA.Q_RES(CHIPS)':
 C_PATH='@s9s_mb_2u_lib.s9s_mb_2u(sch_1):page563_i125@pure_quanta.q_res(chips)';

PART_NAME
 R1730 'Q_RES_0402LF-33.2,1%,1/16W,CHIA':;

SECTION_NUMBER 1
 '@S9S_MB_2U_LIB.S9S_MB_2U(SCH_1):PAGE563_I139@PURE_QUANTA.Q_RES(CHIPS)':
 C_PATH='@s9s_mb_2u_lib.s9s_mb_2u(sch_1):page563_i139@pure_quanta.q_res(chips)';

PART_NAME
 R1670 'Q_RES_0402LF-0,5%,1/16W,CHIP,CA':;

SECTION_NUMBER 1
 '@S9S_MB_2U_LIB.S9S_MB_2U(SCH_1):PAGE563_I136@PURE_QUANTA.Q_RES(CHIPS)':
 C_PATH='@s9s_mb_2u_lib.s9s_mb_2u(sch_1):page563_i136@pure_quanta.q_res(chips)';

PART_NAME
 R1669 'Q_RES_0402LF-33.2,1%,1/16W,CHIA':;

SECTION_NUMBER 1
 '@S9S_MB_2U_LIB.S9S_MB_2U(SCH_1):PAGE563_I150@PURE_QUANTA.Q_RES(CHIPS)':
 C_PATH='@s9s_mb_2u_lib.s9s_mb_2u(sch_1):page563_i150@pure_quanta.q_res(chips)';

PART_NAME
 R1668 'Q_RES_0402LF-0,5%,1/16W,CHIP,CA':;

SECTION_NUMBER 1
 '@S9S_MB_2U_LIB.S9S_MB_2U(SCH_1):PAGE563_I151@PURE_QUANTA.Q_RES(CHIPS)':
 C_PATH='@s9s_mb_2u_lib.s9s_mb_2u(sch_1):page563_i151@pure_quanta.q_res(chips)';

PART_NAME
 R1666 'Q_RES_0402LF-2.2K ,5%,1/16W,EMA':;

SECTION_NUMBER 1
 '@S9S_MB_2U_LIB.S9S_MB_2U(SCH_1):PAGE563_I120@PURE_QUANTA.Q_RES(CHIPS)':
 C_PATH='@s9s_mb_2u_lib.s9s_mb_2u(sch_1):page563_i120@pure_quanta.q_res(chips)';

PART_NAME
 R1665 'Q_RES_0402LF-2.2K ,5%,1/16W,EMA':;

SECTION_NUMBER 1
 '@S9S_MB_2U_LIB.S9S_MB_2U(SCH_1):PAGE563_I121@PURE_QUANTA.Q_RES(CHIPS)':
 C_PATH='@s9s_mb_2u_lib.s9s_mb_2u(sch_1):page563_i121@pure_quanta.q_res(chips)';

PART_NAME
 R1664 'Q_RES_0402LF-33,5%,1/16W,CHIP,A':;

SECTION_NUMBER 1
 '@S9S_MB_2U_LIB.S9S_MB_2U(SCH_1):PAGE563_I142@PURE_QUANTA.Q_RES(CHIPS)':
 C_PATH='@s9s_mb_2u_lib.s9s_mb_2u(sch_1):page563_i142@pure_quanta.q_res(chips)';

PART_NAME
 R1663 'Q_RES_0402LF-33,5%,1/16W,CHIP,A':;

SECTION_NUMBER 1
 '@S9S_MB_2U_LIB.S9S_MB_2U(SCH_1):PAGE563_I143@PURE_QUANTA.Q_RES(CHIPS)':
 C_PATH='@s9s_mb_2u_lib.s9s_mb_2u(sch_1):page563_i143@pure_quanta.q_res(chips)';

PART_NAME
 R1662 'Q_RES_0402LF-33,5%,1/16W,EMPTYA':;

SECTION_NUMBER 1
 '@S9S_MB_2U_LIB.S9S_MB_2U(SCH_1):PAGE563_I90@PURE_QUANTA.Q_RES(CHIPS)':
 C_PATH='@s9s_mb_2u_lib.s9s_mb_2u(sch_1):page563_i90@pure_quanta.q_res(chips)';

PART_NAME
 R1661 'Q_RES_0402LF-33,5%,1/16W,EMPTYA':;

SECTION_NUMBER 1
 '@S9S_MB_2U_LIB.S9S_MB_2U(SCH_1):PAGE563_I89@PURE_QUANTA.Q_RES(CHIPS)':
 C_PATH='@s9s_mb_2u_lib.s9s_mb_2u(sch_1):page563_i89@pure_quanta.q_res(chips)';

PART_NAME
 R1526 'Q_RES_0402LF-33.2,1%,1/16W,CHIA':;

SECTION_NUMBER 1
 '@S9S_MB_2U_LIB.S9S_MB_2U(SCH_1):PAGE563_I41@PURE_QUANTA.Q_RES(CHIPS)':
 C_PATH='@s9s_mb_2u_lib.s9s_mb_2u(sch_1):page563_i41@pure_quanta.q_res(chips)';

PART_NAME
 R1525 'Q_RES_0402LF-0,5%,1/16W,CHIP,CA':;

SECTION_NUMBER 1
 '@S9S_MB_2U_LIB.S9S_MB_2U(SCH_1):PAGE563_I40@PURE_QUANTA.Q_RES(CHIPS)':
 C_PATH='@s9s_mb_2u_lib.s9s_mb_2u(sch_1):page563_i40@pure_quanta.q_res(chips)';

PART_NAME
 R1387 'Q_RES_0402LF-2K,1%,1/16W,CHIP,A':;

SECTION_NUMBER 1
 '@S9S_MB_2U_LIB.S9S_MB_2U(SCH_1):PAGE563_I7@PURE_QUANTA.Q_RES(CHIPS)':
 C_PATH='@s9s_mb_2u_lib.s9s_mb_2u(sch_1):page563_i7@pure_quanta.q_res(chips)';

PART_NAME
 R1386 'Q_RES_0402LF-2K,1%,1/16W,CHIP,A':;

SECTION_NUMBER 1
 '@S9S_MB_2U_LIB.S9S_MB_2U(SCH_1):PAGE563_I6@PURE_QUANTA.Q_RES(CHIPS)':
 C_PATH='@s9s_mb_2u_lib.s9s_mb_2u(sch_1):page563_i6@pure_quanta.q_res(chips)';

PART_NAME
 R1385 'Q_RES_0402LF-2K,1%,1/16W,CHIP,A':;

SECTION_NUMBER 1
 '@S9S_MB_2U_LIB.S9S_MB_2U(SCH_1):PAGE563_I5@PURE_QUANTA.Q_RES(CHIPS)':
 C_PATH='@s9s_mb_2u_lib.s9s_mb_2u(sch_1):page563_i5@pure_quanta.q_res(chips)';

PART_NAME
 R1384 'Q_RES_0402LF-2K,1%,1/16W,CHIP,A':;

SECTION_NUMBER 1
 '@S9S_MB_2U_LIB.S9S_MB_2U(SCH_1):PAGE563_I4@PURE_QUANTA.Q_RES(CHIPS)':
 C_PATH='@s9s_mb_2u_lib.s9s_mb_2u(sch_1):page563_i4@pure_quanta.q_res(chips)';

PART_NAME
 R1321 'Q_RES_0402LF-2K,1%,1/16W,CHIP,A':;

SECTION_NUMBER 1
 '@S9S_MB_2U_LIB.S9S_MB_2U(SCH_1):PAGE563_I3@PURE_QUANTA.Q_RES(CHIPS)':
 C_PATH='@s9s_mb_2u_lib.s9s_mb_2u(sch_1):page563_i3@pure_quanta.q_res(chips)';

PART_NAME
 R1319 'Q_RES_0402LF-2K,1%,1/16W,CHIP,A':;

SECTION_NUMBER 1
 '@S9S_MB_2U_LIB.S9S_MB_2U(SCH_1):PAGE563_I2@PURE_QUANTA.Q_RES(CHIPS)':
 C_PATH='@s9s_mb_2u_lib.s9s_mb_2u(sch_1):page563_i2@pure_quanta.q_res(chips)';

PART_NAME
 R600 'Q_RES_0402LF-33,5%,1/16W,CHIP,A':;

SECTION_NUMBER 1
 '@S9S_MB_2U_LIB.S9S_MB_2U(SCH_1):PAGE563_I65@PURE_QUANTA.Q_RES(CHIPS)':
 C_PATH='@s9s_mb_2u_lib.s9s_mb_2u(sch_1):page563_i65@pure_quanta.q_res(chips)';

PART_NAME
 R599 'Q_RES_0402LF-33,5%,1/16W,CHIP,A':;

SECTION_NUMBER 1
 '@S9S_MB_2U_LIB.S9S_MB_2U(SCH_1):PAGE563_I64@PURE_QUANTA.Q_RES(CHIPS)':
 C_PATH='@s9s_mb_2u_lib.s9s_mb_2u(sch_1):page563_i64@pure_quanta.q_res(chips)';

PART_NAME
 R598 'Q_RES_0402LF-33,5%,1/16W,CHIP,A':;

SECTION_NUMBER 1
 '@S9S_MB_2U_LIB.S9S_MB_2U(SCH_1):PAGE563_I63@PURE_QUANTA.Q_RES(CHIPS)':
 C_PATH='@s9s_mb_2u_lib.s9s_mb_2u(sch_1):page563_i63@pure_quanta.q_res(chips)';

PART_NAME
 R597 'Q_RES_0402LF-33,5%,1/16W,CHIP,A':;

SECTION_NUMBER 1
 '@S9S_MB_2U_LIB.S9S_MB_2U(SCH_1):PAGE563_I62@PURE_QUANTA.Q_RES(CHIPS)':
 C_PATH='@s9s_mb_2u_lib.s9s_mb_2u(sch_1):page563_i62@pure_quanta.q_res(chips)';

PART_NAME
 R596 'Q_RES_0402LF-33,5%,1/16W,CHIP,A':;

SECTION_NUMBER 1
 '@S9S_MB_2U_LIB.S9S_MB_2U(SCH_1):PAGE563_I61@PURE_QUANTA.Q_RES(CHIPS)':
 C_PATH='@s9s_mb_2u_lib.s9s_mb_2u(sch_1):page563_i61@pure_quanta.q_res(chips)';

PART_NAME
 R595 'Q_RES_0402LF-33,5%,1/16W,CHIP,A':;

SECTION_NUMBER 1
 '@S9S_MB_2U_LIB.S9S_MB_2U(SCH_1):PAGE563_I60@PURE_QUANTA.Q_RES(CHIPS)':
 C_PATH='@s9s_mb_2u_lib.s9s_mb_2u(sch_1):page563_i60@pure_quanta.q_res(chips)';

PART_NAME
 R594 'Q_RES_0402LF-33,5%,1/16W,CHIP,A':;

SECTION_NUMBER 1
 '@S9S_MB_2U_LIB.S9S_MB_2U(SCH_1):PAGE563_I59@PURE_QUANTA.Q_RES(CHIPS)':
 C_PATH='@s9s_mb_2u_lib.s9s_mb_2u(sch_1):page563_i59@pure_quanta.q_res(chips)';

PART_NAME
 R593 'Q_RES_0402LF-33,5%,1/16W,CHIP,A':;

SECTION_NUMBER 1
 '@S9S_MB_2U_LIB.S9S_MB_2U(SCH_1):PAGE563_I58@PURE_QUANTA.Q_RES(CHIPS)':
 C_PATH='@s9s_mb_2u_lib.s9s_mb_2u(sch_1):page563_i58@pure_quanta.q_res(chips)';

PART_NAME
 R586 'Q_RES_0402LF-33,5%,1/16W,EMPTYA':;

SECTION_NUMBER 1
 '@S9S_MB_2U_LIB.S9S_MB_2U(SCH_1):PAGE563_I106@PURE_QUANTA.Q_RES(CHIPS)':
 C_PATH='@s9s_mb_2u_lib.s9s_mb_2u(sch_1):page563_i106@pure_quanta.q_res(chips)';

PART_NAME
 R585 'Q_RES_0402LF-33,5%,1/16W,EMPTYA':;

SECTION_NUMBER 1
 '@S9S_MB_2U_LIB.S9S_MB_2U(SCH_1):PAGE563_I109@PURE_QUANTA.Q_RES(CHIPS)':
 C_PATH='@s9s_mb_2u_lib.s9s_mb_2u(sch_1):page563_i109@pure_quanta.q_res(chips)';

PART_NAME
 R584 'Q_RES_0402LF-33,5%,1/16W,CHIP,A':;

SECTION_NUMBER 1
 '@S9S_MB_2U_LIB.S9S_MB_2U(SCH_1):PAGE563_I134@PURE_QUANTA.Q_RES(CHIPS)':
 C_PATH='@s9s_mb_2u_lib.s9s_mb_2u(sch_1):page563_i134@pure_quanta.q_res(chips)';

PART_NAME
 R583 'Q_RES_0402LF-33,5%,1/16W,CHIP,A':;

SECTION_NUMBER 1
 '@S9S_MB_2U_LIB.S9S_MB_2U(SCH_1):PAGE563_I135@PURE_QUANTA.Q_RES(CHIPS)':
 C_PATH='@s9s_mb_2u_lib.s9s_mb_2u(sch_1):page563_i135@pure_quanta.q_res(chips)';

PART_NAME
 R582 'Q_RES_0402LF-33,5%,1/16W,CHIP,A':;

SECTION_NUMBER 1
 '@S9S_MB_2U_LIB.S9S_MB_2U(SCH_1):PAGE563_I45@PURE_QUANTA.Q_RES(CHIPS)':
 C_PATH='@s9s_mb_2u_lib.s9s_mb_2u(sch_1):page563_i45@pure_quanta.q_res(chips)';

PART_NAME
 R581 'Q_RES_0402LF-33,5%,1/16W,CHIP,A':;

SECTION_NUMBER 1
 '@S9S_MB_2U_LIB.S9S_MB_2U(SCH_1):PAGE563_I44@PURE_QUANTA.Q_RES(CHIPS)':
 C_PATH='@s9s_mb_2u_lib.s9s_mb_2u(sch_1):page563_i44@pure_quanta.q_res(chips)';

PART_NAME
 R580 'Q_RES_0402LF-33,5%,1/16W,CHIP,A':;

SECTION_NUMBER 1
 '@S9S_MB_2U_LIB.S9S_MB_2U(SCH_1):PAGE563_I39@PURE_QUANTA.Q_RES(CHIPS)':
 C_PATH='@s9s_mb_2u_lib.s9s_mb_2u(sch_1):page563_i39@pure_quanta.q_res(chips)';

PART_NAME
 R579 'Q_RES_0402LF-33,5%,1/16W,CHIP,A':;

SECTION_NUMBER 1
 '@S9S_MB_2U_LIB.S9S_MB_2U(SCH_1):PAGE563_I38@PURE_QUANTA.Q_RES(CHIPS)':
 C_PATH='@s9s_mb_2u_lib.s9s_mb_2u(sch_1):page563_i38@pure_quanta.q_res(chips)';

PART_NAME
 R578 'Q_RES_0402LF-33,5%,1/16W,CHIP,A':;

SECTION_NUMBER 1
 '@S9S_MB_2U_LIB.S9S_MB_2U(SCH_1):PAGE563_I37@PURE_QUANTA.Q_RES(CHIPS)':
 C_PATH='@s9s_mb_2u_lib.s9s_mb_2u(sch_1):page563_i37@pure_quanta.q_res(chips)';

PART_NAME
 R577 'Q_RES_0402LF-33,5%,1/16W,CHIP,A':;

SECTION_NUMBER 1
 '@S9S_MB_2U_LIB.S9S_MB_2U(SCH_1):PAGE563_I36@PURE_QUANTA.Q_RES(CHIPS)':
 C_PATH='@s9s_mb_2u_lib.s9s_mb_2u(sch_1):page563_i36@pure_quanta.q_res(chips)';

PART_NAME
 R108 'Q_RES_0402LF-33.2,1%,1/16W,CHIA':;

SECTION_NUMBER 1
 '@S9S_MB_2U_LIB.S9S_MB_2U(SCH_1):PAGE563_I42@PURE_QUANTA.Q_RES(CHIPS)':
 C_PATH='@s9s_mb_2u_lib.s9s_mb_2u(sch_1):page563_i42@pure_quanta.q_res(chips)';

PART_NAME
 R107 'Q_RES_0402LF-0,5%,1/16W,CHIP,CA':;

SECTION_NUMBER 1
 '@S9S_MB_2U_LIB.S9S_MB_2U(SCH_1):PAGE563_I43@PURE_QUANTA.Q_RES(CHIPS)':
 C_PATH='@s9s_mb_2u_lib.s9s_mb_2u(sch_1):page563_i43@pure_quanta.q_res(chips)';

PART_NAME
 R119 'Q_RES_0402LF-10K,1%,1/16W,EMPTA':;

SECTION_NUMBER 1
 '@S9S_MB_2U_LIB.S9S_MB_2U(SCH_1):PAGE488_I98@PURE_QUANTA.Q_RES(CHIPS)':
 C_PATH='@s9s_mb_2u_lib.s9s_mb_2u(sch_1):page488_i98@pure_quanta.q_res(chips)';

PART_NAME
 R118 'Q_RES_0402LF-10K,1%,1/16W,CHIPA':;

SECTION_NUMBER 1
 '@S9S_MB_2U_LIB.S9S_MB_2U(SCH_1):PAGE488_I97@PURE_QUANTA.Q_RES(CHIPS)':
 C_PATH='@s9s_mb_2u_lib.s9s_mb_2u(sch_1):page488_i97@pure_quanta.q_res(chips)';

PART_NAME
 R117 'Q_RES_0402LF-10K,1%,1/16W,CHIPA':;

SECTION_NUMBER 1
 '@S9S_MB_2U_LIB.S9S_MB_2U(SCH_1):PAGE488_I96@PURE_QUANTA.Q_RES(CHIPS)':
 C_PATH='@s9s_mb_2u_lib.s9s_mb_2u(sch_1):page488_i96@pure_quanta.q_res(chips)';

PART_NAME
 R116 'Q_RES_0402LF-10K,1%,1/16W,EMPTA':;

SECTION_NUMBER 1
 '@S9S_MB_2U_LIB.S9S_MB_2U(SCH_1):PAGE488_I93@PURE_QUANTA.Q_RES(CHIPS)':
 C_PATH='@s9s_mb_2u_lib.s9s_mb_2u(sch_1):page488_i93@pure_quanta.q_res(chips)';

PART_NAME
 R115 'Q_RES_0402LF-10K,1%,1/16W,CHIPA':;

SECTION_NUMBER 1
 '@S9S_MB_2U_LIB.S9S_MB_2U(SCH_1):PAGE488_I92@PURE_QUANTA.Q_RES(CHIPS)':
 C_PATH='@s9s_mb_2u_lib.s9s_mb_2u(sch_1):page488_i92@pure_quanta.q_res(chips)';

PART_NAME
 R114 'Q_RES_0402LF-10K,1%,1/16W,CHIPA':;

SECTION_NUMBER 1
 '@S9S_MB_2U_LIB.S9S_MB_2U(SCH_1):PAGE488_I91@PURE_QUANTA.Q_RES(CHIPS)':
 C_PATH='@s9s_mb_2u_lib.s9s_mb_2u(sch_1):page488_i91@pure_quanta.q_res(chips)';

PART_NAME
 R105 'Q_RES_0402LF-33,5%,1/16W,CHIP,A':;

SECTION_NUMBER 1
 '@S9S_MB_2U_LIB.S9S_MB_2U(SCH_1):PAGE488_I109@PURE_QUANTA.Q_RES(CHIPS)':
 C_PATH='@s9s_mb_2u_lib.s9s_mb_2u(sch_1):page488_i109@pure_quanta.q_res(chips)';

PART_NAME
 R104 'Q_RES_0402LF-33,5%,1/16W,CHIP,A':;

SECTION_NUMBER 1
 '@S9S_MB_2U_LIB.S9S_MB_2U(SCH_1):PAGE488_I108@PURE_QUANTA.Q_RES(CHIPS)':
 C_PATH='@s9s_mb_2u_lib.s9s_mb_2u(sch_1):page488_i108@pure_quanta.q_res(chips)';

PART_NAME
 R103 'Q_RES_0402LF-33,5%,1/16W,CHIP,A':;

SECTION_NUMBER 1
 '@S9S_MB_2U_LIB.S9S_MB_2U(SCH_1):PAGE488_I107@PURE_QUANTA.Q_RES(CHIPS)':
 C_PATH='@s9s_mb_2u_lib.s9s_mb_2u(sch_1):page488_i107@pure_quanta.q_res(chips)';

PART_NAME
 R102 'Q_RES_0402LF-33,5%,1/16W,CHIP,A':;

SECTION_NUMBER 1
 '@S9S_MB_2U_LIB.S9S_MB_2U(SCH_1):PAGE488_I106@PURE_QUANTA.Q_RES(CHIPS)':
 C_PATH='@s9s_mb_2u_lib.s9s_mb_2u(sch_1):page488_i106@pure_quanta.q_res(chips)';

PART_NAME
 R101 'Q_RES_0402LF-33,5%,1/16W,CHIP,A':;

SECTION_NUMBER 1
 '@S9S_MB_2U_LIB.S9S_MB_2U(SCH_1):PAGE488_I85@PURE_QUANTA.Q_RES(CHIPS)':
 C_PATH='@s9s_mb_2u_lib.s9s_mb_2u(sch_1):page488_i85@pure_quanta.q_res(chips)';

PART_NAME
 R100 'Q_RES_0402LF-33,5%,1/16W,CHIP,A':;

SECTION_NUMBER 1
 '@S9S_MB_2U_LIB.S9S_MB_2U(SCH_1):PAGE488_I84@PURE_QUANTA.Q_RES(CHIPS)':
 C_PATH='@s9s_mb_2u_lib.s9s_mb_2u(sch_1):page488_i84@pure_quanta.q_res(chips)';

PART_NAME
 R99 'Q_RES_0402LF-33,5%,1/16W,CHIP,A':;

SECTION_NUMBER 1
 '@S9S_MB_2U_LIB.S9S_MB_2U(SCH_1):PAGE488_I79@PURE_QUANTA.Q_RES(CHIPS)':
 C_PATH='@s9s_mb_2u_lib.s9s_mb_2u(sch_1):page488_i79@pure_quanta.q_res(chips)';

PART_NAME
 R98 'Q_RES_0402LF-33,5%,1/16W,CHIP,A':;

SECTION_NUMBER 1
 '@S9S_MB_2U_LIB.S9S_MB_2U(SCH_1):PAGE488_I77@PURE_QUANTA.Q_RES(CHIPS)':
 C_PATH='@s9s_mb_2u_lib.s9s_mb_2u(sch_1):page488_i77@pure_quanta.q_res(chips)';

PART_NAME
 R97 'Q_RES_0402LF-240,1%,1/16W,EMPTA':;

SECTION_NUMBER 1
 '@S9S_MB_2U_LIB.S9S_MB_2U(SCH_1):PAGE488_I114@PURE_QUANTA.Q_RES(CHIPS)':
 C_PATH='@s9s_mb_2u_lib.s9s_mb_2u(sch_1):page488_i114@pure_quanta.q_res(chips)';

PART_NAME
 R96 'Q_RES_0402LF-240,1%,1/16W,EMPTA':;

SECTION_NUMBER 1
 '@S9S_MB_2U_LIB.S9S_MB_2U(SCH_1):PAGE488_I22@PURE_QUANTA.Q_RES(CHIPS)':
 C_PATH='@s9s_mb_2u_lib.s9s_mb_2u(sch_1):page488_i22@pure_quanta.q_res(chips)';

PART_NAME
 R95 'Q_RES_0402LF-240,1%,1/16W,EMPTA':;

SECTION_NUMBER 1
 '@S9S_MB_2U_LIB.S9S_MB_2U(SCH_1):PAGE488_I23@PURE_QUANTA.Q_RES(CHIPS)':
 C_PATH='@s9s_mb_2u_lib.s9s_mb_2u(sch_1):page488_i23@pure_quanta.q_res(chips)';

PART_NAME
 R94 'Q_RES_0402LF-240,1%,1/16W,EMPTA':;

SECTION_NUMBER 1
 '@S9S_MB_2U_LIB.S9S_MB_2U(SCH_1):PAGE488_I25@PURE_QUANTA.Q_RES(CHIPS)':
 C_PATH='@s9s_mb_2u_lib.s9s_mb_2u(sch_1):page488_i25@pure_quanta.q_res(chips)';

PART_NAME
 R93 'Q_RES_0402LF-240,1%,1/16W,EMPTA':;

SECTION_NUMBER 1
 '@S9S_MB_2U_LIB.S9S_MB_2U(SCH_1):PAGE488_I141@PURE_QUANTA.Q_RES(CHIPS)':
 C_PATH='@s9s_mb_2u_lib.s9s_mb_2u(sch_1):page488_i141@pure_quanta.q_res(chips)';

PART_NAME
 R92 'Q_RES_0402LF-240,1%,1/16W,EMPTA':;

SECTION_NUMBER 1
 '@S9S_MB_2U_LIB.S9S_MB_2U(SCH_1):PAGE488_I140@PURE_QUANTA.Q_RES(CHIPS)':
 C_PATH='@s9s_mb_2u_lib.s9s_mb_2u(sch_1):page488_i140@pure_quanta.q_res(chips)';

PART_NAME
 R91 'Q_RES_0402LF-240,1%,1/16W,EMPTA':;

SECTION_NUMBER 1
 '@S9S_MB_2U_LIB.S9S_MB_2U(SCH_1):PAGE488_I136@PURE_QUANTA.Q_RES(CHIPS)':
 C_PATH='@s9s_mb_2u_lib.s9s_mb_2u(sch_1):page488_i136@pure_quanta.q_res(chips)';

PART_NAME
 R90 'Q_RES_0402LF-240,1%,1/16W,EMPTA':;

SECTION_NUMBER 1
 '@S9S_MB_2U_LIB.S9S_MB_2U(SCH_1):PAGE488_I135@PURE_QUANTA.Q_RES(CHIPS)':
 C_PATH='@s9s_mb_2u_lib.s9s_mb_2u(sch_1):page488_i135@pure_quanta.q_res(chips)';

PART_NAME
 R1270 'Q_RES_0402LF-240,1%,1/16W,EMPTA':;

SECTION_NUMBER 1
 '@S9S_MB_2U_LIB.S9S_MB_2U(SCH_1):PAGE340_I55@PURE_QUANTA.Q_RES(CHIPS)':
 C_PATH='@s9s_mb_2u_lib.s9s_mb_2u(sch_1):page340_i55@pure_quanta.q_res(chips)';

PART_NAME
 R66 'Q_RES_0402LF-100,1%,1/16W,CHIPA':;

SECTION_NUMBER 1
 '@S9S_MB_2U_LIB.S9S_MB_2U(SCH_1):PAGE340_I7@PURE_QUANTA.Q_RES(CHIPS)':
 C_PATH='@s9s_mb_2u_lib.s9s_mb_2u(sch_1):page340_i7@pure_quanta.q_res(chips)';

PART_NAME
 R65 'Q_RES_0402LF-100,1%,1/16W,CHIPA':;

SECTION_NUMBER 1
 '@S9S_MB_2U_LIB.S9S_MB_2U(SCH_1):PAGE340_I8@PURE_QUANTA.Q_RES(CHIPS)':
 C_PATH='@s9s_mb_2u_lib.s9s_mb_2u(sch_1):page340_i8@pure_quanta.q_res(chips)';

PART_NAME
 R64 'Q_RES_0402LF-200,1%,1/16W,CHIPA':;

SECTION_NUMBER 1
 '@S9S_MB_2U_LIB.S9S_MB_2U(SCH_1):PAGE340_I9@PURE_QUANTA.Q_RES(CHIPS)':
 C_PATH='@s9s_mb_2u_lib.s9s_mb_2u(sch_1):page340_i9@pure_quanta.q_res(chips)';

PART_NAME
 R63 'Q_RES_0402LF-33.2,1%,1/16W,CHIA':;

SECTION_NUMBER 1
 '@S9S_MB_2U_LIB.S9S_MB_2U(SCH_1):PAGE340_I10@PURE_QUANTA.Q_RES(CHIPS)':
 C_PATH='@s9s_mb_2u_lib.s9s_mb_2u(sch_1):page340_i10@pure_quanta.q_res(chips)';

PART_NAME
 R62 'Q_RES_0402LF-100,1%,1/16W,CHIPA':;

SECTION_NUMBER 1
 '@S9S_MB_2U_LIB.S9S_MB_2U(SCH_1):PAGE340_I11@PURE_QUANTA.Q_RES(CHIPS)':
 C_PATH='@s9s_mb_2u_lib.s9s_mb_2u(sch_1):page340_i11@pure_quanta.q_res(chips)';

PART_NAME
 R61 'Q_RES_0402LF-10,1%,1/16W,CHIP,A':;

SECTION_NUMBER 1
 '@S9S_MB_2U_LIB.S9S_MB_2U(SCH_1):PAGE340_I16@PURE_QUANTA.Q_RES(CHIPS)':
 C_PATH='@s9s_mb_2u_lib.s9s_mb_2u(sch_1):page340_i16@pure_quanta.q_res(chips)';

PART_NAME
 R1935 'Q_RES_0402LF-33.2,1%,1/16W,CHIA':;

SECTION_NUMBER 1
 '@S9S_MB_2U_LIB.S9S_MB_2U(SCH_1):PAGE341_I82@PURE_QUANTA.Q_RES(CHIPS)':
 C_PATH='@s9s_mb_2u_lib.s9s_mb_2u(sch_1):page341_i82@pure_quanta.q_res(chips)';

PART_NAME
 R1934 'Q_RES_0402LF-33.2,1%,1/16W,CHIA':;

SECTION_NUMBER 1
 '@S9S_MB_2U_LIB.S9S_MB_2U(SCH_1):PAGE341_I81@PURE_QUANTA.Q_RES(CHIPS)':
 C_PATH='@s9s_mb_2u_lib.s9s_mb_2u(sch_1):page341_i81@pure_quanta.q_res(chips)';

PART_NAME
 R560 'Q_RES_0402LF-49.9     ,1%  ,1/A':;

SECTION_NUMBER 1
 '@S9S_MB_2U_LIB.S9S_MB_2U(SCH_1):PAGE341_I70@PURE_QUANTA.Q_RES(CHIPS)':
 C_PATH='@s9s_mb_2u_lib.s9s_mb_2u(sch_1):page341_i70@pure_quanta.q_res(chips)';

PART_NAME
 R559 'Q_RES_0402LF-100,1%,1/16W,CHIPA':;

SECTION_NUMBER 1
 '@S9S_MB_2U_LIB.S9S_MB_2U(SCH_1):PAGE341_I69@PURE_QUANTA.Q_RES(CHIPS)':
 C_PATH='@s9s_mb_2u_lib.s9s_mb_2u(sch_1):page341_i69@pure_quanta.q_res(chips)';

PART_NAME
 R558 'Q_RES_0402LF-49.9     ,1%  ,1/A':;

SECTION_NUMBER 1
 '@S9S_MB_2U_LIB.S9S_MB_2U(SCH_1):PAGE341_I73@PURE_QUANTA.Q_RES(CHIPS)':
 C_PATH='@s9s_mb_2u_lib.s9s_mb_2u(sch_1):page341_i73@pure_quanta.q_res(chips)';

PART_NAME
 R557 'Q_RES_0402LF-100,1%,1/16W,CHIPA':;

SECTION_NUMBER 1
 '@S9S_MB_2U_LIB.S9S_MB_2U(SCH_1):PAGE341_I74@PURE_QUANTA.Q_RES(CHIPS)':
 C_PATH='@s9s_mb_2u_lib.s9s_mb_2u(sch_1):page341_i74@pure_quanta.q_res(chips)';

PART_NAME
 R516 'Q_RES_0402LF-49.9     ,1%  ,1/A':;

SECTION_NUMBER 1
 '@S9S_MB_2U_LIB.S9S_MB_2U(SCH_1):PAGE341_I63@PURE_QUANTA.Q_RES(CHIPS)':
 C_PATH='@s9s_mb_2u_lib.s9s_mb_2u(sch_1):page341_i63@pure_quanta.q_res(chips)';

PART_NAME
 R60 'Q_RES_0402LF-200,1%,1/16W,CHIPA':;

SECTION_NUMBER 1
 '@S9S_MB_2U_LIB.S9S_MB_2U(SCH_1):PAGE341_I53@PURE_QUANTA.Q_RES(CHIPS)':
 C_PATH='@s9s_mb_2u_lib.s9s_mb_2u(sch_1):page341_i53@pure_quanta.q_res(chips)';

PART_NAME
 R59 'Q_RES_0402LF-0,5%,1/16W,CHIP,CA':;

SECTION_NUMBER 1
 '@S9S_MB_2U_LIB.S9S_MB_2U(SCH_1):PAGE341_I52@PURE_QUANTA.Q_RES(CHIPS)':
 C_PATH='@s9s_mb_2u_lib.s9s_mb_2u(sch_1):page341_i52@pure_quanta.q_res(chips)';

PART_NAME
 R58 'Q_RES_0402LF-0,5%,1/16W,CHIP,CA':;

SECTION_NUMBER 1
 '@S9S_MB_2U_LIB.S9S_MB_2U(SCH_1):PAGE341_I51@PURE_QUANTA.Q_RES(CHIPS)':
 C_PATH='@s9s_mb_2u_lib.s9s_mb_2u(sch_1):page341_i51@pure_quanta.q_res(chips)';

PART_NAME
 R57 'Q_RES_0402LF-200,1%,1/16W,CHIPA':;

SECTION_NUMBER 1
 '@S9S_MB_2U_LIB.S9S_MB_2U(SCH_1):PAGE341_I56@PURE_QUANTA.Q_RES(CHIPS)':
 C_PATH='@s9s_mb_2u_lib.s9s_mb_2u(sch_1):page341_i56@pure_quanta.q_res(chips)';

PART_NAME
 R56 'Q_RES_0402LF-0,5%,1/16W,CHIP,CA':;

SECTION_NUMBER 1
 '@S9S_MB_2U_LIB.S9S_MB_2U(SCH_1):PAGE341_I55@PURE_QUANTA.Q_RES(CHIPS)':
 C_PATH='@s9s_mb_2u_lib.s9s_mb_2u(sch_1):page341_i55@pure_quanta.q_res(chips)';

PART_NAME
 R55 'Q_RES_0402LF-0,5%,1/16W,CHIP,CA':;

SECTION_NUMBER 1
 '@S9S_MB_2U_LIB.S9S_MB_2U(SCH_1):PAGE341_I54@PURE_QUANTA.Q_RES(CHIPS)':
 C_PATH='@s9s_mb_2u_lib.s9s_mb_2u(sch_1):page341_i54@pure_quanta.q_res(chips)';

PART_NAME
 R54 'Q_RES_0402LF-10,1%,1/16W,CHIP,A':;

SECTION_NUMBER 1
 '@S9S_MB_2U_LIB.S9S_MB_2U(SCH_1):PAGE343_I22@PURE_QUANTA.Q_RES(CHIPS)':
 C_PATH='@s9s_mb_2u_lib.s9s_mb_2u(sch_1):page343_i22@pure_quanta.q_res(chips)';

PART_NAME
 R53 'Q_RES_0402LF-10,1%,1/16W,CHIP,A':;

SECTION_NUMBER 1
 '@S9S_MB_2U_LIB.S9S_MB_2U(SCH_1):PAGE343_I23@PURE_QUANTA.Q_RES(CHIPS)':
 C_PATH='@s9s_mb_2u_lib.s9s_mb_2u(sch_1):page343_i23@pure_quanta.q_res(chips)';

PART_NAME
 R52 'Q_RES_0402LF-100,1%,1/16W,CHIPA':;

SECTION_NUMBER 1
 '@S9S_MB_2U_LIB.S9S_MB_2U(SCH_1):PAGE343_I25@PURE_QUANTA.Q_RES(CHIPS)':
 C_PATH='@s9s_mb_2u_lib.s9s_mb_2u(sch_1):page343_i25@pure_quanta.q_res(chips)';

PART_NAME
 R51 'Q_RES_0402LF-100,1%,1/16W,CHIPA':;

SECTION_NUMBER 1
 '@S9S_MB_2U_LIB.S9S_MB_2U(SCH_1):PAGE343_I24@PURE_QUANTA.Q_RES(CHIPS)':
 C_PATH='@s9s_mb_2u_lib.s9s_mb_2u(sch_1):page343_i24@pure_quanta.q_res(chips)';

PART_NAME
 R50 'Q_RES_0402LF-499,1%,1/16W,CHIPA':;

SECTION_NUMBER 1
 '@S9S_MB_2U_LIB.S9S_MB_2U(SCH_1):PAGE343_I35@PURE_QUANTA.Q_RES(CHIPS)':
 C_PATH='@s9s_mb_2u_lib.s9s_mb_2u(sch_1):page343_i35@pure_quanta.q_res(chips)';

PART_NAME
 R49 'Q_RES_0402LF-499,1%,1/16W,CHIPA':;

SECTION_NUMBER 1
 '@S9S_MB_2U_LIB.S9S_MB_2U(SCH_1):PAGE343_I34@PURE_QUANTA.Q_RES(CHIPS)':
 C_PATH='@s9s_mb_2u_lib.s9s_mb_2u(sch_1):page343_i34@pure_quanta.q_res(chips)';

PART_NAME
 R25 'Q_RES_0402LF-10,1%,1/16W,CHIP,A':;

SECTION_NUMBER 1
 '@S9S_MB_2U_LIB.S9S_MB_2U(SCH_1):PAGE16_I26@PURE_QUANTA.Q_RES(CHIPS)':
 C_PATH='@s9s_mb_2u_lib.s9s_mb_2u(sch_1):page16_i26@pure_quanta.q_res(chips)';

PART_NAME
 R24 'Q_RES_0402LF-10,1%,1/16W,CHIP,A':;

SECTION_NUMBER 1
 '@S9S_MB_2U_LIB.S9S_MB_2U(SCH_1):PAGE16_I25@PURE_QUANTA.Q_RES(CHIPS)':
 C_PATH='@s9s_mb_2u_lib.s9s_mb_2u(sch_1):page16_i25@pure_quanta.q_res(chips)';

PART_NAME
 R23 'Q_RES_0402LF-100,1%,1/16W,CHIPA':;

SECTION_NUMBER 1
 '@S9S_MB_2U_LIB.S9S_MB_2U(SCH_1):PAGE16_I20@PURE_QUANTA.Q_RES(CHIPS)':
 C_PATH='@s9s_mb_2u_lib.s9s_mb_2u(sch_1):page16_i20@pure_quanta.q_res(chips)';

PART_NAME
 R22 'Q_RES_0402LF-100,1%,1/16W,CHIPA':;

SECTION_NUMBER 1
 '@S9S_MB_2U_LIB.S9S_MB_2U(SCH_1):PAGE16_I19@PURE_QUANTA.Q_RES(CHIPS)':
 C_PATH='@s9s_mb_2u_lib.s9s_mb_2u(sch_1):page16_i19@pure_quanta.q_res(chips)';

PART_NAME
 R21 'Q_RES_0402LF-0,5%,1/16W,CHIP,CA':;

SECTION_NUMBER 1
 '@S9S_MB_2U_LIB.S9S_MB_2U(SCH_1):PAGE16_I32@PURE_QUANTA.Q_RES(CHIPS)':
 C_PATH='@s9s_mb_2u_lib.s9s_mb_2u(sch_1):page16_i32@pure_quanta.q_res(chips)';

PART_NAME
 R20 'Q_RES_0402LF-0,5%,1/16W,CHIP,CA':;

SECTION_NUMBER 1
 '@S9S_MB_2U_LIB.S9S_MB_2U(SCH_1):PAGE16_I31@PURE_QUANTA.Q_RES(CHIPS)':
 C_PATH='@s9s_mb_2u_lib.s9s_mb_2u(sch_1):page16_i31@pure_quanta.q_res(chips)';

PART_NAME
 R19 'Q_RES_0402LF-499,1%,1/16W,CHIPA':;

SECTION_NUMBER 1
 '@S9S_MB_2U_LIB.S9S_MB_2U(SCH_1):PAGE16_I36@PURE_QUANTA.Q_RES(CHIPS)':
 C_PATH='@s9s_mb_2u_lib.s9s_mb_2u(sch_1):page16_i36@pure_quanta.q_res(chips)';

PART_NAME
 R18 'Q_RES_0402LF-499,1%,1/16W,CHIPA':;

SECTION_NUMBER 1
 '@S9S_MB_2U_LIB.S9S_MB_2U(SCH_1):PAGE16_I35@PURE_QUANTA.Q_RES(CHIPS)':
 C_PATH='@s9s_mb_2u_lib.s9s_mb_2u(sch_1):page16_i35@pure_quanta.q_res(chips)';

PART_NAME
 R1227 'Q_RES_0402LF-10K,1%,1/16W,CHIPA':;

SECTION_NUMBER 1
 '@S9S_MB_2U_LIB.S9S_MB_2U(SCH_1):PAGE339_I56@PURE_QUANTA.Q_RES(CHIPS)':
 C_PATH='@s9s_mb_2u_lib.s9s_mb_2u(sch_1):page339_i56@pure_quanta.q_res(chips)';

PART_NAME
 R1226 'Q_RES_0402LF-1K,1%,1/16W,CHIP,A':;

SECTION_NUMBER 1
 '@S9S_MB_2U_LIB.S9S_MB_2U(SCH_1):PAGE339_I52@PURE_QUANTA.Q_RES(CHIPS)':
 C_PATH='@s9s_mb_2u_lib.s9s_mb_2u(sch_1):page339_i52@pure_quanta.q_res(chips)';

PART_NAME
 R1225 'Q_RES_0402LF-10K,1%,1/16W,CHIPA':;

SECTION_NUMBER 1
 '@S9S_MB_2U_LIB.S9S_MB_2U(SCH_1):PAGE339_I51@PURE_QUANTA.Q_RES(CHIPS)':
 C_PATH='@s9s_mb_2u_lib.s9s_mb_2u(sch_1):page339_i51@pure_quanta.q_res(chips)';

PART_NAME
 R1224 'Q_RES_0402LF-10K,1%,1/16W,CHIPA':;

SECTION_NUMBER 1
 '@S9S_MB_2U_LIB.S9S_MB_2U(SCH_1):PAGE339_I50@PURE_QUANTA.Q_RES(CHIPS)':
 C_PATH='@s9s_mb_2u_lib.s9s_mb_2u(sch_1):page339_i50@pure_quanta.q_res(chips)';

PART_NAME
 R1223 'Q_RES_0402LF-10K,1%,1/16W,EMPTA':;

SECTION_NUMBER 1
 '@S9S_MB_2U_LIB.S9S_MB_2U(SCH_1):PAGE339_I49@PURE_QUANTA.Q_RES(CHIPS)':
 C_PATH='@s9s_mb_2u_lib.s9s_mb_2u(sch_1):page339_i49@pure_quanta.q_res(chips)';

PART_NAME
 R1219 'Q_RES_0402LF-33.2,1%,1/16W,CHIA':;

SECTION_NUMBER 1
 '@S9S_MB_2U_LIB.S9S_MB_2U(SCH_1):PAGE339_I27@PURE_QUANTA.Q_RES(CHIPS)':
 C_PATH='@s9s_mb_2u_lib.s9s_mb_2u(sch_1):page339_i27@pure_quanta.q_res(chips)';

PART_NAME
 R1218 'Q_RES_0402LF-33.2,1%,1/16W,CHIA':;

SECTION_NUMBER 1
 '@S9S_MB_2U_LIB.S9S_MB_2U(SCH_1):PAGE339_I26@PURE_QUANTA.Q_RES(CHIPS)':
 C_PATH='@s9s_mb_2u_lib.s9s_mb_2u(sch_1):page339_i26@pure_quanta.q_res(chips)';

PART_NAME
 R316 'Q_RES_0402LF-4.32K,1%,1/16W,CHA':;

SECTION_NUMBER 1
 '@S9S_MB_2U_LIB.S9S_MB_2U(SCH_1):PAGE339_I59@PURE_QUANTA.Q_RES(CHIPS)':
 C_PATH='@s9s_mb_2u_lib.s9s_mb_2u(sch_1):page339_i59@pure_quanta.q_res(chips)';

PART_NAME
 R70 'Q_RES_0402LF-10K,1%,1/16W,CHIPA':;

SECTION_NUMBER 1
 '@S9S_MB_2U_LIB.S9S_MB_2U(SCH_1):PAGE339_I17@PURE_QUANTA.Q_RES(CHIPS)':
 C_PATH='@s9s_mb_2u_lib.s9s_mb_2u(sch_1):page339_i17@pure_quanta.q_res(chips)';

PART_NAME
 R69 'Q_RES_0402LF-10K,1%,1/16W,CHIPA':;

SECTION_NUMBER 1
 '@S9S_MB_2U_LIB.S9S_MB_2U(SCH_1):PAGE339_I16@PURE_QUANTA.Q_RES(CHIPS)':
 C_PATH='@s9s_mb_2u_lib.s9s_mb_2u(sch_1):page339_i16@pure_quanta.q_res(chips)';

PART_NAME
 R68 'Q_RES_0402LF-33.2,1%,1/16W,CHIA':;

SECTION_NUMBER 1
 '@S9S_MB_2U_LIB.S9S_MB_2U(SCH_1):PAGE339_I13@PURE_QUANTA.Q_RES(CHIPS)':
 C_PATH='@s9s_mb_2u_lib.s9s_mb_2u(sch_1):page339_i13@pure_quanta.q_res(chips)';

PART_NAME
 R67 'Q_RES_0402LF-33.2,1%,1/16W,CHIA':;

SECTION_NUMBER 1
 '@S9S_MB_2U_LIB.S9S_MB_2U(SCH_1):PAGE339_I12@PURE_QUANTA.Q_RES(CHIPS)':
 C_PATH='@s9s_mb_2u_lib.s9s_mb_2u(sch_1):page339_i12@pure_quanta.q_res(chips)';

PART_NAME
 R9 'Q_RES_0402LF-4.32K,1%,1/16W,CHA':;

SECTION_NUMBER 1
 '@S9S_MB_2U_LIB.S9S_MB_2U(SCH_1):PAGE339_I57@PURE_QUANTA.Q_RES(CHIPS)':
 C_PATH='@s9s_mb_2u_lib.s9s_mb_2u(sch_1):page339_i57@pure_quanta.q_res(chips)';

PART_NAME
 R1554 'Q_RES_0402LF-10K,1%,1/16W,CHIPA':;

SECTION_NUMBER 1
 '@S9S_MB_2U_LIB.S9S_MB_2U(SCH_1):PAGE463_I62@PURE_QUANTA.Q_RES(CHIPS)':
 C_PATH='@s9s_mb_2u_lib.s9s_mb_2u(sch_1):page463_i62@pure_quanta.q_res(chips)';

PART_NAME
 R1459 'Q_RES_0402LF-10K,1%,1/16W,CHIPA':;

SECTION_NUMBER 1
 '@S9S_MB_2U_LIB.S9S_MB_2U(SCH_1):PAGE463_I51@PURE_QUANTA.Q_RES(CHIPS)':
 C_PATH='@s9s_mb_2u_lib.s9s_mb_2u(sch_1):page463_i51@pure_quanta.q_res(chips)';

PART_NAME
 R1458 'Q_RES_0402LF-10K,1%,1/16W,CHIPA':;

SECTION_NUMBER 1
 '@S9S_MB_2U_LIB.S9S_MB_2U(SCH_1):PAGE463_I50@PURE_QUANTA.Q_RES(CHIPS)':
 C_PATH='@s9s_mb_2u_lib.s9s_mb_2u(sch_1):page463_i50@pure_quanta.q_res(chips)';

PART_NAME
 R1450 'Q_RES_0402LF-10K,1%,1/16W,CHIPA':;

SECTION_NUMBER 1
 '@S9S_MB_2U_LIB.S9S_MB_2U(SCH_1):PAGE463_I42@PURE_QUANTA.Q_RES(CHIPS)':
 C_PATH='@s9s_mb_2u_lib.s9s_mb_2u(sch_1):page463_i42@pure_quanta.q_res(chips)';

PART_NAME
 R1449 'Q_RES_0402LF-10K,1%,1/16W,CHIPA':;

SECTION_NUMBER 1
 '@S9S_MB_2U_LIB.S9S_MB_2U(SCH_1):PAGE463_I41@PURE_QUANTA.Q_RES(CHIPS)':
 C_PATH='@s9s_mb_2u_lib.s9s_mb_2u(sch_1):page463_i41@pure_quanta.q_res(chips)';

PART_NAME
 R1344 'Q_RES_0402LF-10K,1%,1/16W,EMPTA':;

SECTION_NUMBER 1
 '@S9S_MB_2U_LIB.S9S_MB_2U(SCH_1):PAGE463_I40@PURE_QUANTA.Q_RES(CHIPS)':
 C_PATH='@s9s_mb_2u_lib.s9s_mb_2u(sch_1):page463_i40@pure_quanta.q_res(chips)';

PART_NAME
 R1262 'Q_RES_0402LF-10K,1%,1/16W,EMPTA':;

SECTION_NUMBER 1
 '@S9S_MB_2U_LIB.S9S_MB_2U(SCH_1):PAGE463_I11@PURE_QUANTA.Q_RES(CHIPS)':
 C_PATH='@s9s_mb_2u_lib.s9s_mb_2u(sch_1):page463_i11@pure_quanta.q_res(chips)';

PART_NAME
 R1261 'Q_RES_0402LF-10K,1%,1/16W,EMPTA':;

SECTION_NUMBER 1
 '@S9S_MB_2U_LIB.S9S_MB_2U(SCH_1):PAGE463_I18@PURE_QUANTA.Q_RES(CHIPS)':
 C_PATH='@s9s_mb_2u_lib.s9s_mb_2u(sch_1):page463_i18@pure_quanta.q_res(chips)';

PART_NAME
 R1260 'Q_RES_0402LF-10K,1%,1/16W,EMPTA':;

SECTION_NUMBER 1
 '@S9S_MB_2U_LIB.S9S_MB_2U(SCH_1):PAGE463_I17@PURE_QUANTA.Q_RES(CHIPS)':
 C_PATH='@s9s_mb_2u_lib.s9s_mb_2u(sch_1):page463_i17@pure_quanta.q_res(chips)';

PART_NAME
 R1259 'Q_RES_0402LF-10K,1%,1/16W,CHIPA':;

SECTION_NUMBER 1
 '@S9S_MB_2U_LIB.S9S_MB_2U(SCH_1):PAGE463_I8@PURE_QUANTA.Q_RES(CHIPS)':
 C_PATH='@s9s_mb_2u_lib.s9s_mb_2u(sch_1):page463_i8@pure_quanta.q_res(chips)';

PART_NAME
 R1258 'Q_RES_0402LF-10K,1%,1/16W,CHIPA':;

SECTION_NUMBER 1
 '@S9S_MB_2U_LIB.S9S_MB_2U(SCH_1):PAGE463_I6@PURE_QUANTA.Q_RES(CHIPS)':
 C_PATH='@s9s_mb_2u_lib.s9s_mb_2u(sch_1):page463_i6@pure_quanta.q_res(chips)';

PART_NAME
 R1257 'Q_RES_0402LF-10K,1%,1/16W,CHIPA':;

SECTION_NUMBER 1
 '@S9S_MB_2U_LIB.S9S_MB_2U(SCH_1):PAGE463_I4@PURE_QUANTA.Q_RES(CHIPS)':
 C_PATH='@s9s_mb_2u_lib.s9s_mb_2u(sch_1):page463_i4@pure_quanta.q_res(chips)';

PART_NAME
 R1256 'Q_RES_0402LF-10K,1%,1/16W,CHIPA':;

SECTION_NUMBER 1
 '@S9S_MB_2U_LIB.S9S_MB_2U(SCH_1):PAGE463_I1@PURE_QUANTA.Q_RES(CHIPS)':
 C_PATH='@s9s_mb_2u_lib.s9s_mb_2u(sch_1):page463_i1@pure_quanta.q_res(chips)';

PART_NAME
 R1255 'Q_RES_0402LF-1K,1%,1/16W,CHIP,A':;

SECTION_NUMBER 1
 '@S9S_MB_2U_LIB.S9S_MB_2U(SCH_1):PAGE463_I26@PURE_QUANTA.Q_RES(CHIPS)':
 C_PATH='@s9s_mb_2u_lib.s9s_mb_2u(sch_1):page463_i26@pure_quanta.q_res(chips)';

PART_NAME
 R1254 'Q_RES_0402LF-10K,1%,1/16W,CHIPA':;

SECTION_NUMBER 1
 '@S9S_MB_2U_LIB.S9S_MB_2U(SCH_1):PAGE463_I24@PURE_QUANTA.Q_RES(CHIPS)':
 C_PATH='@s9s_mb_2u_lib.s9s_mb_2u(sch_1):page463_i24@pure_quanta.q_res(chips)';

PART_NAME
 R1253 'Q_RES_0402LF-10K,1%,1/16W,CHIPA':;

SECTION_NUMBER 1
 '@S9S_MB_2U_LIB.S9S_MB_2U(SCH_1):PAGE463_I23@PURE_QUANTA.Q_RES(CHIPS)':
 C_PATH='@s9s_mb_2u_lib.s9s_mb_2u(sch_1):page463_i23@pure_quanta.q_res(chips)';

PART_NAME
 R456 'Q_RES_0402LF-10K,1%,1/16W,CHIPA':;

SECTION_NUMBER 1
 '@S9S_MB_2U_LIB.S9S_MB_2U(SCH_1):PAGE463_I66@PURE_QUANTA.Q_RES(CHIPS)':
 C_PATH='@s9s_mb_2u_lib.s9s_mb_2u(sch_1):page463_i66@pure_quanta.q_res(chips)';

PART_NAME
 R401 'Q_RES_0402LF-10K,1%,1/16W,EMPTA':;

SECTION_NUMBER 1
 '@S9S_MB_2U_LIB.S9S_MB_2U(SCH_1):PAGE463_I69@PURE_QUANTA.Q_RES(CHIPS)':
 C_PATH='@s9s_mb_2u_lib.s9s_mb_2u(sch_1):page463_i69@pure_quanta.q_res(chips)';

PART_NAME
 R71 'Q_RES_0402LF-10K,1%,1/16W,CHIPA':;

SECTION_NUMBER 1
 '@S9S_MB_2U_LIB.S9S_MB_2U(SCH_1):PAGE463_I60@PURE_QUANTA.Q_RES(CHIPS)':
 C_PATH='@s9s_mb_2u_lib.s9s_mb_2u(sch_1):page463_i60@pure_quanta.q_res(chips)';

PART_NAME
 R8 'Q_RES_0402LF-10K,1%,1/16W,CHIPA':;

SECTION_NUMBER 1
 '@S9S_MB_2U_LIB.S9S_MB_2U(SCH_1):PAGE463_I59@PURE_QUANTA.Q_RES(CHIPS)':
 C_PATH='@s9s_mb_2u_lib.s9s_mb_2u(sch_1):page463_i59@pure_quanta.q_res(chips)';

PART_NAME
 R1933 'Q_RES_0402LF-33.2,1%,1/16W,CHIA':;

SECTION_NUMBER 1
 '@S9S_MB_2U_LIB.S9S_MB_2U(SCH_1):PAGE14_I110@PURE_QUANTA.Q_RES(CHIPS)':
 C_PATH='@s9s_mb_2u_lib.s9s_mb_2u(sch_1):page14_i110@pure_quanta.q_res(chips)';

PART_NAME
 R1932 'Q_RES_0402LF-33.2,1%,1/16W,CHIA':;

SECTION_NUMBER 1
 '@S9S_MB_2U_LIB.S9S_MB_2U(SCH_1):PAGE14_I109@PURE_QUANTA.Q_RES(CHIPS)':
 C_PATH='@s9s_mb_2u_lib.s9s_mb_2u(sch_1):page14_i109@pure_quanta.q_res(chips)';

PART_NAME
 R556 'Q_RES_0402LF-49.9     ,1%  ,1/A':;

SECTION_NUMBER 1
 '@S9S_MB_2U_LIB.S9S_MB_2U(SCH_1):PAGE14_I100@PURE_QUANTA.Q_RES(CHIPS)':
 C_PATH='@s9s_mb_2u_lib.s9s_mb_2u(sch_1):page14_i100@pure_quanta.q_res(chips)';

PART_NAME
 R555 'Q_RES_0402LF-100,1%,1/16W,CHIPA':;

SECTION_NUMBER 1
 '@S9S_MB_2U_LIB.S9S_MB_2U(SCH_1):PAGE14_I98@PURE_QUANTA.Q_RES(CHIPS)':
 C_PATH='@s9s_mb_2u_lib.s9s_mb_2u(sch_1):page14_i98@pure_quanta.q_res(chips)';

PART_NAME
 R548 'Q_RES_0402LF-49.9     ,1%  ,1/A':;

SECTION_NUMBER 1
 '@S9S_MB_2U_LIB.S9S_MB_2U(SCH_1):PAGE14_I94@PURE_QUANTA.Q_RES(CHIPS)':
 C_PATH='@s9s_mb_2u_lib.s9s_mb_2u(sch_1):page14_i94@pure_quanta.q_res(chips)';

PART_NAME
 R328 'Q_RES_0402LF-100,1%,1/16W,CHIPA':;

SECTION_NUMBER 1
 '@S9S_MB_2U_LIB.S9S_MB_2U(SCH_1):PAGE14_I93@PURE_QUANTA.Q_RES(CHIPS)':
 C_PATH='@s9s_mb_2u_lib.s9s_mb_2u(sch_1):page14_i93@pure_quanta.q_res(chips)';

PART_NAME
 R322 'Q_RES_0402LF-33.2,1%,1/16W,CHIA':;

SECTION_NUMBER 1
 '@S9S_MB_2U_LIB.S9S_MB_2U(SCH_1):PAGE14_I90@PURE_QUANTA.Q_RES(CHIPS)':
 C_PATH='@s9s_mb_2u_lib.s9s_mb_2u(sch_1):page14_i90@pure_quanta.q_res(chips)';

PART_NAME
 R317 'Q_RES_0402LF-49.9     ,1%  ,1/A':;

SECTION_NUMBER 1
 '@S9S_MB_2U_LIB.S9S_MB_2U(SCH_1):PAGE14_I83@PURE_QUANTA.Q_RES(CHIPS)':
 C_PATH='@s9s_mb_2u_lib.s9s_mb_2u(sch_1):page14_i83@pure_quanta.q_res(chips)';

PART_NAME
 R17 'Q_RES_0402LF-200,1%,1/16W,CHIPA':;

SECTION_NUMBER 1
 '@S9S_MB_2U_LIB.S9S_MB_2U(SCH_1):PAGE14_I64@PURE_QUANTA.Q_RES(CHIPS)':
 C_PATH='@s9s_mb_2u_lib.s9s_mb_2u(sch_1):page14_i64@pure_quanta.q_res(chips)';

PART_NAME
 R16 'Q_RES_0402LF-0,5%,1/16W,CHIP,CA':;

SECTION_NUMBER 1
 '@S9S_MB_2U_LIB.S9S_MB_2U(SCH_1):PAGE14_I63@PURE_QUANTA.Q_RES(CHIPS)':
 C_PATH='@s9s_mb_2u_lib.s9s_mb_2u(sch_1):page14_i63@pure_quanta.q_res(chips)';

PART_NAME
 R15 'Q_RES_0402LF-0,5%,1/16W,CHIP,CA':;

SECTION_NUMBER 1
 '@S9S_MB_2U_LIB.S9S_MB_2U(SCH_1):PAGE14_I62@PURE_QUANTA.Q_RES(CHIPS)':
 C_PATH='@s9s_mb_2u_lib.s9s_mb_2u(sch_1):page14_i62@pure_quanta.q_res(chips)';

PART_NAME
 R14 'Q_RES_0402LF-200,1%,1/16W,CHIPA':;

SECTION_NUMBER 1
 '@S9S_MB_2U_LIB.S9S_MB_2U(SCH_1):PAGE14_I61@PURE_QUANTA.Q_RES(CHIPS)':
 C_PATH='@s9s_mb_2u_lib.s9s_mb_2u(sch_1):page14_i61@pure_quanta.q_res(chips)';

PART_NAME
 R13 'Q_RES_0402LF-0,5%,1/16W,CHIP,CA':;

SECTION_NUMBER 1
 '@S9S_MB_2U_LIB.S9S_MB_2U(SCH_1):PAGE14_I60@PURE_QUANTA.Q_RES(CHIPS)':
 C_PATH='@s9s_mb_2u_lib.s9s_mb_2u(sch_1):page14_i60@pure_quanta.q_res(chips)';

PART_NAME
 R12 'Q_RES_0402LF-0,5%,1/16W,CHIP,CA':;

SECTION_NUMBER 1
 '@S9S_MB_2U_LIB.S9S_MB_2U(SCH_1):PAGE14_I59@PURE_QUANTA.Q_RES(CHIPS)':
 C_PATH='@s9s_mb_2u_lib.s9s_mb_2u(sch_1):page14_i59@pure_quanta.q_res(chips)';

PART_NAME
 R11 'Q_RES_0402LF-33.2,1%,1/16W,CHIA':;

SECTION_NUMBER 1
 '@S9S_MB_2U_LIB.S9S_MB_2U(SCH_1):PAGE14_I79@PURE_QUANTA.Q_RES(CHIPS)':
 C_PATH='@s9s_mb_2u_lib.s9s_mb_2u(sch_1):page14_i79@pure_quanta.q_res(chips)';

PART_NAME
 R10 'Q_RES_0402LF-33.2,1%,1/16W,CHIA':;

SECTION_NUMBER 1
 '@S9S_MB_2U_LIB.S9S_MB_2U(SCH_1):PAGE14_I78@PURE_QUANTA.Q_RES(CHIPS)':
 C_PATH='@s9s_mb_2u_lib.s9s_mb_2u(sch_1):page14_i78@pure_quanta.q_res(chips)';

PART_NAME
 R7 'Q_RES_0402LF-33.2,1%,1/16W,CHIA':;

SECTION_NUMBER 1
 '@S9S_MB_2U_LIB.S9S_MB_2U(SCH_1):PAGE14_I66@PURE_QUANTA.Q_RES(CHIPS)':
 C_PATH='@s9s_mb_2u_lib.s9s_mb_2u(sch_1):page14_i66@pure_quanta.q_res(chips)';

PART_NAME
 R6 'Q_RES_0402LF-100,1%,1/16W,CHIPA':;

SECTION_NUMBER 1
 '@S9S_MB_2U_LIB.S9S_MB_2U(SCH_1):PAGE13_I25@PURE_QUANTA.Q_RES(CHIPS)':
 C_PATH='@s9s_mb_2u_lib.s9s_mb_2u(sch_1):page13_i25@pure_quanta.q_res(chips)';

PART_NAME
 R5 'Q_RES_0402LF-100,1%,1/16W,CHIPA':;

SECTION_NUMBER 1
 '@S9S_MB_2U_LIB.S9S_MB_2U(SCH_1):PAGE13_I24@PURE_QUANTA.Q_RES(CHIPS)':
 C_PATH='@s9s_mb_2u_lib.s9s_mb_2u(sch_1):page13_i24@pure_quanta.q_res(chips)';

PART_NAME
 R4 'Q_RES_0402LF-200,1%,1/16W,CHIPA':;

SECTION_NUMBER 1
 '@S9S_MB_2U_LIB.S9S_MB_2U(SCH_1):PAGE13_I29@PURE_QUANTA.Q_RES(CHIPS)':
 C_PATH='@s9s_mb_2u_lib.s9s_mb_2u(sch_1):page13_i29@pure_quanta.q_res(chips)';

PART_NAME
 R3 'Q_RES_0402LF-33.2,1%,1/16W,CHIA':;

SECTION_NUMBER 1
 '@S9S_MB_2U_LIB.S9S_MB_2U(SCH_1):PAGE13_I21@PURE_QUANTA.Q_RES(CHIPS)':
 C_PATH='@s9s_mb_2u_lib.s9s_mb_2u(sch_1):page13_i21@pure_quanta.q_res(chips)';

PART_NAME
 R2 'Q_RES_0402LF-100,1%,1/16W,CHIPA':;

SECTION_NUMBER 1
 '@S9S_MB_2U_LIB.S9S_MB_2U(SCH_1):PAGE13_I16@PURE_QUANTA.Q_RES(CHIPS)':
 C_PATH='@s9s_mb_2u_lib.s9s_mb_2u(sch_1):page13_i16@pure_quanta.q_res(chips)';

PART_NAME
 R1 'Q_RES_0402LF-10,1%,1/16W,CHIP,A':;

SECTION_NUMBER 1
 '@S9S_MB_2U_LIB.S9S_MB_2U(SCH_1):PAGE13_I18@PURE_QUANTA.Q_RES(CHIPS)':
 C_PATH='@s9s_mb_2u_lib.s9s_mb_2u(sch_1):page13_i18@pure_quanta.q_res(chips)';

PART_NAME
 R1820 'Q_RES_0402LF-10K,1%,1/16W,CHIPA':;

SECTION_NUMBER 1
 '@S9S_MB_2U_LIB.S9S_MB_2U(SCH_1):PAGE464_I35@PURE_QUANTA.Q_RES(CHIPS)':
 C_PATH='@s9s_mb_2u_lib.s9s_mb_2u(sch_1):page464_i35@pure_quanta.q_res(chips)';

PART_NAME
 R1266 'Q_RES_0402LF-49.9     ,1%  ,1/A':;

SECTION_NUMBER 1
 '@S9S_MB_2U_LIB.S9S_MB_2U(SCH_1):PAGE464_I23@PURE_QUANTA.Q_RES(CHIPS)':
 C_PATH='@s9s_mb_2u_lib.s9s_mb_2u(sch_1):page464_i23@pure_quanta.q_res(chips)';

PART_NAME
 R1265 'Q_RES_0402LF-10K,1%,1/16W,CHIPA':;

SECTION_NUMBER 1
 '@S9S_MB_2U_LIB.S9S_MB_2U(SCH_1):PAGE464_I25@PURE_QUANTA.Q_RES(CHIPS)':
 C_PATH='@s9s_mb_2u_lib.s9s_mb_2u(sch_1):page464_i25@pure_quanta.q_res(chips)';

PART_NAME
 R1264 'Q_RES_0402LF-10K,1%,1/16W,CHIPA':;

SECTION_NUMBER 1
 '@S9S_MB_2U_LIB.S9S_MB_2U(SCH_1):PAGE464_I27@PURE_QUANTA.Q_RES(CHIPS)':
 C_PATH='@s9s_mb_2u_lib.s9s_mb_2u(sch_1):page464_i27@pure_quanta.q_res(chips)';

PART_NAME
 R1263 'Q_RES_0402LF-33,5%,1/16W,CHIP,A':;

SECTION_NUMBER 1
 '@S9S_MB_2U_LIB.S9S_MB_2U(SCH_1):PAGE464_I29@PURE_QUANTA.Q_RES(CHIPS)':
 C_PATH='@s9s_mb_2u_lib.s9s_mb_2u(sch_1):page464_i29@pure_quanta.q_res(chips)';

PART_NAME
 R1251 'Q_RES_0402LF-0,5%,1/16W,EMPTY,A':;

SECTION_NUMBER 1
 '@S9S_MB_2U_LIB.S9S_MB_2U(SCH_1):PAGE464_I21@PURE_QUANTA.Q_RES(CHIPS)':
 C_PATH='@s9s_mb_2u_lib.s9s_mb_2u(sch_1):page464_i21@pure_quanta.q_res(chips)';

PART_NAME
 R1250 'Q_RES_0402LF-0,5%,1/16W,EMPTY,A':;

SECTION_NUMBER 1
 '@S9S_MB_2U_LIB.S9S_MB_2U(SCH_1):PAGE464_I24@PURE_QUANTA.Q_RES(CHIPS)':
 C_PATH='@s9s_mb_2u_lib.s9s_mb_2u(sch_1):page464_i24@pure_quanta.q_res(chips)';

PART_NAME
 R1249 'Q_RES_0402LF-0,5%,1/16W,CHIP,CA':;

SECTION_NUMBER 1
 '@S9S_MB_2U_LIB.S9S_MB_2U(SCH_1):PAGE464_I2@PURE_QUANTA.Q_RES(CHIPS)':
 C_PATH='@s9s_mb_2u_lib.s9s_mb_2u(sch_1):page464_i2@pure_quanta.q_res(chips)';

PART_NAME
 R1248 'Q_RES_0402LF-0,5%,1/16W,EMPTY,A':;

SECTION_NUMBER 1
 '@S9S_MB_2U_LIB.S9S_MB_2U(SCH_1):PAGE464_I3@PURE_QUANTA.Q_RES(CHIPS)':
 C_PATH='@s9s_mb_2u_lib.s9s_mb_2u(sch_1):page464_i3@pure_quanta.q_res(chips)';

PART_NAME
 R1247 'Q_RES_0402LF-0,5%,1/16W,CHIP,CA':;

SECTION_NUMBER 1
 '@S9S_MB_2U_LIB.S9S_MB_2U(SCH_1):PAGE464_I14@PURE_QUANTA.Q_RES(CHIPS)':
 C_PATH='@s9s_mb_2u_lib.s9s_mb_2u(sch_1):page464_i14@pure_quanta.q_res(chips)';

PART_NAME
 R1246 'Q_RES_0402LF-0,5%,1/16W,EMPTY,A':;

SECTION_NUMBER 1
 '@S9S_MB_2U_LIB.S9S_MB_2U(SCH_1):PAGE464_I11@PURE_QUANTA.Q_RES(CHIPS)':
 C_PATH='@s9s_mb_2u_lib.s9s_mb_2u(sch_1):page464_i11@pure_quanta.q_res(chips)';

PART_NAME
 Q8 'MOSFET_NCH_DUAL-2N7002KDW,SMLFA':;

SECTION_NUMBER 1
 '@S9S_MB_2U_LIB.S9S_MB_2U(SCH_1):PAGE464_I31@PURE_QUANTA.MOSFET_NCH_DUAL(CHIPS)':
 C_PATH='@s9s_mb_2u_lib.s9s_mb_2u(sch_1):page464_i31@pure_quanta.mosfet_nch_dual(c~
hips)';

SECTION_NUMBER 2
 '@S9S_MB_2U_LIB.S9S_MB_2U(SCH_1):PAGE464_I32@PURE_QUANTA.MOSFET_NCH_DUAL(CHIPS)':
 C_PATH='@s9s_mb_2u_lib.s9s_mb_2u(sch_1):page464_i32@pure_quanta.mosfet_nch_dual(c~
hips)';

PART_NAME
 Q7 'MOSFET_N_123-BSS123-7-F,SMLF,IA':;

SECTION_NUMBER 1
 '@S9S_MB_2U_LIB.S9S_MB_2U(SCH_1):PAGE464_I33@PURE_QUANTA.MOSFET_N_123(CHIPS)':
 C_PATH='@s9s_mb_2u_lib.s9s_mb_2u(sch_1):page464_i33@pure_quanta.mosfet_n_123(chip~
s)';

PART_NAME
 R248 'Q_RES_0402LF-0,5%,1/16W,EMPTY,A':;

SECTION_NUMBER 1
 '@S9S_MB_2U_LIB.S9S_MB_2U(SCH_1):PAGE483_I146@PURE_QUANTA.Q_RES(CHIPS)':
 C_PATH='@s9s_mb_2u_lib.s9s_mb_2u(sch_1):page483_i146@pure_quanta.q_res(chips)';

PART_NAME
 R247 'Q_RES_0402LF-0,5%,1/16W,EMPTY,A':;

SECTION_NUMBER 1
 '@S9S_MB_2U_LIB.S9S_MB_2U(SCH_1):PAGE483_I116@PURE_QUANTA.Q_RES(CHIPS)':
 C_PATH='@s9s_mb_2u_lib.s9s_mb_2u(sch_1):page483_i116@pure_quanta.q_res(chips)';

PART_NAME
 R246 'Q_RES_0402LF-0,5%,1/16W,EMPTY,A':;

SECTION_NUMBER 1
 '@S9S_MB_2U_LIB.S9S_MB_2U(SCH_1):PAGE483_I73@PURE_QUANTA.Q_RES(CHIPS)':
 C_PATH='@s9s_mb_2u_lib.s9s_mb_2u(sch_1):page483_i73@pure_quanta.q_res(chips)';

PART_NAME
 R245 'Q_RES_0402LF-0,5%,1/16W,EMPTY,A':;

SECTION_NUMBER 1
 '@S9S_MB_2U_LIB.S9S_MB_2U(SCH_1):PAGE483_I67@PURE_QUANTA.Q_RES(CHIPS)':
 C_PATH='@s9s_mb_2u_lib.s9s_mb_2u(sch_1):page483_i67@pure_quanta.q_res(chips)';

PART_NAME
 R244 'Q_RES_0402LF-100,1%,1/16W,EMPTA':;

SECTION_NUMBER 1
 '@S9S_MB_2U_LIB.S9S_MB_2U(SCH_1):PAGE483_I173@PURE_QUANTA.Q_RES(CHIPS)':
 C_PATH='@s9s_mb_2u_lib.s9s_mb_2u(sch_1):page483_i173@pure_quanta.q_res(chips)';

PART_NAME
 R243 'Q_RES_0402LF-100,1%,1/16W,EMPTA':;

SECTION_NUMBER 1
 '@S9S_MB_2U_LIB.S9S_MB_2U(SCH_1):PAGE483_I171@PURE_QUANTA.Q_RES(CHIPS)':
 C_PATH='@s9s_mb_2u_lib.s9s_mb_2u(sch_1):page483_i171@pure_quanta.q_res(chips)';

PART_NAME
 R242 'Q_RES_0402LF-1K,1%,1/16W,EMPTYA':;

SECTION_NUMBER 1
 '@S9S_MB_2U_LIB.S9S_MB_2U(SCH_1):PAGE483_I169@PURE_QUANTA.Q_RES(CHIPS)':
 C_PATH='@s9s_mb_2u_lib.s9s_mb_2u(sch_1):page483_i169@pure_quanta.q_res(chips)';

PART_NAME
 R241 'Q_RES_0402LF-1K,1%,1/16W,EMPTYA':;

SECTION_NUMBER 1
 '@S9S_MB_2U_LIB.S9S_MB_2U(SCH_1):PAGE483_I167@PURE_QUANTA.Q_RES(CHIPS)':
 C_PATH='@s9s_mb_2u_lib.s9s_mb_2u(sch_1):page483_i167@pure_quanta.q_res(chips)';

PART_NAME
 R240 'Q_RES_0402LF-0,5%,1/16W,CHIP,CA':;

SECTION_NUMBER 1
 '@S9S_MB_2U_LIB.S9S_MB_2U(SCH_1):PAGE483_I151@PURE_QUANTA.Q_RES(CHIPS)':
 C_PATH='@s9s_mb_2u_lib.s9s_mb_2u(sch_1):page483_i151@pure_quanta.q_res(chips)';

PART_NAME
 R239 'Q_RES_0402LF-0,5%,1/16W,CHIP,CA':;

SECTION_NUMBER 1
 '@S9S_MB_2U_LIB.S9S_MB_2U(SCH_1):PAGE483_I129@PURE_QUANTA.Q_RES(CHIPS)':
 C_PATH='@s9s_mb_2u_lib.s9s_mb_2u(sch_1):page483_i129@pure_quanta.q_res(chips)';

PART_NAME
 R238 'Q_RES_0402LF-0,5%,1/16W,CHIP,CA':;

SECTION_NUMBER 1
 '@S9S_MB_2U_LIB.S9S_MB_2U(SCH_1):PAGE483_I80@PURE_QUANTA.Q_RES(CHIPS)':
 C_PATH='@s9s_mb_2u_lib.s9s_mb_2u(sch_1):page483_i80@pure_quanta.q_res(chips)';

PART_NAME
 R237 'Q_RES_0402LF-0,5%,1/16W,CHIP,CA':;

SECTION_NUMBER 1
 '@S9S_MB_2U_LIB.S9S_MB_2U(SCH_1):PAGE483_I69@PURE_QUANTA.Q_RES(CHIPS)':
 C_PATH='@s9s_mb_2u_lib.s9s_mb_2u(sch_1):page483_i69@pure_quanta.q_res(chips)';

PART_NAME
 R236 'Q_RES_0402LF-1K,1%,1/16W,CHIP,A':;

SECTION_NUMBER 1
 '@S9S_MB_2U_LIB.S9S_MB_2U(SCH_1):PAGE483_I150@PURE_QUANTA.Q_RES(CHIPS)':
 C_PATH='@s9s_mb_2u_lib.s9s_mb_2u(sch_1):page483_i150@pure_quanta.q_res(chips)';

PART_NAME
 R235 'Q_RES_0402LF-1K,1%,1/16W,CHIP,A':;

SECTION_NUMBER 1
 '@S9S_MB_2U_LIB.S9S_MB_2U(SCH_1):PAGE483_I128@PURE_QUANTA.Q_RES(CHIPS)':
 C_PATH='@s9s_mb_2u_lib.s9s_mb_2u(sch_1):page483_i128@pure_quanta.q_res(chips)';

PART_NAME
 R234 'Q_RES_0402LF-1K,1%,1/16W,CHIP,A':;

SECTION_NUMBER 1
 '@S9S_MB_2U_LIB.S9S_MB_2U(SCH_1):PAGE483_I79@PURE_QUANTA.Q_RES(CHIPS)':
 C_PATH='@s9s_mb_2u_lib.s9s_mb_2u(sch_1):page483_i79@pure_quanta.q_res(chips)';

PART_NAME
 R233 'Q_RES_0402LF-1K,1%,1/16W,CHIP,A':;

SECTION_NUMBER 1
 '@S9S_MB_2U_LIB.S9S_MB_2U(SCH_1):PAGE483_I62@PURE_QUANTA.Q_RES(CHIPS)':
 C_PATH='@s9s_mb_2u_lib.s9s_mb_2u(sch_1):page483_i62@pure_quanta.q_res(chips)';

PART_NAME
 R232 'Q_RES_0402LF-0,5%,1/16W,EMPTY,A':;

SECTION_NUMBER 1
 '@S9S_MB_2U_LIB.S9S_MB_2U(SCH_1):PAGE483_I153@PURE_QUANTA.Q_RES(CHIPS)':
 C_PATH='@s9s_mb_2u_lib.s9s_mb_2u(sch_1):page483_i153@pure_quanta.q_res(chips)';

PART_NAME
 R231 'Q_RES_0402LF-0,5%,1/16W,EMPTY,A':;

SECTION_NUMBER 1
 '@S9S_MB_2U_LIB.S9S_MB_2U(SCH_1):PAGE483_I132@PURE_QUANTA.Q_RES(CHIPS)':
 C_PATH='@s9s_mb_2u_lib.s9s_mb_2u(sch_1):page483_i132@pure_quanta.q_res(chips)';

PART_NAME
 R230 'Q_RES_0402LF-0,5%,1/16W,EMPTY,A':;

SECTION_NUMBER 1
 '@S9S_MB_2U_LIB.S9S_MB_2U(SCH_1):PAGE483_I81@PURE_QUANTA.Q_RES(CHIPS)':
 C_PATH='@s9s_mb_2u_lib.s9s_mb_2u(sch_1):page483_i81@pure_quanta.q_res(chips)';

PART_NAME
 R229 'Q_RES_0402LF-0,5%,1/16W,EMPTY,A':;

SECTION_NUMBER 1
 '@S9S_MB_2U_LIB.S9S_MB_2U(SCH_1):PAGE483_I58@PURE_QUANTA.Q_RES(CHIPS)':
 C_PATH='@s9s_mb_2u_lib.s9s_mb_2u(sch_1):page483_i58@pure_quanta.q_res(chips)';

PART_NAME
 Q6 'MOSFET_NCH_DUAL-2N7002KDW,SMLFA':;

SECTION_NUMBER 1
 '@S9S_MB_2U_LIB.S9S_MB_2U(SCH_1):PAGE483_I142@PURE_QUANTA.MOSFET_NCH_DUAL(CHIPS)':
 C_PATH='@s9s_mb_2u_lib.s9s_mb_2u(sch_1):page483_i142@pure_quanta.mosfet_nch_dual(~
chips)';

SECTION_NUMBER 2
 '@S9S_MB_2U_LIB.S9S_MB_2U(SCH_1):PAGE483_I164@PURE_QUANTA.MOSFET_NCH_DUAL(CHIPS)':
 C_PATH='@s9s_mb_2u_lib.s9s_mb_2u(sch_1):page483_i164@pure_quanta.mosfet_nch_dual(~
chips)';

PART_NAME
 Q5 'MOSFET_NCH_DUAL-2N7002KDW,SMLFA':;

SECTION_NUMBER 1
 '@S9S_MB_2U_LIB.S9S_MB_2U(SCH_1):PAGE483_I130@PURE_QUANTA.MOSFET_NCH_DUAL(CHIPS)':
 C_PATH='@s9s_mb_2u_lib.s9s_mb_2u(sch_1):page483_i130@pure_quanta.mosfet_nch_dual(~
chips)';

SECTION_NUMBER 2
 '@S9S_MB_2U_LIB.S9S_MB_2U(SCH_1):PAGE483_I165@PURE_QUANTA.MOSFET_NCH_DUAL(CHIPS)':
 C_PATH='@s9s_mb_2u_lib.s9s_mb_2u(sch_1):page483_i165@pure_quanta.mosfet_nch_dual(~
chips)';

PART_NAME
 Q4 'MOSFET_NCH_DUAL-2N7002KDW,SMLFA':;

SECTION_NUMBER 1
 '@S9S_MB_2U_LIB.S9S_MB_2U(SCH_1):PAGE483_I70@PURE_QUANTA.MOSFET_NCH_DUAL(CHIPS)':
 C_PATH='@s9s_mb_2u_lib.s9s_mb_2u(sch_1):page483_i70@pure_quanta.mosfet_nch_dual(c~
hips)';

SECTION_NUMBER 2
 '@S9S_MB_2U_LIB.S9S_MB_2U(SCH_1):PAGE483_I166@PURE_QUANTA.MOSFET_NCH_DUAL(CHIPS)':
 C_PATH='@s9s_mb_2u_lib.s9s_mb_2u(sch_1):page483_i166@pure_quanta.mosfet_nch_dual(~
chips)';

PART_NAME
 Q3 'MOSFET_NCH_DUAL-2N7002KDW,SMLFA':;

SECTION_NUMBER 1
 '@S9S_MB_2U_LIB.S9S_MB_2U(SCH_1):PAGE483_I57@PURE_QUANTA.MOSFET_NCH_DUAL(CHIPS)':
 C_PATH='@s9s_mb_2u_lib.s9s_mb_2u(sch_1):page483_i57@pure_quanta.mosfet_nch_dual(c~
hips)';

SECTION_NUMBER 2
 '@S9S_MB_2U_LIB.S9S_MB_2U(SCH_1):PAGE483_I163@PURE_QUANTA.MOSFET_NCH_DUAL(CHIPS)':
 C_PATH='@s9s_mb_2u_lib.s9s_mb_2u(sch_1):page483_i163@pure_quanta.mosfet_nch_dual(~
chips)';

PART_NAME
 PU108_P0_5 'ISL99390FRZTR5935-ISL99390FRZ-B':;

SECTION_NUMBER 1
 '@S9S_MB_2U_LIB.S9S_MB_2U(SCH_1):PAGE641_I1@PURE_QUANTA.ISL99390FRZTR5935(CHIPS)':
 C_PATH='@s9s_mb_2u_lib.s9s_mb_2u(sch_1):page641_i1@pure_quanta.isl99390frztr5935(~
chips)',
 VAR_0_ONSEMI='VAR_REPLACED|ISL99390FRZTR5935|VAR_PARTNAME|FDMF5085|VALUE|FDMF50~
85|PART_TYPE|SMLF|MATERIAL|EMPTY|PART_NUMBER|AL005085000|STANDARD||LIFECYCLE||PA~
RT_NUMBER|AL005085000|JEDEC_TYPE|PQFN21_6X5XB|DESCRIPTION|IC OTHER(39P) FDMF5085~
(PQFN)|MANUFTR|ONS|MANUF_PN|FDMF5085|RD_CMPLS_LVL|EP(V1)|CMPLS_LVL||FROM_PJ|S9S-~
KIMI|CLASS|IC|DIP_SMD||DATA|ONS_FDMF5085.pdf|EE_CHECK_LIST||FP_ECN||PSL||CREATOR~
||STATUS||MSD|NA|ESD_CDM|NA|ESD_HBM|NA|ESD_MM|NA|PIN_LENGTH_SHORT_PIN|0 MILS|PIN~
_LENGTH_LONG_PIN|0 MILS|CREATEDAY|20200423|VARIANT_DEVICE_TYPE|FDMF5085-FDMF5085~
,SMLF,EMPTY,A',
 CDSVAR_REPCELL_ONSEMI='pure_quanta|fdmf5085';

PART_NAME
 PR1890 'Q_RES_0402LF-0,5%,1/16W,EMPTY,A':;

SECTION_NUMBER 1
 '@S9S_MB_2U_LIB.S9S_MB_2U(SCH_1):PAGE641_I20@PURE_QUANTA.Q_RES(CHIPS)':
 C_PATH='@s9s_mb_2u_lib.s9s_mb_2u(sch_1):page641_i20@pure_quanta.q_res(chips)',
 VAR_0_ONSEMI='',
 CDSVAR_REPCELL_ONSEMI='pure_quanta|Q_res';

PART_NAME
 PR1889 'Q_RES_0402LF-3.3,1%,1/16W,EMPTA':;

SECTION_NUMBER 1
 '@S9S_MB_2U_LIB.S9S_MB_2U(SCH_1):PAGE641_I23@PURE_QUANTA.Q_RES(CHIPS)':
 C_PATH='@s9s_mb_2u_lib.s9s_mb_2u(sch_1):page641_i23@pure_quanta.q_res(chips)',
 VAR_0_ONSEMI='VALUE|5.1|TOLERANCE|5%|WATTAGE|1/16W|PACK_TYPE|0402LF|MATERIAL|EM~
PTY|PART_NUMBER|CS-5102JB03|STANDARD|End of Design|LIFECYCLE|Comp-Approve|PART_N~
UMBER|CS-5102JB03|JEDEC_TYPE|R0402|ALT_SYMBOLS|(R0402-0201)|VALUE|5.1|TOL|5%|WAT~
TAGE|1/16W |CLASS|IO|DESCRIPTION|RES CHIP 5.1 1/16W +-5%(0402)|COMPONENT_TYPE|CH~
IP0402|LEAD_LENGTH||DFM_EXCLUSION||DAY|20100827|VARIANT_DEVICE_TYPE|Q_RES-5.1,5%~
,1/16W,0402LF,EMPT',
 CDSVAR_REPCELL_ONSEMI='pure_quanta|Q_res';

PART_NAME
 PR1888 'Q_RES_0402LF-2.2,1%,1/16W,EMPTA':;

SECTION_NUMBER 1
 '@S9S_MB_2U_LIB.S9S_MB_2U(SCH_1):PAGE641_I28@PURE_QUANTA.Q_RES(CHIPS)':
 C_PATH='@s9s_mb_2u_lib.s9s_mb_2u(sch_1):page641_i28@pure_quanta.q_res(chips)';

PART_NAME
 PR1887 'Q_RES_0402LF-8.87K,1%,1/16W,EMA':;

SECTION_NUMBER 1
 '@S9S_MB_2U_LIB.S9S_MB_2U(SCH_1):PAGE641_I36@PURE_QUANTA.Q_RES(CHIPS)':
 C_PATH='@s9s_mb_2u_lib.s9s_mb_2u(sch_1):page641_i36@pure_quanta.q_res(chips)';

PART_NAME
 PL57 'Q_INDUCTOR_SMLF-130NH/106A,EMPA':;

SECTION_NUMBER 1
 '@S9S_MB_2U_LIB.S9S_MB_2U(SCH_1):PAGE641_I19@PURE_QUANTA.Q_INDUCTOR(CHIPS)':
 C_PATH='@s9s_mb_a_lib.s9s_mb_a(sch_1):page641_i19@pure_quanta.q_inductor(chips)~
';

PART_NAME
 PC2378 'Q_CAPP_SMLF-470UF,2.5V,20%,EMPA':;

SECTION_NUMBER 1
 '@S9S_MB_2U_LIB.S9S_MB_2U(SCH_1):PAGE641_I8@PURE_QUANTA.Q_CAPP(CHIPS)':
 C_PATH='@s9s_mb_2u_lib.s9s_mb_2u(sch_1):page641_i8@pure_quanta.q_capp(chips)';

PART_NAME
 PC2377 'Q_CAPP_RDLF-560UF,2.5V,20%,EMPA':;

SECTION_NUMBER 1
 '@S9S_MB_2U_LIB.S9S_MB_2U(SCH_1):PAGE641_I10@PURE_QUANTA.Q_CAPP(CHIPS)':
 C_PATH='@s9s_mb_2u_lib.s9s_mb_2u(sch_1):page641_i10@pure_quanta.q_capp(chips)';

PART_NAME
 PC2376_P0_5 'Q_CAP_0805-22UF,4V,20%,EMPTY,TA':;

SECTION_NUMBER 1
 '@S9S_MB_2U_LIB.S9S_MB_2U(SCH_1):PAGE641_I15@PURE_QUANTA.Q_CAP(CHIPS)':
 C_PATH='@s9s_mb_2u_lib.s9s_mb_2u(sch_1):page641_i15@pure_quanta.q_cap(chips)';

PART_NAME
 PC2375_P0_5 'Q_CAP_0805-22UF,4V,20%,EMPTY,TA':;

SECTION_NUMBER 1
 '@S9S_MB_2U_LIB.S9S_MB_2U(SCH_1):PAGE641_I16@PURE_QUANTA.Q_CAP(CHIPS)':
 C_PATH='@s9s_mb_2u_lib.s9s_mb_2u(sch_1):page641_i16@pure_quanta.q_cap(chips)';

PART_NAME
 PC2374 'Q_CAP_C0402-100NF,50V,10%,EMPTA':;

SECTION_NUMBER 1
 '@S9S_MB_2U_LIB.S9S_MB_2U(SCH_1):PAGE641_I21@PURE_QUANTA.Q_CAP(CHIPS)':
 C_PATH='@s9s_mb_2u_lib.s9s_mb_2u(sch_1):page641_i21@pure_quanta.q_cap(chips)';

PART_NAME
 PC2373_P0_5 'Q_CAP_C0805-22UF,16V,20%,EMPTYA':;

SECTION_NUMBER 1
 '@S9S_MB_2U_LIB.S9S_MB_2U(SCH_1):PAGE641_I22@PURE_QUANTA.Q_CAP(CHIPS)':
 C_PATH='@s9s_mb_2u_lib.s9s_mb_2u(sch_1):page641_i22@pure_quanta.q_cap(chips)';

PART_NAME
 PC2372_P0_5 'Q_CAP_C0805-22UF,16V,20%,EMPTYA':;

SECTION_NUMBER 1
 '@S9S_MB_2U_LIB.S9S_MB_2U(SCH_1):PAGE641_I5@PURE_QUANTA.Q_CAP(CHIPS)':
 C_PATH='@s9s_mb_2u_lib.s9s_mb_2u(sch_1):page641_i5@pure_quanta.q_cap(chips)';

PART_NAME
 PC2371_P0_5 'Q_CAP_C0402-1UF,16V,10%,EMPTY,A':;

SECTION_NUMBER 1
 '@S9S_MB_2U_LIB.S9S_MB_2U(SCH_1):PAGE641_I4@PURE_QUANTA.Q_CAP(CHIPS)':
 C_PATH='@s9s_mb_2u_lib.s9s_mb_2u(sch_1):page641_i4@pure_quanta.q_cap(chips)';

PART_NAME
 PC2370_P0_5 'Q_CAP_0402-3300PF,50V,10%,EMPTA':;

SECTION_NUMBER 1
 '@S9S_MB_2U_LIB.S9S_MB_2U(SCH_1):PAGE641_I3@PURE_QUANTA.Q_CAP(CHIPS)':
 C_PATH='@s9s_mb_2u_lib.s9s_mb_2u(sch_1):page641_i3@pure_quanta.q_cap(chips)';

PART_NAME
 PC2369_P0_5 'Q_CAP_C0402-2.2UF,10V,10%,EMPTA':;

SECTION_NUMBER 1
 '@S9S_MB_2U_LIB.S9S_MB_2U(SCH_1):PAGE641_I25@PURE_QUANTA.Q_CAP(CHIPS)':
 C_PATH='@s9s_mb_2u_lib.s9s_mb_2u(sch_1):page641_i25@pure_quanta.q_cap(chips)';

PART_NAME
 PC2368 'Q_CAP_0402-0.1UF,25V,10%,EMPTYA':;

SECTION_NUMBER 1
 '@S9S_MB_2U_LIB.S9S_MB_2U(SCH_1):PAGE641_I30@PURE_QUANTA.Q_CAP(CHIPS)':
 C_PATH='@s9s_mb_2u_lib.s9s_mb_2u(sch_1):page641_i30@pure_quanta.q_cap(chips)',
 VAR_0_ONSEMI='';

PART_NAME
 PC2367 'Q_CAP_C0402-2.2UF,10V,10%,EMPTA':;

SECTION_NUMBER 1
 '@S9S_MB_2U_LIB.S9S_MB_2U(SCH_1):PAGE641_I29@PURE_QUANTA.Q_CAP(CHIPS)':
 C_PATH='@s9s_mb_2u_lib.s9s_mb_2u(sch_1):page641_i29@pure_quanta.q_cap(chips)';

PART_NAME
 PU98 'NB695GDZ-NB695GD-Z,SMLF,IC,AL0A':;

SECTION_NUMBER 1
 '@S9S_MB_2U_LIB.S9S_MB_2U(SCH_1):PAGE580_I22@PURE_QUANTA.NB695GDZ(CHIPS)':
 C_PATH='@s9s_mb_2u_lib.s9s_mb_2u(sch_1):page580_i22@pure_quanta.nb695gdz(chips)';

PART_NAME
 PR926 'Q_RES_0402LF-0,5%,1/16W,CHIP,CA':;

SECTION_NUMBER 1
 '@S9S_MB_2U_LIB.S9S_MB_2U(SCH_1):PAGE580_I30@PURE_QUANTA.Q_RES(CHIPS)':
 C_PATH='@s9s_mb_2u_lib.s9s_mb_2u(sch_1):page580_i30@pure_quanta.q_res(chips)';

PART_NAME
 PR925 'Q_RES_0402LF-150K,1%,1/16W,CHIA':;

SECTION_NUMBER 1
 '@S9S_MB_2U_LIB.S9S_MB_2U(SCH_1):PAGE580_I23@PURE_QUANTA.Q_RES(CHIPS)':
 C_PATH='@s9s_mb_2u_lib.s9s_mb_2u(sch_1):page580_i23@pure_quanta.q_res(chips)';

PART_NAME
 PR924 'Q_RES_0402LF-5.1,5%,1/16W,CHIPA':;

SECTION_NUMBER 1
 '@S9S_MB_2U_LIB.S9S_MB_2U(SCH_1):PAGE580_I27@PURE_QUANTA.Q_RES(CHIPS)':
 C_PATH='@s9s_mb_2u_lib.s9s_mb_2u(sch_1):page580_i27@pure_quanta.q_res(chips)';

PART_NAME
 PR923 'Q_RES_0402LF-10K,1%,1/16W,CHIPA':;

SECTION_NUMBER 1
 '@S9S_MB_2U_LIB.S9S_MB_2U(SCH_1):PAGE580_I12@PURE_QUANTA.Q_RES(CHIPS)':
 C_PATH='@s9s_mb_2u_lib.s9s_mb_2u(sch_1):page580_i12@pure_quanta.q_res(chips)';

PART_NAME
 PL116 'Q_INDUCTOR_SMLF-1UH,IND,CV-10BA':;

SECTION_NUMBER 1
 '@S9S_MB_2U_LIB.S9S_MB_2U(SCH_1):PAGE580_I10@PURE_QUANTA.Q_INDUCTOR(CHIPS)':
 C_PATH='@s9s_mb_a_lib.s9s_mb_a(sch_1):page580_i10@pure_quanta.q_inductor(chips)~
';

PART_NAME
 PL115 'Q_INDUCTOR_SMLF-BLM18SN220TN1DA':;

SECTION_NUMBER 1
 '@S9S_MB_2U_LIB.S9S_MB_2U(SCH_1):PAGE580_I18@PURE_QUANTA.Q_INDUCTOR(CHIPS)':
 C_PATH='@s9s_mb_a_lib.s9s_mb_a(sch_1):page580_i18@pure_quanta.q_inductor(chips)~
';

PART_NAME
 PC1333 'Q_CAP_0402-0.1UF,25V,10%,X7R,CA':;

SECTION_NUMBER 1
 '@S9S_MB_2U_LIB.S9S_MB_2U(SCH_1):PAGE580_I33@PURE_QUANTA.Q_CAP(CHIPS)':
 C_PATH='@s9s_mb_2u_lib.s9s_mb_2u(sch_1):page580_i33@pure_quanta.q_cap(chips)';

PART_NAME
 PC1332 'Q_CAP_0402-0.01UF,25V,10%,X7R,A':;

SECTION_NUMBER 1
 '@S9S_MB_2U_LIB.S9S_MB_2U(SCH_1):PAGE580_I31@PURE_QUANTA.Q_CAP(CHIPS)':
 C_PATH='@s9s_mb_2u_lib.s9s_mb_2u(sch_1):page580_i31@pure_quanta.q_cap(chips)';

PART_NAME
 PC1331 'Q_CAP_0402-0.1UF,25V,10%,X7R,CA':;

SECTION_NUMBER 1
 '@S9S_MB_2U_LIB.S9S_MB_2U(SCH_1):PAGE580_I15@PURE_QUANTA.Q_CAP(CHIPS)':
 C_PATH='@s9s_mb_2u_lib.s9s_mb_2u(sch_1):page580_i15@pure_quanta.q_cap(chips)';

PART_NAME
 PC1330 'Q_CAP_C0805-10UF,16V,10%,X6S,CA':;

SECTION_NUMBER 1
 '@S9S_MB_2U_LIB.S9S_MB_2U(SCH_1):PAGE580_I16@PURE_QUANTA.Q_CAP(CHIPS)':
 C_PATH='@s9s_mb_2u_lib.s9s_mb_2u(sch_1):page580_i16@pure_quanta.q_cap(chips)';

PART_NAME
 PC1329 'Q_CAP_C0805-10UF,16V,10%,X6S,CA':;

SECTION_NUMBER 1
 '@S9S_MB_2U_LIB.S9S_MB_2U(SCH_1):PAGE580_I17@PURE_QUANTA.Q_CAP(CHIPS)':
 C_PATH='@s9s_mb_2u_lib.s9s_mb_2u(sch_1):page580_i17@pure_quanta.q_cap(chips)';

PART_NAME
 PC1328 'Q_CAP_0805-22UF,4V,20%,X6S,TMPA':;

SECTION_NUMBER 1
 '@S9S_MB_2U_LIB.S9S_MB_2U(SCH_1):PAGE580_I2@PURE_QUANTA.Q_CAP(CHIPS)':
 C_PATH='@s9s_mb_2u_lib.s9s_mb_2u(sch_1):page580_i2@pure_quanta.q_cap(chips)';

PART_NAME
 PC1327 'Q_CAP_0805-22UF,4V,20%,X6S,TMPA':;

SECTION_NUMBER 1
 '@S9S_MB_2U_LIB.S9S_MB_2U(SCH_1):PAGE580_I4@PURE_QUANTA.Q_CAP(CHIPS)':
 C_PATH='@s9s_mb_2u_lib.s9s_mb_2u(sch_1):page580_i4@pure_quanta.q_cap(chips)';

PART_NAME
 PC1326 'Q_CAP_0805-22UF,4V,20%,X6S,TMPA':;

SECTION_NUMBER 1
 '@S9S_MB_2U_LIB.S9S_MB_2U(SCH_1):PAGE580_I5@PURE_QUANTA.Q_CAP(CHIPS)':
 C_PATH='@s9s_mb_2u_lib.s9s_mb_2u(sch_1):page580_i5@pure_quanta.q_cap(chips)';

PART_NAME
 PC1325 'Q_CAP_0805-22UF,4V,20%,X6S,TMPA':;

SECTION_NUMBER 1
 '@S9S_MB_2U_LIB.S9S_MB_2U(SCH_1):PAGE580_I7@PURE_QUANTA.Q_CAP(CHIPS)':
 C_PATH='@s9s_mb_2u_lib.s9s_mb_2u(sch_1):page580_i7@pure_quanta.q_cap(chips)';

PART_NAME
 PC1324 'Q_CAP_0402-0.22UF,16V,10%,X7R,A':;

SECTION_NUMBER 1
 '@S9S_MB_2U_LIB.S9S_MB_2U(SCH_1):PAGE580_I13@PURE_QUANTA.Q_CAP(CHIPS)':
 C_PATH='@s9s_mb_2u_lib.s9s_mb_2u(sch_1):page580_i13@pure_quanta.q_cap(chips)';

PART_NAME
 PC1323 'Q_CAP_C0402-1UF,25V,10%,X6S,CHA':;

SECTION_NUMBER 1
 '@S9S_MB_2U_LIB.S9S_MB_2U(SCH_1):PAGE580_I29@PURE_QUANTA.Q_CAP(CHIPS)':
 C_PATH='@s9s_mb_2u_lib.s9s_mb_2u(sch_1):page580_i29@pure_quanta.q_cap(chips)';

PART_NAME
 R1850 'Q_RES_0402LF-1K,5%,1/16W,EMPTYA':;

SECTION_NUMBER 1
 '@S9S_MB_2U_LIB.S9S_MB_2U(SCH_1):PAGE579_I37@PURE_QUANTA.Q_RES(CHIPS)':
 C_PATH='@s9s_mb_2u_lib.s9s_mb_2u(sch_1):page579_i37@pure_quanta.q_res(chips)';

PART_NAME
 PU74 'NB695GDZ-NB695GD-Z,SMLF,IC,AL0A':;

SECTION_NUMBER 1
 '@S9S_MB_2U_LIB.S9S_MB_2U(SCH_1):PAGE579_I13@PURE_QUANTA.NB695GDZ(CHIPS)':
 C_PATH='@s9s_mb_2u_lib.s9s_mb_2u(sch_1):page579_i13@pure_quanta.nb695gdz(chips)';

PART_NAME
 PR1943 'Q_RES_0402LF-0,5%,1/16W,EMPTY,A':;

SECTION_NUMBER 1
 '@S9S_MB_2U_LIB.S9S_MB_2U(SCH_1):PAGE579_I45@PURE_QUANTA.Q_RES(CHIPS)':
 C_PATH='@s9s_mb_2u_lib.s9s_mb_2u(sch_1):page579_i45@pure_quanta.q_res(chips)';

PART_NAME
 PR1942 'Q_RES_0402LF-0,5%,1/16W,CHIP,CA':;

SECTION_NUMBER 1
 '@S9S_MB_2U_LIB.S9S_MB_2U(SCH_1):PAGE579_I46@PURE_QUANTA.Q_RES(CHIPS)':
 C_PATH='@s9s_mb_2u_lib.s9s_mb_2u(sch_1):page579_i46@pure_quanta.q_res(chips)';

PART_NAME
 PR1651 'Q_RES_0402LF-0,5%,1/16W,CHIP,CA':;

SECTION_NUMBER 1
 '@S9S_MB_2U_LIB.S9S_MB_2U(SCH_1):PAGE579_I18@PURE_QUANTA.Q_RES(CHIPS)':
 C_PATH='@s9s_mb_2u_lib.s9s_mb_2u(sch_1):page579_i18@pure_quanta.q_res(chips)';

PART_NAME
 PR1330 'Q_RES_0402LF-150K,1%,1/16W,CHIA':;

SECTION_NUMBER 1
 '@S9S_MB_2U_LIB.S9S_MB_2U(SCH_1):PAGE579_I10@PURE_QUANTA.Q_RES(CHIPS)':
 C_PATH='@s9s_mb_2u_lib.s9s_mb_2u(sch_1):page579_i10@pure_quanta.q_res(chips)';

PART_NAME
 PR1329 'Q_RES_0402LF-5.1,5%,1/16W,CHIPA':;

SECTION_NUMBER 1
 '@S9S_MB_2U_LIB.S9S_MB_2U(SCH_1):PAGE579_I4@PURE_QUANTA.Q_RES(CHIPS)':
 C_PATH='@s9s_mb_2u_lib.s9s_mb_2u(sch_1):page579_i4@pure_quanta.q_res(chips)';

PART_NAME
 PR1302 'Q_RES_0402LF-10K,1%,1/16W,CHIPA':;

SECTION_NUMBER 1
 '@S9S_MB_2U_LIB.S9S_MB_2U(SCH_1):PAGE579_I16@PURE_QUANTA.Q_RES(CHIPS)':
 C_PATH='@s9s_mb_2u_lib.s9s_mb_2u(sch_1):page579_i16@pure_quanta.q_res(chips)';

PART_NAME
 PR412 'Q_RES_0402LF-0,5%,1/16W,EMPTY,A':;

SECTION_NUMBER 1
 '@S9S_MB_2U_LIB.S9S_MB_2U(SCH_1):PAGE579_I34@PURE_QUANTA.Q_RES(CHIPS)':
 C_PATH='@s9s_mb_2u_lib.s9s_mb_2u(sch_1):page579_i34@pure_quanta.q_res(chips)';

PART_NAME
 PR411 'Q_RES_0402LF-0,5%,1/16W,CHIP,CA':;

SECTION_NUMBER 1
 '@S9S_MB_2U_LIB.S9S_MB_2U(SCH_1):PAGE579_I35@PURE_QUANTA.Q_RES(CHIPS)':
 C_PATH='@s9s_mb_2u_lib.s9s_mb_2u(sch_1):page579_i35@pure_quanta.q_res(chips)';

PART_NAME
 PL170 'Q_INDUCTOR_SMLF-1UH,IND,CV-10BA':;

SECTION_NUMBER 1
 '@S9S_MB_2U_LIB.S9S_MB_2U(SCH_1):PAGE579_I19@PURE_QUANTA.Q_INDUCTOR(CHIPS)':
 C_PATH='@s9s_mb_a_lib.s9s_mb_a(sch_1):page579_i19@pure_quanta.q_inductor(chips)~
';

PART_NAME
 PL16 'Q_INDUCTOR_SMLF-BLM18SN220TN1DA':;

SECTION_NUMBER 1
 '@S9S_MB_2U_LIB.S9S_MB_2U(SCH_1):PAGE579_I30@PURE_QUANTA.Q_INDUCTOR(CHIPS)':
 C_PATH='@s9s_mb_a_lib.s9s_mb_a(sch_1):page579_i30@pure_quanta.q_inductor(chips)~
';

PART_NAME
 PC2287 'Q_CAP_0402-0.01UF,25V,10%,X7R,A':;

SECTION_NUMBER 1
 '@S9S_MB_2U_LIB.S9S_MB_2U(SCH_1):PAGE579_I23@PURE_QUANTA.Q_CAP(CHIPS)':
 C_PATH='@s9s_mb_2u_lib.s9s_mb_2u(sch_1):page579_i23@pure_quanta.q_cap(chips)';

PART_NAME
 PC1642 'Q_CAP_C0402-1UF,25V,10%,X6S,CHA':;

SECTION_NUMBER 1
 '@S9S_MB_2U_LIB.S9S_MB_2U(SCH_1):PAGE579_I2@PURE_QUANTA.Q_CAP(CHIPS)':
 C_PATH='@s9s_mb_2u_lib.s9s_mb_2u(sch_1):page579_i2@pure_quanta.q_cap(chips)';

PART_NAME
 PC1241 'Q_CAP_0805-22UF,4V,20%,X6S,TMPA':;

SECTION_NUMBER 1
 '@S9S_MB_2U_LIB.S9S_MB_2U(SCH_1):PAGE579_I28@PURE_QUANTA.Q_CAP(CHIPS)':
 C_PATH='@s9s_mb_2u_lib.s9s_mb_2u(sch_1):page579_i28@pure_quanta.q_cap(chips)';

PART_NAME
 PC1240 'Q_CAP_0805-22UF,4V,20%,X6S,TMPA':;

SECTION_NUMBER 1
 '@S9S_MB_2U_LIB.S9S_MB_2U(SCH_1):PAGE579_I26@PURE_QUANTA.Q_CAP(CHIPS)':
 C_PATH='@s9s_mb_2u_lib.s9s_mb_2u(sch_1):page579_i26@pure_quanta.q_cap(chips)';

PART_NAME
 PC1239 'Q_CAP_0805-22UF,4V,20%,X6S,TMPA':;

SECTION_NUMBER 1
 '@S9S_MB_2U_LIB.S9S_MB_2U(SCH_1):PAGE579_I25@PURE_QUANTA.Q_CAP(CHIPS)':
 C_PATH='@s9s_mb_2u_lib.s9s_mb_2u(sch_1):page579_i25@pure_quanta.q_cap(chips)';

PART_NAME
 PC1238 'Q_CAP_0805-22UF,4V,20%,X6S,TMPA':;

SECTION_NUMBER 1
 '@S9S_MB_2U_LIB.S9S_MB_2U(SCH_1):PAGE579_I21@PURE_QUANTA.Q_CAP(CHIPS)':
 C_PATH='@s9s_mb_2u_lib.s9s_mb_2u(sch_1):page579_i21@pure_quanta.q_cap(chips)';

PART_NAME
 PC1237 'Q_CAP_0805-22UF,4V,20%,X6S,TMPA':;

SECTION_NUMBER 1
 '@S9S_MB_2U_LIB.S9S_MB_2U(SCH_1):PAGE579_I20@PURE_QUANTA.Q_CAP(CHIPS)':
 C_PATH='@s9s_mb_2u_lib.s9s_mb_2u(sch_1):page579_i20@pure_quanta.q_cap(chips)';

PART_NAME
 PC1236 'Q_CAP_C0402-100NF,50V,10%,X7R,A':;

SECTION_NUMBER 1
 '@S9S_MB_2U_LIB.S9S_MB_2U(SCH_1):PAGE579_I17@PURE_QUANTA.Q_CAP(CHIPS)':
 C_PATH='@s9s_mb_2u_lib.s9s_mb_2u(sch_1):page579_i17@pure_quanta.q_cap(chips)';

PART_NAME
 PC1235 'Q_CAP_0402-0.22UF,16V,10%,X7R,A':;

SECTION_NUMBER 1
 '@S9S_MB_2U_LIB.S9S_MB_2U(SCH_1):PAGE579_I15@PURE_QUANTA.Q_CAP(CHIPS)':
 C_PATH='@s9s_mb_2u_lib.s9s_mb_2u(sch_1):page579_i15@pure_quanta.q_cap(chips)';

PART_NAME
 PC1234 'Q_CAP_C0402-100NF,50V,10%,X7R,A':;

SECTION_NUMBER 1
 '@S9S_MB_2U_LIB.S9S_MB_2U(SCH_1):PAGE579_I12@PURE_QUANTA.Q_CAP(CHIPS)':
 C_PATH='@s9s_mb_2u_lib.s9s_mb_2u(sch_1):page579_i12@pure_quanta.q_cap(chips)';

PART_NAME
 PC1233 'Q_CAP_C0805-22UF,16V,20%,X6S,CA':;

SECTION_NUMBER 1
 '@S9S_MB_2U_LIB.S9S_MB_2U(SCH_1):PAGE579_I8@PURE_QUANTA.Q_CAP(CHIPS)':
 C_PATH='@s9s_mb_2u_lib.s9s_mb_2u(sch_1):page579_i8@pure_quanta.q_cap(chips)';

PART_NAME
 PC1232 'Q_CAP_C0805-22UF,16V,20%,X6S,CA':;

SECTION_NUMBER 1
 '@S9S_MB_2U_LIB.S9S_MB_2U(SCH_1):PAGE579_I7@PURE_QUANTA.Q_CAP(CHIPS)':
 C_PATH='@s9s_mb_2u_lib.s9s_mb_2u(sch_1):page579_i7@pure_quanta.q_cap(chips)';

PART_NAME
 PU72_P0_4 'ISL99390FRZTR5935-ISL99390FRZ-A':;

SECTION_NUMBER 1
 '@S9S_MB_2U_LIB.S9S_MB_2U(SCH_1):PAGE448_I4@PURE_QUANTA.ISL99390FRZTR5935(CHIPS)':
 C_PATH='@s9s_mb_2u_lib.s9s_mb_2u(sch_1):page448_i4@pure_quanta.isl99390frztr5935(~
chips)',
 VAR_0_ONSEMI='VAR_REPLACED|ISL99390FRZTR5935|VAR_PARTNAME|FDMF5085|VALUE|FDMF50~
85|PART_TYPE|SMLF|MATERIAL|IC|PART_NUMBER|AL005085000|STANDARD||LIFECYCLE||PART_~
NUMBER|AL005085000|JEDEC_TYPE|PQFN21_6X5XB|DESCRIPTION|IC OTHER(39P) FDMF5085(PQ~
FN)|MANUFTR|ONS|MANUF_PN|FDMF5085|RD_CMPLS_LVL|EP(V1)|CMPLS_LVL||FROM_PJ|S9S-KIM~
I|CLASS|IC|DIP_SMD||DATA|ONS_FDMF5085.pdf|EE_CHECK_LIST||FP_ECN||PSL||CREATOR||S~
TATUS||MSD|NA|ESD_CDM|NA|ESD_HBM|NA|ESD_MM|NA|PIN_LENGTH_SHORT_PIN|0 MILS|PIN_LE~
NGTH_LONG_PIN|0 MILS|CREATEDAY|20200423|VARIANT_DEVICE_TYPE|FDMF5085-FDMF5085,SM~
LF,IC,AL00',
 CDSVAR_REPCELL_ONSEMI='pure_quanta|fdmf5085';

PART_NAME
 PU71_P0_3 'ISL99390FRZTR5935-ISL99390FRZ-A':;

SECTION_NUMBER 1
 '@S9S_MB_2U_LIB.S9S_MB_2U(SCH_1):PAGE448_I22@PURE_QUANTA.ISL99390FRZTR5935(CHIPS)':
 C_PATH='@s9s_mb_2u_lib.s9s_mb_2u(sch_1):page448_i22@pure_quanta.isl99390frztr5935~
(chips)',
 VAR_0_ONSEMI='VAR_REPLACED|ISL99390FRZTR5935|VAR_PARTNAME|FDMF5085|VALUE|FDMF50~
85|PART_TYPE|SMLF|MATERIAL|IC|PART_NUMBER|AL005085000|STANDARD||LIFECYCLE||PART_~
NUMBER|AL005085000|JEDEC_TYPE|PQFN21_6X5XB|DESCRIPTION|IC OTHER(39P) FDMF5085(PQ~
FN)|MANUFTR|ONS|MANUF_PN|FDMF5085|RD_CMPLS_LVL|EP(V1)|CMPLS_LVL||FROM_PJ|S9S-KIM~
I|CLASS|IC|DIP_SMD||DATA|ONS_FDMF5085.pdf|EE_CHECK_LIST||FP_ECN||PSL||CREATOR||S~
TATUS||MSD|NA|ESD_CDM|NA|ESD_HBM|NA|ESD_MM|NA|PIN_LENGTH_SHORT_PIN|0 MILS|PIN_LE~
NGTH_LONG_PIN|0 MILS|CREATEDAY|20200423|VARIANT_DEVICE_TYPE|FDMF5085-FDMF5085,SM~
LF,IC,AL00',
 CDSVAR_REPCELL_ONSEMI='pure_quanta|fdmf5085';

PART_NAME
 PR1783 'Q_RES_0402LF-3.3,1%,1/16W,CHIPA':;

SECTION_NUMBER 1
 '@S9S_MB_2U_LIB.S9S_MB_2U(SCH_1):PAGE448_I104@PURE_QUANTA.Q_RES(CHIPS)':
 C_PATH='@s9s_mb_2u_lib.s9s_mb_2u(sch_1):page448_i104@pure_quanta.q_res(chips)',
 VAR_0_ONSEMI='VALUE|5.1|TOLERANCE|5%|WATTAGE|1/16W|PACK_TYPE|0402LF|MATERIAL|CH~
IP|PART_NUMBER|CS-5102JB03|STANDARD|End of Design|LIFECYCLE|Comp-Approve|PART_NU~
MBER|CS-5102JB03|JEDEC_TYPE|R0402|ALT_SYMBOLS|(R0402-0201)|VALUE|5.1|TOL|5%|WATT~
AGE|1/16W |CLASS|DISCRETE|DESCRIPTION|RES CHIP 5.1 1/16W +-5%(0402)|COMPONENT_TY~
PE|CHIP0402|LEAD_LENGTH||DFM_EXCLUSION||DAY|20100827|VARIANT_DEVICE_TYPE|Q_RES-5~
.1,5%,1/16W,0402LF,CHIP',
 CDSVAR_REPCELL_ONSEMI='pure_quanta|Q_res';

PART_NAME
 PR1782 'Q_RES_0402LF-3.3,1%,1/16W,CHIPA':;

SECTION_NUMBER 1
 '@S9S_MB_2U_LIB.S9S_MB_2U(SCH_1):PAGE448_I102@PURE_QUANTA.Q_RES(CHIPS)':
 C_PATH='@s9s_mb_2u_lib.s9s_mb_2u(sch_1):page448_i102@pure_quanta.q_res(chips)',
 VAR_0_ONSEMI='VALUE|5.1|TOLERANCE|5%|WATTAGE|1/16W|PACK_TYPE|0402LF|MATERIAL|CH~
IP|PART_NUMBER|CS-5102JB03|STANDARD|End of Design|LIFECYCLE|Comp-Approve|PART_NU~
MBER|CS-5102JB03|JEDEC_TYPE|R0402|ALT_SYMBOLS|(R0402-0201)|VALUE|5.1|TOL|5%|WATT~
AGE|1/16W |CLASS|DISCRETE|DESCRIPTION|RES CHIP 5.1 1/16W +-5%(0402)|COMPONENT_TY~
PE|CHIP0402|LEAD_LENGTH||DFM_EXCLUSION||DAY|20100827|VARIANT_DEVICE_TYPE|Q_RES-5~
.1,5%,1/16W,0402LF,CHIP',
 CDSVAR_REPCELL_ONSEMI='pure_quanta|Q_res';

PART_NAME
 PR1325 'Q_RES_0402LF-0,5%,1/16W,CHIP,CA':;

SECTION_NUMBER 1
 '@S9S_MB_2U_LIB.S9S_MB_2U(SCH_1):PAGE448_I29@PURE_QUANTA.Q_RES(CHIPS)':
 C_PATH='@s9s_mb_2u_lib.s9s_mb_2u(sch_1):page448_i29@pure_quanta.q_res(chips)',
 VAR_0_ONSEMI='VALUE|0|TOLERANCE|5%|WATTAGE|1/16W|PACK_TYPE|0402LF|MATERIAL|EMPT~
Y|PART_NUMBER|CS00002JB38|STANDARD|End of Design|LIFECYCLE|Comp-Approve|PART_NUM~
BER|CS00002JB38|JEDEC_TYPE|R0402|ALT_SYMBOLS|(R0402-0201)|VALUE|0|TOL|5%|WATTAGE~
|1/16W|CLASS|IO|DESCRIPTION|RESISTOR CHIP 0 1/16W +-5%(0402)|COMPONENT_TYPE|CHIP~
0402|LEAD_LENGTH||DFM_EXCLUSION||DAY|20100618|VARIANT_DEVICE_TYPE|Q_RES-0,5%,1/1~
6W,0402LF,EMPTY,',
 CDSVAR_REPCELL_ONSEMI='pure_quanta|Q_res';

PART_NAME
 PR1324 'Q_RES_0402LF-0,5%,1/16W,CHIP,CA':;

SECTION_NUMBER 1
 '@S9S_MB_2U_LIB.S9S_MB_2U(SCH_1):PAGE448_I36@PURE_QUANTA.Q_RES(CHIPS)':
 C_PATH='@s9s_mb_2u_lib.s9s_mb_2u(sch_1):page448_i36@pure_quanta.q_res(chips)',
 VAR_0_ONSEMI='VALUE|0|TOLERANCE|5%|WATTAGE|1/16W|PACK_TYPE|0402LF|MATERIAL|EMPT~
Y|PART_NUMBER|CS00002JB38|STANDARD|End of Design|LIFECYCLE|Comp-Approve|PART_NUM~
BER|CS00002JB38|JEDEC_TYPE|R0402|ALT_SYMBOLS|(R0402-0201)|VALUE|0|TOL|5%|WATTAGE~
|1/16W|CLASS|IO|DESCRIPTION|RESISTOR CHIP 0 1/16W +-5%(0402)|COMPONENT_TYPE|CHIP~
0402|LEAD_LENGTH||DFM_EXCLUSION||DAY|20100618|VARIANT_DEVICE_TYPE|Q_RES-0,5%,1/1~
6W,0402LF,EMPTY,',
 CDSVAR_REPCELL_ONSEMI='pure_quanta|Q_res';

PART_NAME
 PR1300 'Q_RES_0402LF-2.2,1%,1/16W,CHIPA':;

SECTION_NUMBER 1
 '@S9S_MB_2U_LIB.S9S_MB_2U(SCH_1):PAGE448_I10@PURE_QUANTA.Q_RES(CHIPS)':
 C_PATH='@s9s_mb_2u_lib.s9s_mb_2u(sch_1):page448_i10@pure_quanta.q_res(chips)';

PART_NAME
 PR1299 'Q_RES_0402LF-2.2,1%,1/16W,CHIPA':;

SECTION_NUMBER 1
 '@S9S_MB_2U_LIB.S9S_MB_2U(SCH_1):PAGE448_I24@PURE_QUANTA.Q_RES(CHIPS)':
 C_PATH='@s9s_mb_2u_lib.s9s_mb_2u(sch_1):page448_i24@pure_quanta.q_res(chips)';

PART_NAME
 PR1298 'Q_RES_0402LF-8.87K,1%,1/16W,EMA':;

SECTION_NUMBER 1
 '@S9S_MB_2U_LIB.S9S_MB_2U(SCH_1):PAGE448_I15@PURE_QUANTA.Q_RES(CHIPS)':
 C_PATH='@s9s_mb_2u_lib.s9s_mb_2u(sch_1):page448_i15@pure_quanta.q_res(chips)';

PART_NAME
 PR1297 'Q_RES_0402LF-8.87K,1%,1/16W,EMA':;

SECTION_NUMBER 1
 '@S9S_MB_2U_LIB.S9S_MB_2U(SCH_1):PAGE448_I1@PURE_QUANTA.Q_RES(CHIPS)':
 C_PATH='@s9s_mb_2u_lib.s9s_mb_2u(sch_1):page448_i1@pure_quanta.q_res(chips)';

PART_NAME
 PL210 'Q_INDUCTOR_SMLF-130NH/106A,INDA':;

SECTION_NUMBER 1
 '@S9S_MB_2U_LIB.S9S_MB_2U(SCH_1):PAGE448_I98@PURE_QUANTA.Q_INDUCTOR(CHIPS)':
 C_PATH='@s9s_mb_a_lib.s9s_mb_a(sch_1):page448_i98@pure_quanta.q_inductor(chips)~
';

PART_NAME
 PL101 'Q_INDUCTOR_SMLF-100NH/16A,IND,A':;

SECTION_NUMBER 1
 '@S9S_MB_2U_LIB.S9S_MB_2U(SCH_1):PAGE448_I67@PURE_QUANTA.Q_INDUCTOR(CHIPS)':
 C_PATH='@s9s_mb_a_lib.s9s_mb_a(sch_1):page448_i67@pure_quanta.q_inductor(chips)~
';

PART_NAME
 PL2 'Q_INDUCTOR_SMLF-130NH/106A,INDA':;

SECTION_NUMBER 1
 '@S9S_MB_2U_LIB.S9S_MB_2U(SCH_1):PAGE448_I91@PURE_QUANTA.Q_INDUCTOR(CHIPS)':
 C_PATH='@s9s_mb_a_lib.s9s_mb_a(sch_1):page448_i91@pure_quanta.q_inductor(chips)~
';

PART_NAME
 PC2170 'Q_CAPP_SMLF-470UF,2.5V,20%,EMPA':;

SECTION_NUMBER 1
 '@S9S_MB_2U_LIB.S9S_MB_2U(SCH_1):PAGE448_I99@PURE_QUANTA.Q_CAPP(CHIPS)':
 C_PATH='@s9s_mb_2u_lib.s9s_mb_2u(sch_1):page448_i99@pure_quanta.q_capp(chips)';

PART_NAME
 PC1352 'Q_CAP_0402-0.1UF,25V,10%,X7R,CA':;

SECTION_NUMBER 1
 '@S9S_MB_2U_LIB.S9S_MB_2U(SCH_1):PAGE448_I109@PURE_QUANTA.Q_CAP(CHIPS)':
 C_PATH='@s9s_mb_2u_lib.s9s_mb_2u(sch_1):page448_i109@pure_quanta.q_cap(chips)',
 VAR_0_ONSEMI='VALUE|0.1UF|VOLTAGE|25V|TOLERANCE|10%|PACK_TYPE|0402|MATERIAL|EMP~
TY|PART_NUMBER|CH4104K1B00|STANDARD||LIFECYCLE||ASS_PART||PART_NUMBER|CH4104K1B0~
0|JEDEC_TYPE|C0402|ALT_SYMBOLS|(C0402_OCTAGONXA,C0402-0201)|VALUE|NA|RATED_VOLTA~
GE|25V|TOL|10%|CLASS|IO|DESCRIPTION|CAP CHIP 0.1U 25V(+-10%,X7R,0402)|COMPONENT_~
TYPE|CHIP0402|LEAD_LENGTH||LPID||DATE|20160113|VARIANT_DEVICE_TYPE|Q_CAP-0.1UF,2~
5V,10%,0402,EMPTY',
 CDSVAR_REPCELL_ONSEMI='pure_quanta|Q_cap';

PART_NAME
 PC1351 'Q_CAP_0402-0.1UF,25V,10%,X7R,CA':;

SECTION_NUMBER 1
 '@S9S_MB_2U_LIB.S9S_MB_2U(SCH_1):PAGE448_I107@PURE_QUANTA.Q_CAP(CHIPS)':
 C_PATH='@s9s_mb_2u_lib.s9s_mb_2u(sch_1):page448_i107@pure_quanta.q_cap(chips)',
 VAR_0_ONSEMI='VALUE|0.1UF|VOLTAGE|25V|TOLERANCE|10%|PACK_TYPE|0402|MATERIAL|EMP~
TY|PART_NUMBER|CH4104K1B00|STANDARD||LIFECYCLE||ASS_PART||PART_NUMBER|CH4104K1B0~
0|JEDEC_TYPE|C0402|ALT_SYMBOLS|(C0402_OCTAGONXA,C0402-0201)|VALUE|NA|RATED_VOLTA~
GE|25V|TOL|10%|CLASS|IO|DESCRIPTION|CAP CHIP 0.1U 25V(+-10%,X7R,0402)|COMPONENT_~
TYPE|CHIP0402|LEAD_LENGTH||LPID||DATE|20160113|VARIANT_DEVICE_TYPE|Q_CAP-0.1UF,2~
5V,10%,0402,EMPTY',
 CDSVAR_REPCELL_ONSEMI='pure_quanta|Q_cap';

PART_NAME
 PC1214_P0_4 'Q_CAP_C0402-2.2UF,10V,10%,X6S,A':;

SECTION_NUMBER 1
 '@S9S_MB_2U_LIB.S9S_MB_2U(SCH_1):PAGE448_I13@PURE_QUANTA.Q_CAP(CHIPS)':
 C_PATH='@s9s_mb_2u_lib.s9s_mb_2u(sch_1):page448_i13@pure_quanta.q_cap(chips)';

PART_NAME
 PC1213_P0_3 'Q_CAP_C0402-2.2UF,10V,10%,X6S,A':;

SECTION_NUMBER 1
 '@S9S_MB_2U_LIB.S9S_MB_2U(SCH_1):PAGE448_I26@PURE_QUANTA.Q_CAP(CHIPS)':
 C_PATH='@s9s_mb_2u_lib.s9s_mb_2u(sch_1):page448_i26@pure_quanta.q_cap(chips)';

PART_NAME
 PC1189 'Q_CAPP_THLF-270UF,16V,20%,OSCOA':;

SECTION_NUMBER 1
 '@S9S_MB_2U_LIB.S9S_MB_2U(SCH_1):PAGE448_I66@PURE_QUANTA.Q_CAPP(CHIPS)':
 C_PATH='@s9s_mb_2u_lib.s9s_mb_2u(sch_1):page448_i66@pure_quanta.q_capp(chips)';

PART_NAME
 PC1188_P0_4 'Q_CAP_0805-22UF,4V,20%,X6S,TMPA':;

SECTION_NUMBER 1
 '@S9S_MB_2U_LIB.S9S_MB_2U(SCH_1):PAGE448_I44@PURE_QUANTA.Q_CAP(CHIPS)':
 C_PATH='@s9s_mb_2u_lib.s9s_mb_2u(sch_1):page448_i44@pure_quanta.q_cap(chips)';

PART_NAME
 PC1187_P0_3 'Q_CAP_0805-22UF,4V,20%,X6S,TMPA':;

SECTION_NUMBER 1
 '@S9S_MB_2U_LIB.S9S_MB_2U(SCH_1):PAGE448_I49@PURE_QUANTA.Q_CAP(CHIPS)':
 C_PATH='@s9s_mb_2u_lib.s9s_mb_2u(sch_1):page448_i49@pure_quanta.q_cap(chips)';

PART_NAME
 PC1187 'Q_CAPP_SMLF-470UF,2.5V,20%,POSA':;

SECTION_NUMBER 1
 '@S9S_MB_2U_LIB.S9S_MB_2U(SCH_1):PAGE448_I97@PURE_QUANTA.Q_CAPP(CHIPS)':
 C_PATH='@s9s_mb_2u_lib.s9s_mb_2u(sch_1):page448_i97@pure_quanta.q_capp(chips)';

PART_NAME
 PC1186_P0_4 'Q_CAP_0805-22UF,4V,20%,X6S,TMPA':;

SECTION_NUMBER 1
 '@S9S_MB_2U_LIB.S9S_MB_2U(SCH_1):PAGE448_I43@PURE_QUANTA.Q_CAP(CHIPS)':
 C_PATH='@s9s_mb_2u_lib.s9s_mb_2u(sch_1):page448_i43@pure_quanta.q_cap(chips)';

PART_NAME
 PC1186 'Q_CAPP_RDLF-560UF,2.5V,20%,ALUA':;

SECTION_NUMBER 1
 '@S9S_MB_2U_LIB.S9S_MB_2U(SCH_1):PAGE448_I96@PURE_QUANTA.Q_CAPP(CHIPS)':
 C_PATH='@s9s_mb_2u_lib.s9s_mb_2u(sch_1):page448_i96@pure_quanta.q_capp(chips)';

PART_NAME
 PC1185_P0_3 'Q_CAP_0805-22UF,4V,20%,X6S,TMPA':;

SECTION_NUMBER 1
 '@S9S_MB_2U_LIB.S9S_MB_2U(SCH_1):PAGE448_I48@PURE_QUANTA.Q_CAP(CHIPS)':
 C_PATH='@s9s_mb_2u_lib.s9s_mb_2u(sch_1):page448_i48@pure_quanta.q_cap(chips)';

PART_NAME
 PC1185 'Q_CAPP_RDLF-560UF,2.5V,20%,ALUA':;

SECTION_NUMBER 1
 '@S9S_MB_2U_LIB.S9S_MB_2U(SCH_1):PAGE448_I95@PURE_QUANTA.Q_CAPP(CHIPS)':
 C_PATH='@s9s_mb_2u_lib.s9s_mb_2u(sch_1):page448_i95@pure_quanta.q_capp(chips)';

PART_NAME
 PC1183_P0_4 'Q_CAP_C0402-100NF,50V,10%,X7R,A':;

SECTION_NUMBER 1
 '@S9S_MB_2U_LIB.S9S_MB_2U(SCH_1):PAGE448_I113@PURE_QUANTA.Q_CAP(CHIPS)':
 C_PATH='@s9s_mb_2u_lib.s9s_mb_2u(sch_1):page448_i113@pure_quanta.q_cap(chips)';

PART_NAME
 PC1183_P0_3 'Q_CAP_C0402-1UF,16V,10%,X6S,CHA':;

SECTION_NUMBER 1
 '@S9S_MB_2U_LIB.S9S_MB_2U(SCH_1):PAGE448_I47@PURE_QUANTA.Q_CAP(CHIPS)':
 C_PATH='@s9s_mb_2u_lib.s9s_mb_2u(sch_1):page448_i47@pure_quanta.q_cap(chips)';

PART_NAME
 PC1183 'Q_CAPP_RDLF-560UF,2.5V,20%,ALUA':;

SECTION_NUMBER 1
 '@S9S_MB_2U_LIB.S9S_MB_2U(SCH_1):PAGE448_I94@PURE_QUANTA.Q_CAPP(CHIPS)':
 C_PATH='@s9s_mb_2u_lib.s9s_mb_2u(sch_1):page448_i94@pure_quanta.q_capp(chips)';

PART_NAME
 PC1182_P0_4 'Q_CAP_C0805-22UF,16V,20%,X6S,CA':;

SECTION_NUMBER 1
 '@S9S_MB_2U_LIB.S9S_MB_2U(SCH_1):PAGE448_I39@PURE_QUANTA.Q_CAP(CHIPS)':
 C_PATH='@s9s_mb_2u_lib.s9s_mb_2u(sch_1):page448_i39@pure_quanta.q_cap(chips)';

PART_NAME
 PC1181_P0_3 'Q_CAP_C0805-22UF,16V,20%,X6S,CA':;

SECTION_NUMBER 1
 '@S9S_MB_2U_LIB.S9S_MB_2U(SCH_1):PAGE448_I53@PURE_QUANTA.Q_CAP(CHIPS)':
 C_PATH='@s9s_mb_2u_lib.s9s_mb_2u(sch_1):page448_i53@pure_quanta.q_cap(chips)';

PART_NAME
 PC1180_P0_4 'Q_CAP_C0805-22UF,16V,20%,X6S,CA':;

SECTION_NUMBER 1
 '@S9S_MB_2U_LIB.S9S_MB_2U(SCH_1):PAGE448_I34@PURE_QUANTA.Q_CAP(CHIPS)':
 C_PATH='@s9s_mb_2u_lib.s9s_mb_2u(sch_1):page448_i34@pure_quanta.q_cap(chips)';

PART_NAME
 PC1179_P0_3 'Q_CAP_C0805-22UF,16V,20%,X6S,CA':;

SECTION_NUMBER 1
 '@S9S_MB_2U_LIB.S9S_MB_2U(SCH_1):PAGE448_I52@PURE_QUANTA.Q_CAP(CHIPS)':
 C_PATH='@s9s_mb_2u_lib.s9s_mb_2u(sch_1):page448_i52@pure_quanta.q_cap(chips)';

PART_NAME
 PC1178 'Q_CAP_C0402-100NF,50V,10%,X7R,A':;

SECTION_NUMBER 1
 '@S9S_MB_2U_LIB.S9S_MB_2U(SCH_1):PAGE448_I112@PURE_QUANTA.Q_CAP(CHIPS)':
 C_PATH='@s9s_mb_2u_lib.s9s_mb_2u(sch_1):page448_i112@pure_quanta.q_cap(chips)';

PART_NAME
 PC1177 'Q_CAP_C0402-100NF,50V,10%,X7R,A':;

SECTION_NUMBER 1
 '@S9S_MB_2U_LIB.S9S_MB_2U(SCH_1):PAGE448_I111@PURE_QUANTA.Q_CAP(CHIPS)':
 C_PATH='@s9s_mb_2u_lib.s9s_mb_2u(sch_1):page448_i111@pure_quanta.q_cap(chips)';

PART_NAME
 PC1176_P0_4 'Q_CAP_C0402-1UF,16V,10%,X6S,CHA':;

SECTION_NUMBER 1
 '@S9S_MB_2U_LIB.S9S_MB_2U(SCH_1):PAGE448_I33@PURE_QUANTA.Q_CAP(CHIPS)':
 C_PATH='@s9s_mb_2u_lib.s9s_mb_2u(sch_1):page448_i33@pure_quanta.q_cap(chips)';

PART_NAME
 PC1175_P0_3 'Q_CAP_C0402-1UF,16V,10%,X6S,CHA':;

SECTION_NUMBER 1
 '@S9S_MB_2U_LIB.S9S_MB_2U(SCH_1):PAGE448_I51@PURE_QUANTA.Q_CAP(CHIPS)':
 C_PATH='@s9s_mb_2u_lib.s9s_mb_2u(sch_1):page448_i51@pure_quanta.q_cap(chips)';

PART_NAME
 PC1174_P0_4 'Q_CAP_0402-3300PF,50V,10%,X7R,A':;

SECTION_NUMBER 1
 '@S9S_MB_2U_LIB.S9S_MB_2U(SCH_1):PAGE448_I32@PURE_QUANTA.Q_CAP(CHIPS)':
 C_PATH='@s9s_mb_2u_lib.s9s_mb_2u(sch_1):page448_i32@pure_quanta.q_cap(chips)';

PART_NAME
 PC1173_P0_3 'Q_CAP_0402-3300PF,50V,10%,X7R,A':;

SECTION_NUMBER 1
 '@S9S_MB_2U_LIB.S9S_MB_2U(SCH_1):PAGE448_I50@PURE_QUANTA.Q_CAP(CHIPS)':
 C_PATH='@s9s_mb_2u_lib.s9s_mb_2u(sch_1):page448_i50@pure_quanta.q_cap(chips)';

PART_NAME
 PC1172 'Q_CAP_C0402-2.2UF,10V,10%,X6S,A':;

SECTION_NUMBER 1
 '@S9S_MB_2U_LIB.S9S_MB_2U(SCH_1):PAGE448_I9@PURE_QUANTA.Q_CAP(CHIPS)':
 C_PATH='@s9s_mb_2u_lib.s9s_mb_2u(sch_1):page448_i9@pure_quanta.q_cap(chips)';

PART_NAME
 PC1171 'Q_CAP_C0402-2.2UF,10V,10%,X6S,A':;

SECTION_NUMBER 1
 '@S9S_MB_2U_LIB.S9S_MB_2U(SCH_1):PAGE448_I21@PURE_QUANTA.Q_CAP(CHIPS)':
 C_PATH='@s9s_mb_2u_lib.s9s_mb_2u(sch_1):page448_i21@pure_quanta.q_cap(chips)';

PART_NAME
 PU36 'RAA2213404GNPHB0-RAA2213404GNPA':;

SECTION_NUMBER 1
 '@S9S_MB_2U_LIB.S9S_MB_2U(SCH_1):PAGE453_I110@PURE_QUANTA.RAA2213404GNPHB0(CHIPS)':
 C_PATH='@s9s_mb_2u_lib.s9s_mb_2u(sch_1):page453_i110@pure_quanta.raa2213404gnphb0~
(chips)',
 VAR_0_ONSEMI='VAR_REPLACED|RAA2213404GNPHB0|VAR_PARTNAME|FDMF5076|VALUE|FDMF507~
6|PART_TYPE|SMLF|MATERIAL|IC|PART_NUMBER|AL005076000|STANDARD||LIFECYCLE||PART_N~
UMBER|AL005076000|JEDEC_TYPE|PQFN17_TH_5X4XA|DESCRIPTION|IC OTHER(27P)FDMF5076(P~
QFN)|MANUFTR|ONS|MANUF_PN|FDMF5076|RD_CMPLS_LVL|EP(V1)|CMPLS_LVL|EP(V1)|FROM_PJ|~
S9S-KIMI|CLASS|IC|DIP_SMD||DATA|ONS_FDMF5076.pdf|EE_CHECK_LIST||FP_ECN|FDMF5076.~
msg|PSL||CREATOR||STATUS||MSD|NA|ESD_CDM|NA|ESD_HBM|NA|ESD_MM|NA|PIN_LENGTH_SHOR~
T_PIN|0 MILS|PIN_LENGTH_LONG_PIN|0 MILS|CREATEDAY|20200416|VARIANT_DEVICE_TYPE|F~
DMF5076-FDMF5076,SMLF,IC,AL00',
 CDSVAR_REPCELL_ONSEMI='pure_quanta|fdmf5076';

PART_NAME
 PR2718 'Q_RES_0402LF-8.87K,1%,1/16W,EMA':;

SECTION_NUMBER 1
 '@S9S_MB_2U_LIB.S9S_MB_2U(SCH_1):PAGE453_I169@PURE_QUANTA.Q_RES(CHIPS)':
 C_PATH='@s9s_mb_2u_lib.s9s_mb_2u(sch_1):page453_i169@pure_quanta.q_res(chips)';

PART_NAME
 PR1785 'Q_RES_0402LF-0,5%,1/16W,CHIP,CA':;

SECTION_NUMBER 1
 '@S9S_MB_2U_LIB.S9S_MB_2U(SCH_1):PAGE453_I163@PURE_QUANTA.Q_RES(CHIPS)':
 C_PATH='@s9s_mb_2u_lib.s9s_mb_2u(sch_1):page453_i163@pure_quanta.q_res(chips)',
 VAR_0_ONSEMI='VALUE|0|TOLERANCE|5%|WATTAGE|1/16W|PACK_TYPE|0402LF|MATERIAL|EMPT~
Y|PART_NUMBER|CS00002JB38|STANDARD|End of Design|LIFECYCLE|Comp-Approve|PART_NUM~
BER|CS00002JB38|JEDEC_TYPE|R0402|ALT_SYMBOLS|(R0402-0201)|VALUE|0|TOL|5%|WATTAGE~
|1/16W|CLASS|IO|DESCRIPTION|RESISTOR CHIP 0 1/16W +-5%(0402)|COMPONENT_TYPE|CHIP~
0402|LEAD_LENGTH||DFM_EXCLUSION||DAY|20100618|VARIANT_DEVICE_TYPE|Q_RES-0,5%,1/1~
6W,0402LF,EMPTY,',
 CDSVAR_REPCELL_ONSEMI='pure_quanta|Q_res';

PART_NAME
 PR1784 'Q_RES_0402LF-4.7,1%,1/16W,CHIPA':;

SECTION_NUMBER 1
 '@S9S_MB_2U_LIB.S9S_MB_2U(SCH_1):PAGE453_I160@PURE_QUANTA.Q_RES(CHIPS)':
 C_PATH='@s9s_mb_2u_lib.s9s_mb_2u(sch_1):page453_i160@pure_quanta.q_res(chips)',
 VAR_0_ONSEMI='VALUE|0|TOLERANCE|5%|WATTAGE|1/16W|PACK_TYPE|0402LF|MATERIAL|CHIP~
|PART_NUMBER|CS00002JB38|STANDARD|End of Design|LIFECYCLE|Comp-Approve|PART_NUMB~
ER|CS00002JB38|JEDEC_TYPE|R0402|ALT_SYMBOLS|(R0402-0201)|VALUE|0|TOL|5%|WATTAGE|~
1/16W|CLASS|DISCRETE|DESCRIPTION|RESISTOR CHIP 0 1/16W +-5%(0402)|COMPONENT_TYPE~
|CHIP0402|LEAD_LENGTH||DFM_EXCLUSION||DAY|20100618|VARIANT_DEVICE_TYPE|Q_RES-0,5~
%,1/16W,0402LF,CHIP,C',
 CDSVAR_REPCELL_ONSEMI='pure_quanta|Q_res';

PART_NAME
 PR380 'Q_RES_0402LF-2.2,1%,1/16W,CHIPA':;

SECTION_NUMBER 1
 '@S9S_MB_2U_LIB.S9S_MB_2U(SCH_1):PAGE453_I132@PURE_QUANTA.Q_RES(CHIPS)':
 C_PATH='@s9s_mb_2u_lib.s9s_mb_2u(sch_1):page453_i132@pure_quanta.q_res(chips)';

PART_NAME
 PL35 'Q_INDUCTOR_SMLF-130NH/95A,IND,A':;

SECTION_NUMBER 1
 '@S9S_MB_2U_LIB.S9S_MB_2U(SCH_1):PAGE453_I129@PURE_QUANTA.Q_INDUCTOR(CHIPS)':
 C_PATH='@s9s_mb_2u_lib.s9s_mb_2u(sch_1):page453_i129@pure_quanta.q_inductor(chips~
)';

PART_NAME
 PC1910 'Q_CAPP_RDLLF-330UF,2V,35%,C_POA':;

SECTION_NUMBER 1
 '@S9S_MB_2U_LIB.S9S_MB_2U(SCH_1):PAGE453_I159@PURE_QUANTA.Q_CAPP(CHIPS)':
 C_PATH='@s9s_mb_2u_lib.s9s_mb_2u(sch_1):page453_i159@pure_quanta.q_capp(chips)';

PART_NAME
 PC1645 'Q_CAPP_SMLF-470UF,2.5V,20%,EMPB':;

SECTION_NUMBER 1
 '@S9S_MB_2U_LIB.S9S_MB_2U(SCH_1):PAGE453_I157@PURE_QUANTA.Q_CAPP(CHIPS)':
 C_PATH='@s9s_mb_2u_lib.s9s_mb_2u(sch_1):page453_i157@pure_quanta.q_capp(chips)';

PART_NAME
 PC1644 'Q_CAPP_SMLF-470UF,2.5V,20%,OSCA':;

SECTION_NUMBER 1
 '@S9S_MB_2U_LIB.S9S_MB_2U(SCH_1):PAGE453_I145@PURE_QUANTA.Q_CAPP(CHIPS)':
 C_PATH='@s9s_mb_2u_lib.s9s_mb_2u(sch_1):page453_i145@pure_quanta.q_capp(chips)';

PART_NAME
 PC1354 'Q_CAP_0402-0.1UF,25V,10%,X7R,CA':;

SECTION_NUMBER 1
 '@S9S_MB_2U_LIB.S9S_MB_2U(SCH_1):PAGE453_I166@PURE_QUANTA.Q_CAP(CHIPS)':
 C_PATH='@s9s_mb_2u_lib.s9s_mb_2u(sch_1):page453_i166@pure_quanta.q_cap(chips)',
 CDSVAR_REPCELL_ONSEMI='pure_quanta|Q_cap',
 VAR_0_ONSEMI='VALUE|0.1UF|VOLTAGE|25V|TOLERANCE|10%|PACK_TYPE|0402|MATERIAL|EMP~
TY|PART_NUMBER|CH4104K1B00|STANDARD||LIFECYCLE||ASS_PART||PART_NUMBER|CH4104K1B0~
0|JEDEC_TYPE|C0402|ALT_SYMBOLS|(C0402_OCTAGONXA,C0402-0201)|VALUE|NA|RATED_VOLTA~
GE|25V|TOL|10%|CLASS|IO|DESCRIPTION|CAP CHIP 0.1U 25V(+-10%,X7R,0402)|COMPONENT_~
TYPE|CHIP0402|LEAD_LENGTH||LPID||DATE|20160113|VARIANT_DEVICE_TYPE|Q_CAP-0.1UF,2~
5V,10%,0402,EMPTY';

PART_NAME
 PC642 'Q_CAP_0805-22UF,4V,20%,X6S,TMPA':;

SECTION_NUMBER 1
 '@S9S_MB_2U_LIB.S9S_MB_2U(SCH_1):PAGE453_I125@PURE_QUANTA.Q_CAP(CHIPS)':
 C_PATH='@s9s_mb_2u_lib.s9s_mb_2u(sch_1):page453_i125@pure_quanta.q_cap(chips)';

PART_NAME
 PC641 'Q_CAP_0805-22UF,4V,20%,X6S,TMPA':;

SECTION_NUMBER 1
 '@S9S_MB_2U_LIB.S9S_MB_2U(SCH_1):PAGE453_I126@PURE_QUANTA.Q_CAP(CHIPS)':
 C_PATH='@s9s_mb_2u_lib.s9s_mb_2u(sch_1):page453_i126@pure_quanta.q_cap(chips)';

PART_NAME
 PC639 'Q_CAP_C0402-100NF,50V,10%,X7R,A':;

SECTION_NUMBER 1
 '@S9S_MB_2U_LIB.S9S_MB_2U(SCH_1):PAGE453_I128@PURE_QUANTA.Q_CAP(CHIPS)':
 C_PATH='@s9s_mb_2u_lib.s9s_mb_2u(sch_1):page453_i128@pure_quanta.q_cap(chips)';

PART_NAME
 PC638 'Q_CAP_C0805-22UF,16V,20%,X6S,CA':;

SECTION_NUMBER 1
 '@S9S_MB_2U_LIB.S9S_MB_2U(SCH_1):PAGE453_I119@PURE_QUANTA.Q_CAP(CHIPS)':
 C_PATH='@s9s_mb_2u_lib.s9s_mb_2u(sch_1):page453_i119@pure_quanta.q_cap(chips)';

PART_NAME
 PC637 'Q_CAP_C0805-22UF,16V,20%,X6S,CA':;

SECTION_NUMBER 1
 '@S9S_MB_2U_LIB.S9S_MB_2U(SCH_1):PAGE453_I120@PURE_QUANTA.Q_CAP(CHIPS)':
 C_PATH='@s9s_mb_2u_lib.s9s_mb_2u(sch_1):page453_i120@pure_quanta.q_cap(chips)';

PART_NAME
 PC636 'Q_CAP_C0402-100NF,50V,10%,X7R,A':;

SECTION_NUMBER 1
 '@S9S_MB_2U_LIB.S9S_MB_2U(SCH_1):PAGE453_I167@PURE_QUANTA.Q_CAP(CHIPS)':
 C_PATH='@s9s_mb_2u_lib.s9s_mb_2u(sch_1):page453_i167@pure_quanta.q_cap(chips)';

PART_NAME
 PC635 'Q_CAP_C0402-1UF,16V,10%,X6S,CHA':;

SECTION_NUMBER 1
 '@S9S_MB_2U_LIB.S9S_MB_2U(SCH_1):PAGE453_I122@PURE_QUANTA.Q_CAP(CHIPS)':
 C_PATH='@s9s_mb_2u_lib.s9s_mb_2u(sch_1):page453_i122@pure_quanta.q_cap(chips)';

PART_NAME
 PC634 'Q_CAP_0402-3300PF,50V,10%,X7R,A':;

SECTION_NUMBER 1
 '@S9S_MB_2U_LIB.S9S_MB_2U(SCH_1):PAGE453_I123@PURE_QUANTA.Q_CAP(CHIPS)':
 C_PATH='@s9s_mb_2u_lib.s9s_mb_2u(sch_1):page453_i123@pure_quanta.q_cap(chips)';

PART_NAME
 PC633 'Q_CAP_C0402-2.2UF,10V,10%,X6S,A':;

SECTION_NUMBER 1
 '@S9S_MB_2U_LIB.S9S_MB_2U(SCH_1):PAGE453_I134@PURE_QUANTA.Q_CAP(CHIPS)':
 C_PATH='@s9s_mb_2u_lib.s9s_mb_2u(sch_1):page453_i134@pure_quanta.q_cap(chips)';

PART_NAME
 PU70_P0_2 'ISL99390FRZTR5935-ISL99390FRZ-A':;

SECTION_NUMBER 1
 '@S9S_MB_2U_LIB.S9S_MB_2U(SCH_1):PAGE447_I21@PURE_QUANTA.ISL99390FRZTR5935(CHIPS)':
 C_PATH='@s9s_mb_2u_lib.s9s_mb_2u(sch_1):page447_i21@pure_quanta.isl99390frztr5935~
(chips)',
 VAR_0_ONSEMI='VAR_REPLACED|ISL99390FRZTR5935|VAR_PARTNAME|FDMF5085|VALUE|FDMF50~
85|PART_TYPE|SMLF|MATERIAL|IC|PART_NUMBER|AL005085000|STANDARD||LIFECYCLE||PART_~
NUMBER|AL005085000|JEDEC_TYPE|PQFN21_6X5XB|DESCRIPTION|IC OTHER(39P) FDMF5085(PQ~
FN)|MANUFTR|ONS|MANUF_PN|FDMF5085|RD_CMPLS_LVL|EP(V1)|CMPLS_LVL||FROM_PJ|S9S-KIM~
I|CLASS|IC|DIP_SMD||DATA|ONS_FDMF5085.pdf|EE_CHECK_LIST||FP_ECN||PSL||CREATOR||S~
TATUS||MSD|NA|ESD_CDM|NA|ESD_HBM|NA|ESD_MM|NA|PIN_LENGTH_SHORT_PIN|0 MILS|PIN_LE~
NGTH_LONG_PIN|0 MILS|CREATEDAY|20200423|VARIANT_DEVICE_TYPE|FDMF5085-FDMF5085,SM~
LF,IC,AL00',
 CDSVAR_REPCELL_ONSEMI='pure_quanta|fdmf5085';

PART_NAME
 PU69_P0_1 'ISL99390FRZTR5935-ISL99390FRZ-A':;

SECTION_NUMBER 1
 '@S9S_MB_2U_LIB.S9S_MB_2U(SCH_1):PAGE447_I23@PURE_QUANTA.ISL99390FRZTR5935(CHIPS)':
 C_PATH='@s9s_mb_2u_lib.s9s_mb_2u(sch_1):page447_i23@pure_quanta.isl99390frztr5935~
(chips)',
 VAR_0_ONSEMI='VAR_REPLACED|ISL99390FRZTR5935|VAR_PARTNAME|FDMF5085|VALUE|FDMF50~
85|PART_TYPE|SMLF|MATERIAL|IC|PART_NUMBER|AL005085000|STANDARD||LIFECYCLE||PART_~
NUMBER|AL005085000|JEDEC_TYPE|PQFN21_6X5XB|DESCRIPTION|IC OTHER(39P) FDMF5085(PQ~
FN)|MANUFTR|ONS|MANUF_PN|FDMF5085|RD_CMPLS_LVL|EP(V1)|CMPLS_LVL||FROM_PJ|S9S-KIM~
I|CLASS|IC|DIP_SMD||DATA|ONS_FDMF5085.pdf|EE_CHECK_LIST||FP_ECN||PSL||CREATOR||S~
TATUS||MSD|NA|ESD_CDM|NA|ESD_HBM|NA|ESD_MM|NA|PIN_LENGTH_SHORT_PIN|0 MILS|PIN_LE~
NGTH_LONG_PIN|0 MILS|CREATEDAY|20200423|VARIANT_DEVICE_TYPE|FDMF5085-FDMF5085,SM~
LF,IC,AL00',
 CDSVAR_REPCELL_ONSEMI='pure_quanta|fdmf5085';

PART_NAME
 PR1781 'Q_RES_0402LF-3.3,1%,1/16W,CHIPA':;

SECTION_NUMBER 1
 '@S9S_MB_2U_LIB.S9S_MB_2U(SCH_1):PAGE447_I95@PURE_QUANTA.Q_RES(CHIPS)':
 C_PATH='@s9s_mb_2u_lib.s9s_mb_2u(sch_1):page447_i95@pure_quanta.q_res(chips)',
 VAR_0_ONSEMI='VALUE|5.1|TOLERANCE|5%|WATTAGE|1/16W|PACK_TYPE|0402LF|MATERIAL|CH~
IP|PART_NUMBER|CS-5102JB03|STANDARD|End of Design|LIFECYCLE|Comp-Approve|PART_NU~
MBER|CS-5102JB03|JEDEC_TYPE|R0402|ALT_SYMBOLS|(R0402-0201)|VALUE|5.1|TOL|5%|WATT~
AGE|1/16W |CLASS|DISCRETE|DESCRIPTION|RES CHIP 5.1 1/16W +-5%(0402)|COMPONENT_TY~
PE|CHIP0402|LEAD_LENGTH||DFM_EXCLUSION||DAY|20100827|VARIANT_DEVICE_TYPE|Q_RES-5~
.1,5%,1/16W,0402LF,CHIP',
 CDSVAR_REPCELL_ONSEMI='pure_quanta|Q_res';

PART_NAME
 PR1780 'Q_RES_0402LF-3.3,1%,1/16W,CHIPA':;

SECTION_NUMBER 1
 '@S9S_MB_2U_LIB.S9S_MB_2U(SCH_1):PAGE447_I94@PURE_QUANTA.Q_RES(CHIPS)':
 C_PATH='@s9s_mb_2u_lib.s9s_mb_2u(sch_1):page447_i94@pure_quanta.q_res(chips)',
 VAR_0_ONSEMI='VALUE|5.1|TOLERANCE|5%|WATTAGE|1/16W|PACK_TYPE|0402LF|MATERIAL|CH~
IP|PART_NUMBER|CS-5102JB03|STANDARD|End of Design|LIFECYCLE|Comp-Approve|PART_NU~
MBER|CS-5102JB03|JEDEC_TYPE|R0402|ALT_SYMBOLS|(R0402-0201)|VALUE|5.1|TOL|5%|WATT~
AGE|1/16W |CLASS|DISCRETE|DESCRIPTION|RES CHIP 5.1 1/16W +-5%(0402)|COMPONENT_TY~
PE|CHIP0402|LEAD_LENGTH||DFM_EXCLUSION||DAY|20100827|VARIANT_DEVICE_TYPE|Q_RES-5~
.1,5%,1/16W,0402LF,CHIP',
 CDSVAR_REPCELL_ONSEMI='pure_quanta|Q_res';

PART_NAME
 PR1323 'Q_RES_0402LF-0,5%,1/16W,CHIP,CA':;

SECTION_NUMBER 1
 '@S9S_MB_2U_LIB.S9S_MB_2U(SCH_1):PAGE447_I69@PURE_QUANTA.Q_RES(CHIPS)':
 C_PATH='@s9s_mb_2u_lib.s9s_mb_2u(sch_1):page447_i69@pure_quanta.q_res(chips)',
 VAR_0_ONSEMI='VALUE|0|TOLERANCE|5%|WATTAGE|1/16W|PACK_TYPE|0402LF|MATERIAL|EMPT~
Y|PART_NUMBER|CS00002JB38|STANDARD|End of Design|LIFECYCLE|Comp-Approve|PART_NUM~
BER|CS00002JB38|JEDEC_TYPE|R0402|ALT_SYMBOLS|(R0402-0201)|VALUE|0|TOL|5%|WATTAGE~
|1/16W|CLASS|IO|DESCRIPTION|RESISTOR CHIP 0 1/16W +-5%(0402)|COMPONENT_TYPE|CHIP~
0402|LEAD_LENGTH||DFM_EXCLUSION||DAY|20100618|VARIANT_DEVICE_TYPE|Q_RES-0,5%,1/1~
6W,0402LF,EMPTY,',
 CDSVAR_REPCELL_ONSEMI='pure_quanta|Q_res';

PART_NAME
 PR1322 'Q_RES_0402LF-0,5%,1/16W,CHIP,CA':;

SECTION_NUMBER 1
 '@S9S_MB_2U_LIB.S9S_MB_2U(SCH_1):PAGE447_I66@PURE_QUANTA.Q_RES(CHIPS)':
 C_PATH='@s9s_mb_2u_lib.s9s_mb_2u(sch_1):page447_i66@pure_quanta.q_res(chips)',
 VAR_0_ONSEMI='VALUE|0|TOLERANCE|5%|WATTAGE|1/16W|PACK_TYPE|0402LF|MATERIAL|EMPT~
Y|PART_NUMBER|CS00002JB38|STANDARD|End of Design|LIFECYCLE|Comp-Approve|PART_NUM~
BER|CS00002JB38|JEDEC_TYPE|R0402|ALT_SYMBOLS|(R0402-0201)|VALUE|0|TOL|5%|WATTAGE~
|1/16W|CLASS|IO|DESCRIPTION|RESISTOR CHIP 0 1/16W +-5%(0402)|COMPONENT_TYPE|CHIP~
0402|LEAD_LENGTH||DFM_EXCLUSION||DAY|20100618|VARIANT_DEVICE_TYPE|Q_RES-0,5%,1/1~
6W,0402LF,EMPTY,',
 CDSVAR_REPCELL_ONSEMI='pure_quanta|Q_res';

PART_NAME
 PR356 'Q_RES_0402LF-2.2,1%,1/16W,CHIPA':;

SECTION_NUMBER 1
 '@S9S_MB_2U_LIB.S9S_MB_2U(SCH_1):PAGE447_I9@PURE_QUANTA.Q_RES(CHIPS)':
 C_PATH='@s9s_mb_2u_lib.s9s_mb_2u(sch_1):page447_i9@pure_quanta.q_res(chips)';

PART_NAME
 PR355 'Q_RES_0402LF-2.2,1%,1/16W,CHIPA':;

SECTION_NUMBER 1
 '@S9S_MB_2U_LIB.S9S_MB_2U(SCH_1):PAGE447_I19@PURE_QUANTA.Q_RES(CHIPS)':
 C_PATH='@s9s_mb_2u_lib.s9s_mb_2u(sch_1):page447_i19@pure_quanta.q_res(chips)';

PART_NAME
 PR354 'Q_RES_0402LF-8.87K,1%,1/16W,EMA':;

SECTION_NUMBER 1
 '@S9S_MB_2U_LIB.S9S_MB_2U(SCH_1):PAGE447_I12@PURE_QUANTA.Q_RES(CHIPS)':
 C_PATH='@s9s_mb_2u_lib.s9s_mb_2u(sch_1):page447_i12@pure_quanta.q_res(chips)';

PART_NAME
 PR353 'Q_RES_0402LF-8.87K,1%,1/16W,EMA':;

SECTION_NUMBER 1
 '@S9S_MB_2U_LIB.S9S_MB_2U(SCH_1):PAGE447_I70@PURE_QUANTA.Q_RES(CHIPS)':
 C_PATH='@s9s_mb_2u_lib.s9s_mb_2u(sch_1):page447_i70@pure_quanta.q_res(chips)';

PART_NAME
 PL44 'Q_INDUCTOR_SMLF-100NH/16A,IND,A':;

SECTION_NUMBER 1
 '@S9S_MB_2U_LIB.S9S_MB_2U(SCH_1):PAGE447_I59@PURE_QUANTA.Q_INDUCTOR(CHIPS)':
 C_PATH='@s9s_mb_a_lib.s9s_mb_a(sch_1):page447_i59@pure_quanta.q_inductor(chips)~
';

PART_NAME
 PL34 'Q_INDUCTOR_SMLF-130NH/106A,INDA':;

SECTION_NUMBER 1
 '@S9S_MB_2U_LIB.S9S_MB_2U(SCH_1):PAGE447_I89@PURE_QUANTA.Q_INDUCTOR(CHIPS)':
 C_PATH='@s9s_mb_a_lib.s9s_mb_a(sch_1):page447_i89@pure_quanta.q_inductor(chips)~
';

PART_NAME
 PL33 'Q_INDUCTOR_SMLF-130NH/106A,INDA':;

SECTION_NUMBER 1
 '@S9S_MB_2U_LIB.S9S_MB_2U(SCH_1):PAGE447_I88@PURE_QUANTA.Q_INDUCTOR(CHIPS)':
 C_PATH='@s9s_mb_a_lib.s9s_mb_a(sch_1):page447_i88@pure_quanta.q_inductor(chips)~
';

PART_NAME
 PC2645 'Q_CAPP_SMLF-470UF,2.5V,20%,EMPA':;

SECTION_NUMBER 1
 '@S9S_MB_2U_LIB.S9S_MB_2U(SCH_1):PAGE447_I90@PURE_QUANTA.Q_CAPP(CHIPS)':
 C_PATH='@s9s_mb_2u_lib.s9s_mb_2u(sch_1):page447_i90@pure_quanta.q_capp(chips)';

PART_NAME
 PC1350 'Q_CAP_0402-0.1UF,25V,10%,X7R,CA':;

SECTION_NUMBER 1
 '@S9S_MB_2U_LIB.S9S_MB_2U(SCH_1):PAGE447_I100@PURE_QUANTA.Q_CAP(CHIPS)':
 C_PATH='@s9s_mb_2u_lib.s9s_mb_2u(sch_1):page447_i100@pure_quanta.q_cap(chips)',
 VAR_0_ONSEMI='VALUE|0.1UF|VOLTAGE|25V|TOLERANCE|10%|PACK_TYPE|0402|MATERIAL|EMP~
TY|PART_NUMBER|CH4104K1B00|STANDARD||LIFECYCLE||ASS_PART||PART_NUMBER|CH4104K1B0~
0|JEDEC_TYPE|C0402|ALT_SYMBOLS|(C0402_OCTAGONXA,C0402-0201)|VALUE|NA|RATED_VOLTA~
GE|25V|TOL|10%|CLASS|IO|DESCRIPTION|CAP CHIP 0.1U 25V(+-10%,X7R,0402)|COMPONENT_~
TYPE|CHIP0402|LEAD_LENGTH||LPID||DATE|20160113|VARIANT_DEVICE_TYPE|Q_CAP-0.1UF,2~
5V,10%,0402,EMPTY',
 CDSVAR_REPCELL_ONSEMI='pure_quanta|Q_cap';

PART_NAME
 PC1349 'Q_CAP_0402-0.1UF,25V,10%,X7R,CA':;

SECTION_NUMBER 1
 '@S9S_MB_2U_LIB.S9S_MB_2U(SCH_1):PAGE447_I98@PURE_QUANTA.Q_CAP(CHIPS)':
 C_PATH='@s9s_mb_2u_lib.s9s_mb_2u(sch_1):page447_i98@pure_quanta.q_cap(chips)',
 VAR_0_ONSEMI='VALUE|0.1UF|VOLTAGE|25V|TOLERANCE|10%|PACK_TYPE|0402|MATERIAL|EMP~
TY|PART_NUMBER|CH4104K1B00|STANDARD||LIFECYCLE||ASS_PART||PART_NUMBER|CH4104K1B0~
0|JEDEC_TYPE|C0402|ALT_SYMBOLS|(C0402_OCTAGONXA,C0402-0201)|VALUE|NA|RATED_VOLTA~
GE|25V|TOL|10%|CLASS|IO|DESCRIPTION|CAP CHIP 0.1U 25V(+-10%,X7R,0402)|COMPONENT_~
TYPE|CHIP0402|LEAD_LENGTH||LPID||DATE|20160113|VARIANT_DEVICE_TYPE|Q_CAP-0.1UF,2~
5V,10%,0402,EMPTY',
 CDSVAR_REPCELL_ONSEMI='pure_quanta|Q_cap';

PART_NAME
 PC1212_P0_2 'Q_CAP_C0402-2.2UF,10V,10%,X6S,A':;

SECTION_NUMBER 1
 '@S9S_MB_2U_LIB.S9S_MB_2U(SCH_1):PAGE447_I67@PURE_QUANTA.Q_CAP(CHIPS)':
 C_PATH='@s9s_mb_2u_lib.s9s_mb_2u(sch_1):page447_i67@pure_quanta.q_cap(chips)';

PART_NAME
 PC1211_P0_1 'Q_CAP_C0402-2.2UF,10V,10%,X6S,A':;

SECTION_NUMBER 1
 '@S9S_MB_2U_LIB.S9S_MB_2U(SCH_1):PAGE447_I65@PURE_QUANTA.Q_CAP(CHIPS)':
 C_PATH='@s9s_mb_2u_lib.s9s_mb_2u(sch_1):page447_i65@pure_quanta.q_cap(chips)';

PART_NAME
 PC623 'Q_CAPP_SMLF-470UF,2.5V,20%,POSA':;

SECTION_NUMBER 1
 '@S9S_MB_2U_LIB.S9S_MB_2U(SCH_1):PAGE447_I56@PURE_QUANTA.Q_CAPP(CHIPS)':
 C_PATH='@s9s_mb_2u_lib.s9s_mb_2u(sch_1):page447_i56@pure_quanta.q_capp(chips)';

PART_NAME
 PC622 'Q_CAPP_THLF-270UF,16V,20%,OSCOA':;

SECTION_NUMBER 1
 '@S9S_MB_2U_LIB.S9S_MB_2U(SCH_1):PAGE447_I61@PURE_QUANTA.Q_CAPP(CHIPS)':
 C_PATH='@s9s_mb_2u_lib.s9s_mb_2u(sch_1):page447_i61@pure_quanta.q_capp(chips)';

PART_NAME
 PC621 'Q_CAPP_RDLF-560UF,2.5V,20%,ALUA':;

SECTION_NUMBER 1
 '@S9S_MB_2U_LIB.S9S_MB_2U(SCH_1):PAGE447_I54@PURE_QUANTA.Q_CAPP(CHIPS)':
 C_PATH='@s9s_mb_2u_lib.s9s_mb_2u(sch_1):page447_i54@pure_quanta.q_capp(chips)';

PART_NAME
 PC620 'Q_CAPP_RDLF-560UF,2.5V,20%,ALUA':;

SECTION_NUMBER 1
 '@S9S_MB_2U_LIB.S9S_MB_2U(SCH_1):PAGE447_I48@PURE_QUANTA.Q_CAPP(CHIPS)':
 C_PATH='@s9s_mb_2u_lib.s9s_mb_2u(sch_1):page447_i48@pure_quanta.q_capp(chips)';

PART_NAME
 PC619 'Q_CAPP_RDLF-560UF,2.5V,20%,ALUA':;

SECTION_NUMBER 1
 '@S9S_MB_2U_LIB.S9S_MB_2U(SCH_1):PAGE447_I47@PURE_QUANTA.Q_CAPP(CHIPS)':
 C_PATH='@s9s_mb_2u_lib.s9s_mb_2u(sch_1):page447_i47@pure_quanta.q_capp(chips)';

PART_NAME
 PC618_P0_2 'Q_CAP_0805-22UF,4V,20%,X6S,TMPA':;

SECTION_NUMBER 1
 '@S9S_MB_2U_LIB.S9S_MB_2U(SCH_1):PAGE447_I44@PURE_QUANTA.Q_CAP(CHIPS)':
 C_PATH='@s9s_mb_2u_lib.s9s_mb_2u(sch_1):page447_i44@pure_quanta.q_cap(chips)';

PART_NAME
 PC617_P0_1 'Q_CAP_0805-22UF,4V,20%,X6S,TMPA':;

SECTION_NUMBER 1
 '@S9S_MB_2U_LIB.S9S_MB_2U(SCH_1):PAGE447_I51@PURE_QUANTA.Q_CAP(CHIPS)':
 C_PATH='@s9s_mb_2u_lib.s9s_mb_2u(sch_1):page447_i51@pure_quanta.q_cap(chips)';

PART_NAME
 PC616_P0_2 'Q_CAP_0805-22UF,4V,20%,X6S,TMPA':;

SECTION_NUMBER 1
 '@S9S_MB_2U_LIB.S9S_MB_2U(SCH_1):PAGE447_I43@PURE_QUANTA.Q_CAP(CHIPS)':
 C_PATH='@s9s_mb_2u_lib.s9s_mb_2u(sch_1):page447_i43@pure_quanta.q_cap(chips)';

PART_NAME
 PC615_P0_1 'Q_CAP_0805-22UF,4V,20%,X6S,TMPA':;

SECTION_NUMBER 1
 '@S9S_MB_2U_LIB.S9S_MB_2U(SCH_1):PAGE447_I50@PURE_QUANTA.Q_CAP(CHIPS)':
 C_PATH='@s9s_mb_2u_lib.s9s_mb_2u(sch_1):page447_i50@pure_quanta.q_cap(chips)';

PART_NAME
 PC613_P0_2 'Q_CAP_C0402-1UF,16V,10%,X6S,CHA':;

SECTION_NUMBER 1
 '@S9S_MB_2U_LIB.S9S_MB_2U(SCH_1):PAGE447_I103@PURE_QUANTA.Q_CAP(CHIPS)':
 C_PATH='@s9s_mb_2u_lib.s9s_mb_2u(sch_1):page447_i103@pure_quanta.q_cap(chips)';

PART_NAME
 PC612_P0_1 'Q_CAP_C0402-100NF,50V,10%,X7R,A':;

SECTION_NUMBER 1
 '@S9S_MB_2U_LIB.S9S_MB_2U(SCH_1):PAGE447_I35@PURE_QUANTA.Q_CAP(CHIPS)':
 C_PATH='@s9s_mb_2u_lib.s9s_mb_2u(sch_1):page447_i35@pure_quanta.q_cap(chips)';

PART_NAME
 PC611_P0_2 'Q_CAP_C0805-22UF,16V,20%,X6S,CA':;

SECTION_NUMBER 1
 '@S9S_MB_2U_LIB.S9S_MB_2U(SCH_1):PAGE447_I30@PURE_QUANTA.Q_CAP(CHIPS)':
 C_PATH='@s9s_mb_2u_lib.s9s_mb_2u(sch_1):page447_i30@pure_quanta.q_cap(chips)';

PART_NAME
 PC610_P0_1 'Q_CAP_C0805-22UF,16V,20%,X6S,CA':;

SECTION_NUMBER 1
 '@S9S_MB_2U_LIB.S9S_MB_2U(SCH_1):PAGE447_I39@PURE_QUANTA.Q_CAP(CHIPS)':
 C_PATH='@s9s_mb_2u_lib.s9s_mb_2u(sch_1):page447_i39@pure_quanta.q_cap(chips)';

PART_NAME
 PC609_P0_2 'Q_CAP_C0805-22UF,16V,20%,X6S,CA':;

SECTION_NUMBER 1
 '@S9S_MB_2U_LIB.S9S_MB_2U(SCH_1):PAGE447_I29@PURE_QUANTA.Q_CAP(CHIPS)':
 C_PATH='@s9s_mb_2u_lib.s9s_mb_2u(sch_1):page447_i29@pure_quanta.q_cap(chips)';

PART_NAME
 PC608_P0_1 'Q_CAP_C0805-22UF,16V,20%,X6S,CA':;

SECTION_NUMBER 1
 '@S9S_MB_2U_LIB.S9S_MB_2U(SCH_1):PAGE447_I38@PURE_QUANTA.Q_CAP(CHIPS)':
 C_PATH='@s9s_mb_2u_lib.s9s_mb_2u(sch_1):page447_i38@pure_quanta.q_cap(chips)';

PART_NAME
 PC607 'Q_CAP_C0402-100NF,50V,10%,X7R,A':;

SECTION_NUMBER 1
 '@S9S_MB_2U_LIB.S9S_MB_2U(SCH_1):PAGE447_I101@PURE_QUANTA.Q_CAP(CHIPS)':
 C_PATH='@s9s_mb_2u_lib.s9s_mb_2u(sch_1):page447_i101@pure_quanta.q_cap(chips)';

PART_NAME
 PC606 'Q_CAP_C0402-100NF,50V,10%,X7R,A':;

SECTION_NUMBER 1
 '@S9S_MB_2U_LIB.S9S_MB_2U(SCH_1):PAGE447_I102@PURE_QUANTA.Q_CAP(CHIPS)':
 C_PATH='@s9s_mb_2u_lib.s9s_mb_2u(sch_1):page447_i102@pure_quanta.q_cap(chips)';

PART_NAME
 PC605_P0_2 'Q_CAP_C0402-1UF,16V,10%,X6S,CHA':;

SECTION_NUMBER 1
 '@S9S_MB_2U_LIB.S9S_MB_2U(SCH_1):PAGE447_I26@PURE_QUANTA.Q_CAP(CHIPS)':
 C_PATH='@s9s_mb_2u_lib.s9s_mb_2u(sch_1):page447_i26@pure_quanta.q_cap(chips)';

PART_NAME
 PC604_P0_1 'Q_CAP_C0402-1UF,16V,10%,X6S,CHA':;

SECTION_NUMBER 1
 '@S9S_MB_2U_LIB.S9S_MB_2U(SCH_1):PAGE447_I37@PURE_QUANTA.Q_CAP(CHIPS)':
 C_PATH='@s9s_mb_2u_lib.s9s_mb_2u(sch_1):page447_i37@pure_quanta.q_cap(chips)';

PART_NAME
 PC603_P0_2 'Q_CAP_0402-3300PF,50V,10%,X7R,A':;

SECTION_NUMBER 1
 '@S9S_MB_2U_LIB.S9S_MB_2U(SCH_1):PAGE447_I25@PURE_QUANTA.Q_CAP(CHIPS)':
 C_PATH='@s9s_mb_2u_lib.s9s_mb_2u(sch_1):page447_i25@pure_quanta.q_cap(chips)';

PART_NAME
 PC602_P0_1 'Q_CAP_0402-3300PF,50V,10%,X7R,A':;

SECTION_NUMBER 1
 '@S9S_MB_2U_LIB.S9S_MB_2U(SCH_1):PAGE447_I36@PURE_QUANTA.Q_CAP(CHIPS)':
 C_PATH='@s9s_mb_2u_lib.s9s_mb_2u(sch_1):page447_i36@pure_quanta.q_cap(chips)';

PART_NAME
 PC601 'Q_CAP_C0402-2.2UF,10V,10%,X6S,A':;

SECTION_NUMBER 1
 '@S9S_MB_2U_LIB.S9S_MB_2U(SCH_1):PAGE447_I7@PURE_QUANTA.Q_CAP(CHIPS)':
 C_PATH='@s9s_mb_2u_lib.s9s_mb_2u(sch_1):page447_i7@pure_quanta.q_cap(chips)';

PART_NAME
 PC600 'Q_CAP_C0402-2.2UF,10V,10%,X6S,A':;

SECTION_NUMBER 1
 '@S9S_MB_2U_LIB.S9S_MB_2U(SCH_1):PAGE447_I18@PURE_QUANTA.Q_CAP(CHIPS)':
 C_PATH='@s9s_mb_2u_lib.s9s_mb_2u(sch_1):page447_i18@pure_quanta.q_cap(chips)';

PART_NAME
 R1772 'Q_RES_0402LF-100,1%,1/16W,EMPTA':;

SECTION_NUMBER 1
 '@S9S_MB_2U_LIB.S9S_MB_2U(SCH_1):PAGE446_I222@PURE_QUANTA.Q_RES(CHIPS)':
 C_PATH='@s9s_mb_2u_lib.s9s_mb_2u(sch_1):page446_i222@pure_quanta.q_res(chips)';

PART_NAME
 R1767 'Q_RES_0402LF-49.9     ,1%  ,1/B':;

SECTION_NUMBER 1
 '@S9S_MB_2U_LIB.S9S_MB_2U(SCH_1):PAGE446_I221@PURE_QUANTA.Q_RES(CHIPS)':
 C_PATH='@s9s_mb_2u_lib.s9s_mb_2u(sch_1):page446_i221@pure_quanta.q_res(chips)';

PART_NAME
 PU32 'ISL69260IRAZT-ISL69260IRAZ-T,SA':;

SECTION_NUMBER 1
 '@S9S_MB_2U_LIB.S9S_MB_2U(SCH_1):PAGE446_I225@PURE_QUANTA.ISL69260IRAZT(CHIPS)':
 C_PATH='@s9s_mb_2u_lib.s9s_mb_2u(sch_1):page446_i225@pure_quanta.isl69260irazt(ch~
ips)',
 VAR_0_ONSEMI='VAR_REPLACED|ISL69260IRAZT|VAR_PARTNAME|FD5001|VALUE|FD5001|PART_~
TYPE|SMLF|MATERIAL|IC|PART_NUMBER|AL005001004|STANDARD||LIFECYCLE||PART_NUMBER|A~
L005001004|JEDEC_TYPE|VFQFPN40_TH_0-4_5X5XC|DESCRIPTION|IC OTHER(40P) FD5001(QFN~
)|MANUFTR|ONS|MANUF_PN|FD5001|RD_CMPLS_LVL|EP(V1)|CMPLS_LVL||FROM_PJ|S9S-KIMI|CL~
ASS|IC|DIP_SMD||DATA|ONS_FD5001.pdf|EE_CHECK_LIST||FP_ECN|FD5001.msg|PSL||CREATO~
R||STATUS||MSD|NA|ESD_CDM|NA|ESD_HBM|NA|ESD_MM|NA|PIN_LENGTH_SHORT_PIN|0 MILS|PI~
N_LENGTH_LONG_PIN|0 MILS|CREATEDAY|20200421|VARIANT_DEVICE_TYPE|FD5001-FD5001,SM~
LF,IC,AL005001',
 CDSVAR_REPCELL_ONSEMI='pure_quanta|fd5001';

PART_NAME
 PR1308 'Q_RES_0402LF-0,5%,1/16W,CHIP,CA':;

SECTION_NUMBER 1
 '@S9S_MB_2U_LIB.S9S_MB_2U(SCH_1):PAGE446_I215@PURE_QUANTA.Q_RES(CHIPS)':
 C_PATH='@s9s_mb_2u_lib.s9s_mb_2u(sch_1):page446_i215@pure_quanta.q_res(chips)';

PART_NAME
 PR587 'Q_RES_0402LF-100,1%,1/16W,CHIPA':;

SECTION_NUMBER 1
 '@S9S_MB_2U_LIB.S9S_MB_2U(SCH_1):PAGE446_I128@PURE_QUANTA.Q_RES(CHIPS)':
 C_PATH='@s9s_mb_2u_lib.s9s_mb_2u(sch_1):page446_i128@pure_quanta.q_res(chips)';

PART_NAME
 PR586 'Q_RES_0402LF-100,1%,1/16W,CHIPA':;

SECTION_NUMBER 1
 '@S9S_MB_2U_LIB.S9S_MB_2U(SCH_1):PAGE446_I117@PURE_QUANTA.Q_RES(CHIPS)':
 C_PATH='@s9s_mb_2u_lib.s9s_mb_2u(sch_1):page446_i117@pure_quanta.q_res(chips)';

PART_NAME
 PR352 'Q_RES_0402LF-1K,1%,1/16W,EMPTYA':;

SECTION_NUMBER 1
 '@S9S_MB_2U_LIB.S9S_MB_2U(SCH_1):PAGE446_I167@PURE_QUANTA.Q_RES(CHIPS)':
 C_PATH='@s9s_mb_2u_lib.s9s_mb_2u(sch_1):page446_i167@pure_quanta.q_res(chips)';

PART_NAME
 PR351 'Q_RES_0402LF-1,1%,1/16W,CHIP,CA':;

SECTION_NUMBER 1
 '@S9S_MB_2U_LIB.S9S_MB_2U(SCH_1):PAGE446_I184@PURE_QUANTA.Q_RES(CHIPS)':
 C_PATH='@s9s_mb_2u_lib.s9s_mb_2u(sch_1):page446_i184@pure_quanta.q_res(chips)';

PART_NAME
 PR347 'Q_RES_0402LF-1K,1%,1/16W,EMPTYA':;

SECTION_NUMBER 1
 '@S9S_MB_2U_LIB.S9S_MB_2U(SCH_1):PAGE446_I191@PURE_QUANTA.Q_RES(CHIPS)':
 C_PATH='@s9s_mb_2u_lib.s9s_mb_2u(sch_1):page446_i191@pure_quanta.q_res(chips)';

PART_NAME
 PR346 'Q_RES_0402LF-1K,1%,1/16W,CHIP,A':;

SECTION_NUMBER 1
 '@S9S_MB_2U_LIB.S9S_MB_2U(SCH_1):PAGE446_I122@PURE_QUANTA.Q_RES(CHIPS)':
 C_PATH='@s9s_mb_2u_lib.s9s_mb_2u(sch_1):page446_i122@pure_quanta.q_res(chips)';

PART_NAME
 PR345 'Q_RES_0402LF-0,5%,1/16W,CHIP,CA':;

SECTION_NUMBER 1
 '@S9S_MB_2U_LIB.S9S_MB_2U(SCH_1):PAGE446_I135@PURE_QUANTA.Q_RES(CHIPS)':
 C_PATH='@s9s_mb_2u_lib.s9s_mb_2u(sch_1):page446_i135@pure_quanta.q_res(chips)';

PART_NAME
 PR344 'Q_RES_0402LF-1K,1%,1/16W,CHIP,A':;

SECTION_NUMBER 1
 '@S9S_MB_2U_LIB.S9S_MB_2U(SCH_1):PAGE446_I120@PURE_QUANTA.Q_RES(CHIPS)':
 C_PATH='@s9s_mb_2u_lib.s9s_mb_2u(sch_1):page446_i120@pure_quanta.q_res(chips)';

PART_NAME
 PR343 'Q_RES_0402LF-1K,1%,1/16W,EMPTYA':;

SECTION_NUMBER 1
 '@S9S_MB_2U_LIB.S9S_MB_2U(SCH_1):PAGE446_I188@PURE_QUANTA.Q_RES(CHIPS)':
 C_PATH='@s9s_mb_2u_lib.s9s_mb_2u(sch_1):page446_i188@pure_quanta.q_res(chips)';

PART_NAME
 PR342 'Q_RES_0402LF-33.2,1%,1/16W,CHIA':;

SECTION_NUMBER 1
 '@S9S_MB_2U_LIB.S9S_MB_2U(SCH_1):PAGE446_I136@PURE_QUANTA.Q_RES(CHIPS)':
 C_PATH='@s9s_mb_2u_lib.s9s_mb_2u(sch_1):page446_i136@pure_quanta.q_res(chips)';

PART_NAME
 PR341 'Q_RES_0402LF-0,5%,1/16W,CHIP,CA':;

SECTION_NUMBER 1
 '@S9S_MB_2U_LIB.S9S_MB_2U(SCH_1):PAGE446_I137@PURE_QUANTA.Q_RES(CHIPS)':
 C_PATH='@s9s_mb_2u_lib.s9s_mb_2u(sch_1):page446_i137@pure_quanta.q_res(chips)';

PART_NAME
 PR340 'Q_RES_0402LF-0,5%,1/16W,CHIP,CA':;

SECTION_NUMBER 1
 '@S9S_MB_2U_LIB.S9S_MB_2U(SCH_1):PAGE446_I132@PURE_QUANTA.Q_RES(CHIPS)':
 C_PATH='@s9s_mb_2u_lib.s9s_mb_2u(sch_1):page446_i132@pure_quanta.q_res(chips)';

PART_NAME
 PR339 'Q_RES_0402LF-0,5%,1/16W,CHIP,CA':;

SECTION_NUMBER 1
 '@S9S_MB_2U_LIB.S9S_MB_2U(SCH_1):PAGE446_I131@PURE_QUANTA.Q_RES(CHIPS)':
 C_PATH='@s9s_mb_2u_lib.s9s_mb_2u(sch_1):page446_i131@pure_quanta.q_res(chips)';

PART_NAME
 PR338 'Q_RES_0402LF-150,1%,1/16W,CHIPA':;

SECTION_NUMBER 1
 '@S9S_MB_2U_LIB.S9S_MB_2U(SCH_1):PAGE446_I134@PURE_QUANTA.Q_RES(CHIPS)':
 C_PATH='@s9s_mb_2u_lib.s9s_mb_2u(sch_1):page446_i134@pure_quanta.q_res(chips)';

PART_NAME
 PR337 'Q_RES_0402LF-0,5%,1/16W,CHIP,CA':;

SECTION_NUMBER 1
 '@S9S_MB_2U_LIB.S9S_MB_2U(SCH_1):PAGE446_I133@PURE_QUANTA.Q_RES(CHIPS)':
 C_PATH='@s9s_mb_2u_lib.s9s_mb_2u(sch_1):page446_i133@pure_quanta.q_res(chips)';

PART_NAME
 PR336 'Q_RES_0402LF-0,5%,1/16W,CHIP,CA':;

SECTION_NUMBER 1
 '@S9S_MB_2U_LIB.S9S_MB_2U(SCH_1):PAGE446_I141@PURE_QUANTA.Q_RES(CHIPS)':
 C_PATH='@s9s_mb_2u_lib.s9s_mb_2u(sch_1):page446_i141@pure_quanta.q_res(chips)';

PART_NAME
 PR335 'Q_RES_0402LF-1K,1%,1/16W,CHIP,A':;

SECTION_NUMBER 1
 '@S9S_MB_2U_LIB.S9S_MB_2U(SCH_1):PAGE446_I140@PURE_QUANTA.Q_RES(CHIPS)':
 C_PATH='@s9s_mb_2u_lib.s9s_mb_2u(sch_1):page446_i140@pure_quanta.q_res(chips)';

PART_NAME
 PR334 'Q_RES_0402LF-0,5%,1/16W,CHIP,CA':;

SECTION_NUMBER 1
 '@S9S_MB_2U_LIB.S9S_MB_2U(SCH_1):PAGE446_I195@PURE_QUANTA.Q_RES(CHIPS)':
 C_PATH='@s9s_mb_2u_lib.s9s_mb_2u(sch_1):page446_i195@pure_quanta.q_res(chips)';

PART_NAME
 PR333 'Q_RES_0402LF-0,5%,1/16W,CHIP,CA':;

SECTION_NUMBER 1
 '@S9S_MB_2U_LIB.S9S_MB_2U(SCH_1):PAGE446_I194@PURE_QUANTA.Q_RES(CHIPS)':
 C_PATH='@s9s_mb_2u_lib.s9s_mb_2u(sch_1):page446_i194@pure_quanta.q_res(chips)';

PART_NAME
 PR332 'Q_RES_0402LF-2.32K,1%,1/16W,CHA':;

SECTION_NUMBER 1
 '@S9S_MB_2U_LIB.S9S_MB_2U(SCH_1):PAGE446_I197@PURE_QUANTA.Q_RES(CHIPS)':
 C_PATH='@s9s_mb_2u_lib.s9s_mb_2u(sch_1):page446_i197@pure_quanta.q_res(chips)',
 VAR_0_ONSEMI='VALUE|45.3K|TOLERANCE|1%|WATTAGE|1/16W|PACK_TYPE|0402LF|MATERIAL|~
CHIP|PART_NUMBER|TMP_QCS34532FB18|STANDARD|End of Design|LIFECYCLE|Comp-Approve|~
PART_NUMBER|CS34532FB18|JEDEC_TYPE|R0402|ALT_SYMBOLS|(R0402-0201)|VALUE|45.3K|TO~
L|1%|WATTAGE|1/16W|CLASS|DISCRETE|DESCRIPTION|45.3Kohm 0402|COMPONENT_TYPE|CHIP0~
402|LEAD_LENGTH||DFM_EXCLUSION||DAY||VARIANT_DEVICE_TYPE|Q_RES-45.3K,1%,1/16W,04~
02LF,CH',
 CDSVAR_REPCELL_ONSEMI='pure_quanta|Q_res';

PART_NAME
 PR331 'Q_RES_0402LF-28K,1%,1/16W,EMPTA':;

SECTION_NUMBER 1
 '@S9S_MB_2U_LIB.S9S_MB_2U(SCH_1):PAGE446_I198@PURE_QUANTA.Q_RES(CHIPS)':
 C_PATH='@s9s_mb_2u_lib.s9s_mb_2u(sch_1):page446_i198@pure_quanta.q_res(chips)';

PART_NAME
 PJ53 'Q_SHORT_SM-EMPTY,SHORT6':;

SECTION_NUMBER 1
 '@S9S_MB_2U_LIB.S9S_MB_2U(SCH_1):PAGE446_I129@PURE_QUANTA.Q_SHORT(CHIPS)':
 C_PATH='@s9s_mb_2u_lib.s9s_mb_2u(sch_1):page446_i129@pure_quanta.q_short(chips)';

PART_NAME
 PC1195 'Q_CAP_C0402-1UF,16V,10%,X6S,CHA':;

SECTION_NUMBER 1
 '@S9S_MB_2U_LIB.S9S_MB_2U(SCH_1):PAGE446_I173@PURE_QUANTA.Q_CAP(CHIPS)':
 C_PATH='@s9s_mb_2u_lib.s9s_mb_2u(sch_1):page446_i173@pure_quanta.q_cap(chips)';

PART_NAME
 PC599 'Q_CAP_C0402-1UF,16V,10%,X6S,CHA':;

SECTION_NUMBER 1
 '@S9S_MB_2U_LIB.S9S_MB_2U(SCH_1):PAGE446_I175@PURE_QUANTA.Q_CAP(CHIPS)':
 C_PATH='@s9s_mb_2u_lib.s9s_mb_2u(sch_1):page446_i175@pure_quanta.q_cap(chips)';

PART_NAME
 PC598 'Q_CAP_0402-470PF,50V,10%,X7R,TA':;

SECTION_NUMBER 1
 '@S9S_MB_2U_LIB.S9S_MB_2U(SCH_1):PAGE446_I145@PURE_QUANTA.Q_CAP(CHIPS)':
 C_PATH='@s9s_mb_2u_lib.s9s_mb_2u(sch_1):page446_i145@pure_quanta.q_cap(chips)',
 VAR_0_ONSEMI='VALUE|2200PF|VOLTAGE|50V|TOLERANCE|10%|PACK_TYPE|C0402|MATERIAL|X~
7R|PART_NUMBER|CH2226K1B06|STANDARD||LIFECYCLE||ASS_PART||PART_NUMBER|CH2226K1B0~
6|JEDEC_TYPE|C0402|ALT_SYMBOLS|(C0402-0201)|VALUE|2200PF|RATED_VOLTAGE|50V|TOL|1~
0%|CLASS|DISCRETE|DESCRIPTION|CAP CHIP 2200P 50V(+-10%,X7R,0402)MUR|COMPONENT_TY~
PE|CHIP0402|LEAD_LENGTH||LPID||DATE|20150614|VARIANT_DEVICE_TYPE|Q_CAP-2200PF,50~
V,10%,C0402,X7R',
 CDSVAR_REPCELL_ONSEMI='pure_quanta|Q_cap';

PART_NAME
 PC597 'Q_CAP_0402-4.7UF,6.3V,20%,X6S,A':;

SECTION_NUMBER 1
 '@S9S_MB_2U_LIB.S9S_MB_2U(SCH_1):PAGE446_I172@PURE_QUANTA.Q_CAP(CHIPS)':
 C_PATH='@s9s_mb_2u_lib.s9s_mb_2u(sch_1):page446_i172@pure_quanta.q_cap(chips)',
 VAR_0_ONSEMI='VALUE|4.7UF|VOLTAGE|6.3V|TOLERANCE|20%|PACK_TYPE|0402|MATERIAL|EM~
PTY|PART_NUMBER|CH5471MEB01|STANDARD||LIFECYCLE||ASS_PART||PART_NUMBER|CH5471MEB~
01|JEDEC_TYPE|C0402|ALT_SYMBOLS|(C0402_OCTAGON,C0402_OCTAGONXA,C0402-0201)|VALUE~
|NA|RATED_VOLTAGE|6.3V|TOL|20%|CLASS|IO|DESCRIPTION|CAP CHIP 4.7UF 6.3V(+-20%,X6~
S,0402)|COMPONENT_TYPE|CHIP0402|LEAD_LENGTH||LPID||DATE|20151211|VARIANT_DEVICE_~
TYPE|Q_CAP-4.7UF,6.3V,20%,0402,EMPT',
 CDSVAR_REPCELL_ONSEMI='pure_quanta|Q_cap';

PART_NAME
 PC596 'Q_CAP_C0402-100NF,50V,10%,EMPTA':;

SECTION_NUMBER 1
 '@S9S_MB_2U_LIB.S9S_MB_2U(SCH_1):PAGE446_I174@PURE_QUANTA.Q_CAP(CHIPS)':
 C_PATH='@s9s_mb_2u_lib.s9s_mb_2u(sch_1):page446_i174@pure_quanta.q_cap(chips)';

PART_NAME
 PC595 'Q_CAP_C0402-1UF,16V,10%,X6S,CHA':;

SECTION_NUMBER 1
 '@S9S_MB_2U_LIB.S9S_MB_2U(SCH_1):PAGE446_I189@PURE_QUANTA.Q_CAP(CHIPS)':
 C_PATH='@s9s_mb_2u_lib.s9s_mb_2u(sch_1):page446_i189@pure_quanta.q_cap(chips)';

PART_NAME
 PC594 'Q_CAP_0402-3300PF,50V,10%,X7R,A':;

SECTION_NUMBER 1
 '@S9S_MB_2U_LIB.S9S_MB_2U(SCH_1):PAGE446_I123@PURE_QUANTA.Q_CAP(CHIPS)':
 C_PATH='@s9s_mb_2u_lib.s9s_mb_2u(sch_1):page446_i123@pure_quanta.q_cap(chips)',
 VAR_0_ONSEMI='VALUE|1NF|VOLTAGE|50V|TOLERANCE|10%|PACK_TYPE|0402|MATERIAL|X7R|P~
ART_NUMBER|CH21006KB16|STANDARD||LIFECYCLE||ASS_PART||PART_NUMBER|CH21006KB16|JE~
DEC_TYPE|C0402|ALT_SYMBOLS|(C0402-0201)|VALUE|1NF|RATED_VOLTAGE|50V|TOL|10%|CLAS~
S|DISCRETE|DESCRIPTION|CAP CHIP 1N 50V(+-10%,X7R,0402)EP|COMPONENT_TYPE|CHIP0402~
|LEAD_LENGTH||LPID||DATE|20100811|VARIANT_DEVICE_TYPE|Q_CAP-1NF,50V,10%,0402,X7R~
,CH2',
 CDSVAR_REPCELL_ONSEMI='pure_quanta|Q_cap';

PART_NAME
 PC593 'Q_CAP_0402-1000PF,50V,5%,EMPTYA':;

SECTION_NUMBER 1
 '@S9S_MB_2U_LIB.S9S_MB_2U(SCH_1):PAGE446_I142@PURE_QUANTA.Q_CAP(CHIPS)':
 C_PATH='@s9s_mb_2u_lib.s9s_mb_2u(sch_1):page446_i142@pure_quanta.q_cap(chips)';

PART_NAME
 PC592 'Q_CAP_0402-0.01UF,25V,10%,X7R,A':;

SECTION_NUMBER 1
 '@S9S_MB_2U_LIB.S9S_MB_2U(SCH_1):PAGE446_I138@PURE_QUANTA.Q_CAP(CHIPS)':
 C_PATH='@s9s_mb_2u_lib.s9s_mb_2u(sch_1):page446_i138@pure_quanta.q_cap(chips)';

PART_NAME
 PC591 'Q_CAP_C0402-1UF,16V,10%,X6S,CHA':;

SECTION_NUMBER 1
 '@S9S_MB_2U_LIB.S9S_MB_2U(SCH_1):PAGE446_I192@PURE_QUANTA.Q_CAP(CHIPS)':
 C_PATH='@s9s_mb_2u_lib.s9s_mb_2u(sch_1):page446_i192@pure_quanta.q_cap(chips)';

PART_NAME
 PU29 'ISL69260IRAZT-ISL69260IRAZ-T,SA':;

SECTION_NUMBER 1
 '@S9S_MB_2U_LIB.S9S_MB_2U(SCH_1):PAGE433_I172@PURE_QUANTA.ISL69260IRAZT(CHIPS)':
 C_PATH='@s9s_mb_2u_lib.s9s_mb_2u(sch_1):page433_i172@pure_quanta.isl69260irazt(ch~
ips)',
 CDSVAR_REPCELL_ONSEMI='pure_quanta|fd5001',
 VAR_0_ONSEMI='VAR_REPLACED|ISL69260IRAZT|VAR_PARTNAME|FD5001|VALUE|FD5001|PART_~
TYPE|SMLF|MATERIAL|IC|PART_NUMBER|AL005001004|STANDARD||LIFECYCLE||PART_NUMBER|A~
L005001004|JEDEC_TYPE|VFQFPN40_TH_0-4_5X5XC|DESCRIPTION|IC OTHER(40P) FD5001(QFN~
)|MANUFTR|ONS|MANUF_PN|FD5001|RD_CMPLS_LVL|EP(V1)|CMPLS_LVL||FROM_PJ|S9S-KIMI|CL~
ASS|IC|DIP_SMD||DATA|ONS_FD5001.pdf|EE_CHECK_LIST||FP_ECN|FD5001.msg|PSL||CREATO~
R||STATUS||MSD|NA|ESD_CDM|NA|ESD_HBM|NA|ESD_MM|NA|PIN_LENGTH_SHORT_PIN|0 MILS|PI~
N_LENGTH_LONG_PIN|0 MILS|CREATEDAY|20200421|VARIANT_DEVICE_TYPE|FD5001-FD5001,SM~
LF,IC,AL005001';

PART_NAME
 PR578 'Q_RES_0402LF-100,1%,1/16W,CHIPA':;

SECTION_NUMBER 1
 '@S9S_MB_2U_LIB.S9S_MB_2U(SCH_1):PAGE433_I138@PURE_QUANTA.Q_RES(CHIPS)':
 C_PATH='@s9s_mb_2u_lib.s9s_mb_2u(sch_1):page433_i138@pure_quanta.q_res(chips)';

PART_NAME
 PR577 'Q_RES_0402LF-49.9     ,1%  ,1/B':;

SECTION_NUMBER 1
 '@S9S_MB_2U_LIB.S9S_MB_2U(SCH_1):PAGE433_I147@PURE_QUANTA.Q_RES(CHIPS)':
 C_PATH='@s9s_mb_2u_lib.s9s_mb_2u(sch_1):page433_i147@pure_quanta.q_res(chips)';

PART_NAME
 PR576 'Q_RES_0402LF-49.9     ,1%  ,1/A':;

SECTION_NUMBER 1
 '@S9S_MB_2U_LIB.S9S_MB_2U(SCH_1):PAGE433_I141@PURE_QUANTA.Q_RES(CHIPS)':
 C_PATH='@s9s_mb_2u_lib.s9s_mb_2u(sch_1):page433_i141@pure_quanta.q_res(chips)';

PART_NAME
 PR575 'Q_RES_0402LF-100,1%,1/16W,CHIPA':;

SECTION_NUMBER 1
 '@S9S_MB_2U_LIB.S9S_MB_2U(SCH_1):PAGE433_I143@PURE_QUANTA.Q_RES(CHIPS)':
 C_PATH='@s9s_mb_2u_lib.s9s_mb_2u(sch_1):page433_i143@pure_quanta.q_res(chips)';

PART_NAME
 PR574 'Q_RES_0402LF-100,1%,1/16W,CHIPA':;

SECTION_NUMBER 1
 '@S9S_MB_2U_LIB.S9S_MB_2U(SCH_1):PAGE433_I136@PURE_QUANTA.Q_RES(CHIPS)':
 C_PATH='@s9s_mb_2u_lib.s9s_mb_2u(sch_1):page433_i136@pure_quanta.q_res(chips)';

PART_NAME
 PR324 'Q_RES_0402LF-1K,1%,1/16W,CHIP,A':;

SECTION_NUMBER 1
 '@S9S_MB_2U_LIB.S9S_MB_2U(SCH_1):PAGE433_I82@PURE_QUANTA.Q_RES(CHIPS)':
 C_PATH='@s9s_mb_2u_lib.s9s_mb_2u(sch_1):page433_i82@pure_quanta.q_res(chips)';

PART_NAME
 PR323 'Q_RES_0402LF-1,1%,1/16W,CHIP,CA':;

SECTION_NUMBER 1
 '@S9S_MB_2U_LIB.S9S_MB_2U(SCH_1):PAGE433_I100@PURE_QUANTA.Q_RES(CHIPS)':
 C_PATH='@s9s_mb_2u_lib.s9s_mb_2u(sch_1):page433_i100@pure_quanta.q_res(chips)';

PART_NAME
 PR321 'Q_RES_0402LF-0,5%,1/16W,CHIP,CA':;

SECTION_NUMBER 1
 '@S9S_MB_2U_LIB.S9S_MB_2U(SCH_1):PAGE433_I171@PURE_QUANTA.Q_RES(CHIPS)':
 C_PATH='@s9s_mb_2u_lib.s9s_mb_2u(sch_1):page433_i171@pure_quanta.q_res(chips)';

PART_NAME
 PR319 'Q_RES_0402LF-1K,1%,1/16W,CHIP,A':;

SECTION_NUMBER 1
 '@S9S_MB_2U_LIB.S9S_MB_2U(SCH_1):PAGE433_I35@PURE_QUANTA.Q_RES(CHIPS)':
 C_PATH='@s9s_mb_2u_lib.s9s_mb_2u(sch_1):page433_i35@pure_quanta.q_res(chips)';

PART_NAME
 PR318 'Q_RES_0402LF-5.23K,1%,1/16W,CHA':;

SECTION_NUMBER 1
 '@S9S_MB_2U_LIB.S9S_MB_2U(SCH_1):PAGE433_I26@PURE_QUANTA.Q_RES(CHIPS)':
 C_PATH='@s9s_mb_2u_lib.s9s_mb_2u(sch_1):page433_i26@pure_quanta.q_res(chips)',
 CDSVAR_REPCELL_ONSEMI='pure_quanta|Q_res',
 VAR_0_ONSEMI='VALUE|7.32K|TOLERANCE|1%|WATTAGE|1/16W|PACK_TYPE|0402LF|MATERIAL|~
CHIP|PART_NUMBER|TMP_QCS27322FB12|STANDARD|End of Design|LIFECYCLE|Comp-Approve|~
PART_NUMBER|CS27322FB12|JEDEC_TYPE|R0402|ALT_SYMBOLS|(R0402-0201)|VALUE|7.32K|TO~
L|1%|WATTAGE|1/16W|CLASS|DISCRETE|DESCRIPTION|7.32Kohm 0402|COMPONENT_TYPE|CHIP0~
402|LEAD_LENGTH||DFM_EXCLUSION||DAY||VARIANT_DEVICE_TYPE|Q_RES-7.32K,1%,1/16W,04~
02LF,CH';

PART_NAME
 PR317 'Q_RES_0402LF-0,5%,1/16W,CHIP,CA':;

SECTION_NUMBER 1
 '@S9S_MB_2U_LIB.S9S_MB_2U(SCH_1):PAGE433_I134@PURE_QUANTA.Q_RES(CHIPS)':
 C_PATH='@s9s_mb_2u_lib.s9s_mb_2u(sch_1):page433_i134@pure_quanta.q_res(chips)';

PART_NAME
 PR316 'Q_RES_0402LF-1K,1%,1/16W,CHIP,A':;

SECTION_NUMBER 1
 '@S9S_MB_2U_LIB.S9S_MB_2U(SCH_1):PAGE433_I34@PURE_QUANTA.Q_RES(CHIPS)':
 C_PATH='@s9s_mb_2u_lib.s9s_mb_2u(sch_1):page433_i34@pure_quanta.q_res(chips)';

PART_NAME
 PR315 'Q_RES_0402LF-33.2,1%,1/16W,CHIA':;

SECTION_NUMBER 1
 '@S9S_MB_2U_LIB.S9S_MB_2U(SCH_1):PAGE433_I133@PURE_QUANTA.Q_RES(CHIPS)':
 C_PATH='@s9s_mb_2u_lib.s9s_mb_2u(sch_1):page433_i133@pure_quanta.q_res(chips)';

PART_NAME
 PR314 'Q_RES_0402LF-0,5%,1/16W,CHIP,CA':;

SECTION_NUMBER 1
 '@S9S_MB_2U_LIB.S9S_MB_2U(SCH_1):PAGE433_I132@PURE_QUANTA.Q_RES(CHIPS)':
 C_PATH='@s9s_mb_2u_lib.s9s_mb_2u(sch_1):page433_i132@pure_quanta.q_res(chips)';

PART_NAME
 PR313 'Q_RES_0402LF-1K,1%,1/16W,EMPTYA':;

SECTION_NUMBER 1
 '@S9S_MB_2U_LIB.S9S_MB_2U(SCH_1):PAGE433_I37@PURE_QUANTA.Q_RES(CHIPS)':
 C_PATH='@s9s_mb_2u_lib.s9s_mb_2u(sch_1):page433_i37@pure_quanta.q_res(chips)';

PART_NAME
 PR312 'Q_RES_0402LF-0,5%,1/16W,CHIP,CA':;

SECTION_NUMBER 1
 '@S9S_MB_2U_LIB.S9S_MB_2U(SCH_1):PAGE433_I121@PURE_QUANTA.Q_RES(CHIPS)':
 C_PATH='@s9s_mb_2u_lib.s9s_mb_2u(sch_1):page433_i121@pure_quanta.q_res(chips)';

PART_NAME
 PR311 'Q_RES_0402LF-0,5%,1/16W,CHIP,CA':;

SECTION_NUMBER 1
 '@S9S_MB_2U_LIB.S9S_MB_2U(SCH_1):PAGE433_I120@PURE_QUANTA.Q_RES(CHIPS)':
 C_PATH='@s9s_mb_2u_lib.s9s_mb_2u(sch_1):page433_i120@pure_quanta.q_res(chips)';

PART_NAME
 PR310 'Q_RES_0402LF-150,1%,1/16W,CHIPA':;

SECTION_NUMBER 1
 '@S9S_MB_2U_LIB.S9S_MB_2U(SCH_1):PAGE433_I52@PURE_QUANTA.Q_RES(CHIPS)':
 C_PATH='@s9s_mb_2u_lib.s9s_mb_2u(sch_1):page433_i52@pure_quanta.q_res(chips)';

PART_NAME
 PR309 'Q_RES_0402LF-0,5%,1/16W,CHIP,CA':;

SECTION_NUMBER 1
 '@S9S_MB_2U_LIB.S9S_MB_2U(SCH_1):PAGE433_I122@PURE_QUANTA.Q_RES(CHIPS)':
 C_PATH='@s9s_mb_2u_lib.s9s_mb_2u(sch_1):page433_i122@pure_quanta.q_res(chips)';

PART_NAME
 PR308 'Q_RES_0402LF-0,5%,1/16W,CHIP,CA':;

SECTION_NUMBER 1
 '@S9S_MB_2U_LIB.S9S_MB_2U(SCH_1):PAGE433_I123@PURE_QUANTA.Q_RES(CHIPS)':
 C_PATH='@s9s_mb_2u_lib.s9s_mb_2u(sch_1):page433_i123@pure_quanta.q_res(chips)';

PART_NAME
 PR307 'Q_RES_0402LF-1K,1%,1/16W,CHIP,A':;

SECTION_NUMBER 1
 '@S9S_MB_2U_LIB.S9S_MB_2U(SCH_1):PAGE433_I126@PURE_QUANTA.Q_RES(CHIPS)':
 C_PATH='@s9s_mb_2u_lib.s9s_mb_2u(sch_1):page433_i126@pure_quanta.q_res(chips)';

PART_NAME
 PR306 'Q_RES_0402LF-28K,1%,1/16W,EMPTA':;

SECTION_NUMBER 1
 '@S9S_MB_2U_LIB.S9S_MB_2U(SCH_1):PAGE433_I25@PURE_QUANTA.Q_RES(CHIPS)':
 C_PATH='@s9s_mb_2u_lib.s9s_mb_2u(sch_1):page433_i25@pure_quanta.q_res(chips)';

PART_NAME
 PR305 'Q_RES_0402LF-1K,1%,1/16W,EMPTYA':;

SECTION_NUMBER 1
 '@S9S_MB_2U_LIB.S9S_MB_2U(SCH_1):PAGE433_I1@PURE_QUANTA.Q_RES(CHIPS)':
 C_PATH='@s9s_mb_2u_lib.s9s_mb_2u(sch_1):page433_i1@pure_quanta.q_res(chips)';

PART_NAME
 PR304 'Q_RES_0402LF-0,5%,1/16W,CHIP,CA':;

SECTION_NUMBER 1
 '@S9S_MB_2U_LIB.S9S_MB_2U(SCH_1):PAGE433_I153@PURE_QUANTA.Q_RES(CHIPS)':
 C_PATH='@s9s_mb_2u_lib.s9s_mb_2u(sch_1):page433_i153@pure_quanta.q_res(chips)';

PART_NAME
 PR303 'Q_RES_0402LF-0,5%,1/16W,CHIP,CA':;

SECTION_NUMBER 1
 '@S9S_MB_2U_LIB.S9S_MB_2U(SCH_1):PAGE433_I154@PURE_QUANTA.Q_RES(CHIPS)':
 C_PATH='@s9s_mb_2u_lib.s9s_mb_2u(sch_1):page433_i154@pure_quanta.q_res(chips)';

PART_NAME
 PJ52 'Q_SHORT_SM-EMPTY,SHORT6':;

SECTION_NUMBER 1
 '@S9S_MB_2U_LIB.S9S_MB_2U(SCH_1):PAGE433_I33@PURE_QUANTA.Q_SHORT(CHIPS)':
 C_PATH='@s9s_mb_2u_lib.s9s_mb_2u(sch_1):page433_i33@pure_quanta.q_short(chips)';

PART_NAME
 PC1194 'Q_CAP_C0402-1UF,16V,10%,X6S,CHA':;

SECTION_NUMBER 1
 '@S9S_MB_2U_LIB.S9S_MB_2U(SCH_1):PAGE433_I115@PURE_QUANTA.Q_CAP(CHIPS)':
 C_PATH='@s9s_mb_2u_lib.s9s_mb_2u(sch_1):page433_i115@pure_quanta.q_cap(chips)';

PART_NAME
 PC555 'Q_CAP_C0402-1UF,16V,10%,X6S,CHA':;

SECTION_NUMBER 1
 '@S9S_MB_2U_LIB.S9S_MB_2U(SCH_1):PAGE433_I96@PURE_QUANTA.Q_CAP(CHIPS)':
 C_PATH='@s9s_mb_2u_lib.s9s_mb_2u(sch_1):page433_i96@pure_quanta.q_cap(chips)';

PART_NAME
 PC554 'Q_CAP_0402-470PF,50V,10%,X7R,TA':;

SECTION_NUMBER 1
 '@S9S_MB_2U_LIB.S9S_MB_2U(SCH_1):PAGE433_I61@PURE_QUANTA.Q_CAP(CHIPS)':
 C_PATH='@s9s_mb_2u_lib.s9s_mb_2u(sch_1):page433_i61@pure_quanta.q_cap(chips)',
 CDSVAR_REPCELL_ONSEMI='pure_quanta|Q_cap',
 VAR_0_ONSEMI='VALUE|2200PF|VOLTAGE|50V|TOLERANCE|10%|PACK_TYPE|C0402|MATERIAL|X~
7R|PART_NUMBER|CH2226K1B06|STANDARD||LIFECYCLE||ASS_PART||PART_NUMBER|CH2226K1B0~
6|JEDEC_TYPE|C0402|ALT_SYMBOLS|(C0402-0201)|VALUE|2200PF|RATED_VOLTAGE|50V|TOL|1~
0%|CLASS|DISCRETE|DESCRIPTION|CAP CHIP 2200P 50V(+-10%,X7R,0402)MUR|COMPONENT_TY~
PE|CHIP0402|LEAD_LENGTH||LPID||DATE|20150614|VARIANT_DEVICE_TYPE|Q_CAP-2200PF,50~
V,10%,C0402,X7R';

PART_NAME
 PC553 'Q_CAP_0402-4.7UF,6.3V,20%,X6S,A':;

SECTION_NUMBER 1
 '@S9S_MB_2U_LIB.S9S_MB_2U(SCH_1):PAGE433_I116@PURE_QUANTA.Q_CAP(CHIPS)':
 C_PATH='@s9s_mb_2u_lib.s9s_mb_2u(sch_1):page433_i116@pure_quanta.q_cap(chips)',
 CDSVAR_REPCELL_ONSEMI='pure_quanta|Q_cap',
 VAR_0_ONSEMI='VALUE|4.7UF|VOLTAGE|6.3V|TOLERANCE|20%|PACK_TYPE|0402|MATERIAL|EM~
PTY|PART_NUMBER|CH5471MEB01|STANDARD||LIFECYCLE||ASS_PART||PART_NUMBER|CH5471MEB~
01|JEDEC_TYPE|C0402|ALT_SYMBOLS|(C0402_OCTAGON,C0402_OCTAGONXA,C0402-0201)|VALUE~
|NA|RATED_VOLTAGE|6.3V|TOL|20%|CLASS|IO|DESCRIPTION|CAP CHIP 4.7UF 6.3V(+-20%,X6~
S,0402)|COMPONENT_TYPE|CHIP0402|LEAD_LENGTH||LPID||DATE|20151211|VARIANT_DEVICE_~
TYPE|Q_CAP-4.7UF,6.3V,20%,0402,EMPT';

PART_NAME
 PC552 'Q_CAP_C0402-100NF,50V,10%,EMPTA':;

SECTION_NUMBER 1
 '@S9S_MB_2U_LIB.S9S_MB_2U(SCH_1):PAGE433_I94@PURE_QUANTA.Q_CAP(CHIPS)':
 C_PATH='@s9s_mb_2u_lib.s9s_mb_2u(sch_1):page433_i94@pure_quanta.q_cap(chips)';

PART_NAME
 PC551 'Q_CAP_0402-1000PF,50V,5%,EMPTYA':;

SECTION_NUMBER 1
 '@S9S_MB_2U_LIB.S9S_MB_2U(SCH_1):PAGE433_I130@PURE_QUANTA.Q_CAP(CHIPS)':
 C_PATH='@s9s_mb_2u_lib.s9s_mb_2u(sch_1):page433_i130@pure_quanta.q_cap(chips)';

PART_NAME
 PC550 'Q_CAP_0402-1000PF,50V,5%,X7R,TA':;

SECTION_NUMBER 1
 '@S9S_MB_2U_LIB.S9S_MB_2U(SCH_1):PAGE433_I128@PURE_QUANTA.Q_CAP(CHIPS)':
 C_PATH='@s9s_mb_2u_lib.s9s_mb_2u(sch_1):page433_i128@pure_quanta.q_cap(chips)';

PART_NAME
 PC549 'Q_CAP_0402-3300PF,50V,10%,X7R,A':;

SECTION_NUMBER 1
 '@S9S_MB_2U_LIB.S9S_MB_2U(SCH_1):PAGE433_I43@PURE_QUANTA.Q_CAP(CHIPS)':
 C_PATH='@s9s_mb_2u_lib.s9s_mb_2u(sch_1):page433_i43@pure_quanta.q_cap(chips)',
 CDSVAR_REPCELL_ONSEMI='pure_quanta|Q_cap',
 VAR_0_ONSEMI='VALUE|1NF|VOLTAGE|50V|TOLERANCE|10%|PACK_TYPE|0402|MATERIAL|X7R|P~
ART_NUMBER|CH21006KB16|STANDARD||LIFECYCLE||ASS_PART||PART_NUMBER|CH21006KB16|JE~
DEC_TYPE|C0402|ALT_SYMBOLS|(C0402-0201)|VALUE|1NF|RATED_VOLTAGE|50V|TOL|10%|CLAS~
S|DISCRETE|DESCRIPTION|CAP CHIP 1N 50V(+-10%,X7R,0402)EP|COMPONENT_TYPE|CHIP0402~
|LEAD_LENGTH||LPID||DATE|20100811|VARIANT_DEVICE_TYPE|Q_CAP-1NF,50V,10%,0402,X7R~
,CH2';

PART_NAME
 PC548 'Q_CAP_C0402-1UF,16V,10%,X6S,CHA':;

SECTION_NUMBER 1
 '@S9S_MB_2U_LIB.S9S_MB_2U(SCH_1):PAGE433_I38@PURE_QUANTA.Q_CAP(CHIPS)':
 C_PATH='@s9s_mb_2u_lib.s9s_mb_2u(sch_1):page433_i38@pure_quanta.q_cap(chips)';

PART_NAME
 PC547 'Q_CAP_C0402-1UF,16V,10%,X6S,CHA':;

SECTION_NUMBER 1
 '@S9S_MB_2U_LIB.S9S_MB_2U(SCH_1):PAGE433_I20@PURE_QUANTA.Q_CAP(CHIPS)':
 C_PATH='@s9s_mb_2u_lib.s9s_mb_2u(sch_1):page433_i20@pure_quanta.q_cap(chips)';

PART_NAME
 PC546 'Q_CAP_C0402-100NF,50V,10%,X7R,A':;

SECTION_NUMBER 1
 '@S9S_MB_2U_LIB.S9S_MB_2U(SCH_1):PAGE433_I151@PURE_QUANTA.Q_CAP(CHIPS)':
 C_PATH='@s9s_mb_2u_lib.s9s_mb_2u(sch_1):page433_i151@pure_quanta.q_cap(chips)';

PART_NAME
 PC545 'Q_CAP_C0603-10UF,4V,20%,EMPTY,A':;

SECTION_NUMBER 1
 '@S9S_MB_2U_LIB.S9S_MB_2U(SCH_1):PAGE433_I150@PURE_QUANTA.Q_CAP(CHIPS)':
 C_PATH='@s9s_mb_2u_lib.s9s_mb_2u(sch_1):page433_i150@pure_quanta.q_cap(chips)';

PART_NAME
 PU28_P1_3 'ISL99390FRZTR5935-ISL99390FRZ-A':;

SECTION_NUMBER 1
 '@S9S_MB_2U_LIB.S9S_MB_2U(SCH_1):PAGE587_I96@PURE_QUANTA.ISL99390FRZTR5935(CHIPS)':
 C_PATH='@s9s_mb_2u_lib.s9s_mb_2u(sch_1):page587_i96@pure_quanta.isl99390frztr5935~
(chips)',
 VAR_0_ONSEMI='VAR_REPLACED|ISL99390FRZTR5935|VAR_PARTNAME|FDMF5085|VALUE|FDMF50~
85|PART_TYPE|SMLF|MATERIAL|IC|PART_NUMBER|AL005085000|STANDARD||LIFECYCLE||PART_~
NUMBER|AL005085000|JEDEC_TYPE|PQFN21_6X5XB|DESCRIPTION|IC OTHER(39P) FDMF5085(PQ~
FN)|MANUFTR|ONS|MANUF_PN|FDMF5085|RD_CMPLS_LVL|EP(V1)|CMPLS_LVL||FROM_PJ|S9S-KIM~
I|CLASS|IC|DIP_SMD||DATA|ONS_FDMF5085.pdf|EE_CHECK_LIST||FP_ECN||PSL||CREATOR||S~
TATUS||MSD|NA|ESD_CDM|NA|ESD_HBM|NA|ESD_MM|NA|PIN_LENGTH_SHORT_PIN|0 MILS|PIN_LE~
NGTH_LONG_PIN|0 MILS|CREATEDAY|20200423|VARIANT_DEVICE_TYPE|FDMF5085-FDMF5085,SM~
LF,IC,AL00',
 CDSVAR_REPCELL_ONSEMI='pure_quanta|fdmf5085';

PART_NAME
 PU27_P1_4 'ISL99390FRZTR5935-ISL99390FRZ-A':;

SECTION_NUMBER 1
 '@S9S_MB_2U_LIB.S9S_MB_2U(SCH_1):PAGE587_I21@PURE_QUANTA.ISL99390FRZTR5935(CHIPS)':
 C_PATH='@s9s_mb_2u_lib.s9s_mb_2u(sch_1):page587_i21@pure_quanta.isl99390frztr5935~
(chips)',
 VAR_0_ONSEMI='VAR_REPLACED|ISL99390FRZTR5935|VAR_PARTNAME|FDMF5085|VALUE|FDMF50~
85|PART_TYPE|SMLF|MATERIAL|IC|PART_NUMBER|AL005085000|STANDARD||LIFECYCLE||PART_~
NUMBER|AL005085000|JEDEC_TYPE|PQFN21_6X5XB|DESCRIPTION|IC OTHER(39P) FDMF5085(PQ~
FN)|MANUFTR|ONS|MANUF_PN|FDMF5085|RD_CMPLS_LVL|EP(V1)|CMPLS_LVL||FROM_PJ|S9S-KIM~
I|CLASS|IC|DIP_SMD||DATA|ONS_FDMF5085.pdf|EE_CHECK_LIST||FP_ECN||PSL||CREATOR||S~
TATUS||MSD|NA|ESD_CDM|NA|ESD_HBM|NA|ESD_MM|NA|PIN_LENGTH_SHORT_PIN|0 MILS|PIN_LE~
NGTH_LONG_PIN|0 MILS|CREATEDAY|20200423|VARIANT_DEVICE_TYPE|FDMF5085-FDMF5085,SM~
LF,IC,AL00',
 CDSVAR_REPCELL_ONSEMI='pure_quanta|fdmf5085';

PART_NAME
 PR1789 'Q_RES_0402LF-3.3,1%,1/16W,CHIPA':;

SECTION_NUMBER 1
 '@S9S_MB_2U_LIB.S9S_MB_2U(SCH_1):PAGE587_I84@PURE_QUANTA.Q_RES(CHIPS)':
 C_PATH='@s9s_mb_2u_lib.s9s_mb_2u(sch_1):page587_i84@pure_quanta.q_res(chips)',
 CDSVAR_REPCELL_ONSEMI='pure_quanta|Q_res',
 VAR_0_ONSEMI='VALUE|5.1|TOLERANCE|5%|WATTAGE|1/16W|PACK_TYPE|0402LF|MATERIAL|CH~
IP|PART_NUMBER|CS-5102JB03|STANDARD|End of Design|LIFECYCLE|Comp-Approve|PART_NU~
MBER|CS-5102JB03|JEDEC_TYPE|R0402|ALT_SYMBOLS|(R0402-0201)|VALUE|5.1|TOL|5%|WATT~
AGE|1/16W |CLASS|DISCRETE|DESCRIPTION|RES CHIP 5.1 1/16W +-5%(0402)|COMPONENT_TY~
PE|CHIP0402|LEAD_LENGTH||DFM_EXCLUSION||DAY|20100827|VARIANT_DEVICE_TYPE|Q_RES-5~
.1,5%,1/16W,0402LF,CHIP';

PART_NAME
 PR1788 'Q_RES_0402LF-3.3,1%,1/16W,CHIPA':;

SECTION_NUMBER 1
 '@S9S_MB_2U_LIB.S9S_MB_2U(SCH_1):PAGE587_I86@PURE_QUANTA.Q_RES(CHIPS)':
 C_PATH='@s9s_mb_2u_lib.s9s_mb_2u(sch_1):page587_i86@pure_quanta.q_res(chips)',
 CDSVAR_REPCELL_ONSEMI='pure_quanta|Q_res',
 VAR_0_ONSEMI='VALUE|5.1|TOLERANCE|5%|WATTAGE|1/16W|PACK_TYPE|0402LF|MATERIAL|CH~
IP|PART_NUMBER|CS-5102JB03|STANDARD|End of Design|LIFECYCLE|Comp-Approve|PART_NU~
MBER|CS-5102JB03|JEDEC_TYPE|R0402|ALT_SYMBOLS|(R0402-0201)|VALUE|5.1|TOL|5%|WATT~
AGE|1/16W |CLASS|DISCRETE|DESCRIPTION|RES CHIP 5.1 1/16W +-5%(0402)|COMPONENT_TY~
PE|CHIP0402|LEAD_LENGTH||DFM_EXCLUSION||DAY|20100827|VARIANT_DEVICE_TYPE|Q_RES-5~
.1,5%,1/16W,0402LF,CHIP';

PART_NAME
 PR302 'Q_RES_0402LF-0,5%,1/16W,CHIP,CA':;

SECTION_NUMBER 1
 '@S9S_MB_2U_LIB.S9S_MB_2U(SCH_1):PAGE587_I95@PURE_QUANTA.Q_RES(CHIPS)':
 C_PATH='@s9s_mb_2u_lib.s9s_mb_2u(sch_1):page587_i95@pure_quanta.q_res(chips)',
 CDSVAR_REPCELL_ONSEMI='pure_quanta|Q_res',
 VAR_0_ONSEMI='VALUE|0|TOLERANCE|5%|WATTAGE|1/16W|PACK_TYPE|0402LF|MATERIAL|EMPT~
Y|PART_NUMBER|CS00002JB38|STANDARD|End of Design|LIFECYCLE|Comp-Approve|PART_NUM~
BER|CS00002JB38|JEDEC_TYPE|R0402|ALT_SYMBOLS|(R0402-0201)|VALUE|0|TOL|5%|WATTAGE~
|1/16W|CLASS|IO|DESCRIPTION|RESISTOR CHIP 0 1/16W +-5%(0402)|COMPONENT_TYPE|CHIP~
0402|LEAD_LENGTH||DFM_EXCLUSION||DAY|20100618|VARIANT_DEVICE_TYPE|Q_RES-0,5%,1/1~
6W,0402LF,EMPTY,';

PART_NAME
 PR301 'Q_RES_0402LF-0,5%,1/16W,CHIP,CA':;

SECTION_NUMBER 1
 '@S9S_MB_2U_LIB.S9S_MB_2U(SCH_1):PAGE587_I94@PURE_QUANTA.Q_RES(CHIPS)':
 C_PATH='@s9s_mb_2u_lib.s9s_mb_2u(sch_1):page587_i94@pure_quanta.q_res(chips)',
 CDSVAR_REPCELL_ONSEMI='pure_quanta|Q_res',
 VAR_0_ONSEMI='VALUE|0|TOLERANCE|5%|WATTAGE|1/16W|PACK_TYPE|0402LF|MATERIAL|EMPT~
Y|PART_NUMBER|CS00002JB38|STANDARD|End of Design|LIFECYCLE|Comp-Approve|PART_NUM~
BER|CS00002JB38|JEDEC_TYPE|R0402|ALT_SYMBOLS|(R0402-0201)|VALUE|0|TOL|5%|WATTAGE~
|1/16W|CLASS|IO|DESCRIPTION|RESISTOR CHIP 0 1/16W +-5%(0402)|COMPONENT_TYPE|CHIP~
0402|LEAD_LENGTH||DFM_EXCLUSION||DAY|20100618|VARIANT_DEVICE_TYPE|Q_RES-0,5%,1/1~
6W,0402LF,EMPTY,';

PART_NAME
 PR300 'Q_RES_0402LF-2.2,1%,1/16W,CHIPA':;

SECTION_NUMBER 1
 '@S9S_MB_2U_LIB.S9S_MB_2U(SCH_1):PAGE587_I19@PURE_QUANTA.Q_RES(CHIPS)':
 C_PATH='@s9s_mb_2u_lib.s9s_mb_2u(sch_1):page587_i19@pure_quanta.q_res(chips)';

PART_NAME
 PR299 'Q_RES_0402LF-2.2,1%,1/16W,CHIPA':;

SECTION_NUMBER 1
 '@S9S_MB_2U_LIB.S9S_MB_2U(SCH_1):PAGE587_I9@PURE_QUANTA.Q_RES(CHIPS)':
 C_PATH='@s9s_mb_2u_lib.s9s_mb_2u(sch_1):page587_i9@pure_quanta.q_res(chips)';

PART_NAME
 PR298 'Q_RES_0402LF-8.87K,1%,1/16W,EMA':;

SECTION_NUMBER 1
 '@S9S_MB_2U_LIB.S9S_MB_2U(SCH_1):PAGE587_I12@PURE_QUANTA.Q_RES(CHIPS)':
 C_PATH='@s9s_mb_2u_lib.s9s_mb_2u(sch_1):page587_i12@pure_quanta.q_res(chips)';

PART_NAME
 PR297 'Q_RES_0402LF-8.87K,1%,1/16W,EMA':;

SECTION_NUMBER 1
 '@S9S_MB_2U_LIB.S9S_MB_2U(SCH_1):PAGE587_I2@PURE_QUANTA.Q_RES(CHIPS)':
 C_PATH='@s9s_mb_2u_lib.s9s_mb_2u(sch_1):page587_i2@pure_quanta.q_res(chips)';

PART_NAME
 PL29 'Q_INDUCTOR_SMLF-130NH/106A,INDA':;

SECTION_NUMBER 1
 '@S9S_MB_2U_LIB.S9S_MB_2U(SCH_1):PAGE587_I42@PURE_QUANTA.Q_INDUCTOR(CHIPS)':
 C_PATH='@s9s_mb_a_lib.s9s_mb_a(sch_1):page587_i42@pure_quanta.q_inductor(chips)~
';

PART_NAME
 PL28 'Q_INDUCTOR_SMLF-130NH/106A,INDA':;

SECTION_NUMBER 1
 '@S9S_MB_2U_LIB.S9S_MB_2U(SCH_1):PAGE587_I30@PURE_QUANTA.Q_INDUCTOR(CHIPS)':
 C_PATH='@s9s_mb_a_lib.s9s_mb_a(sch_1):page587_i30@pure_quanta.q_inductor(chips)~
';

PART_NAME
 PC1359 'Q_CAP_0402-0.1UF,25V,10%,X7R,CA':;

SECTION_NUMBER 1
 '@S9S_MB_2U_LIB.S9S_MB_2U(SCH_1):PAGE587_I89@PURE_QUANTA.Q_CAP(CHIPS)':
 C_PATH='@s9s_mb_2u_lib.s9s_mb_2u(sch_1):page587_i89@pure_quanta.q_cap(chips)',
 CDSVAR_REPCELL_ONSEMI='pure_quanta|Q_cap',
 VAR_0_ONSEMI='VALUE|0.1UF|VOLTAGE|25V|TOLERANCE|10%|PACK_TYPE|0402|MATERIAL|EMP~
TY|PART_NUMBER|CH4104K1B00|STANDARD||LIFECYCLE||ASS_PART||PART_NUMBER|CH4104K1B0~
0|JEDEC_TYPE|C0402|ALT_SYMBOLS|(C0402_OCTAGONXA,C0402-0201)|VALUE|NA|RATED_VOLTA~
GE|25V|TOL|10%|CLASS|IO|DESCRIPTION|CAP CHIP 0.1U 25V(+-10%,X7R,0402)|COMPONENT_~
TYPE|CHIP0402|LEAD_LENGTH||LPID||DATE|20160113|VARIANT_DEVICE_TYPE|Q_CAP-0.1UF,2~
5V,10%,0402,EMPTY';

PART_NAME
 PC1358 'Q_CAP_0402-0.1UF,25V,10%,X7R,CA':;

SECTION_NUMBER 1
 '@S9S_MB_2U_LIB.S9S_MB_2U(SCH_1):PAGE587_I91@PURE_QUANTA.Q_CAP(CHIPS)':
 C_PATH='@s9s_mb_2u_lib.s9s_mb_2u(sch_1):page587_i91@pure_quanta.q_cap(chips)',
 CDSVAR_REPCELL_ONSEMI='pure_quanta|Q_cap',
 VAR_0_ONSEMI='VALUE|0.1UF|VOLTAGE|25V|TOLERANCE|10%|PACK_TYPE|0402|MATERIAL|EMP~
TY|PART_NUMBER|CH4104K1B00|STANDARD||LIFECYCLE||ASS_PART||PART_NUMBER|CH4104K1B0~
0|JEDEC_TYPE|C0402|ALT_SYMBOLS|(C0402_OCTAGONXA,C0402-0201)|VALUE|NA|RATED_VOLTA~
GE|25V|TOL|10%|CLASS|IO|DESCRIPTION|CAP CHIP 0.1U 25V(+-10%,X7R,0402)|COMPONENT_~
TYPE|CHIP0402|LEAD_LENGTH||LPID||DATE|20160113|VARIANT_DEVICE_TYPE|Q_CAP-0.1UF,2~
5V,10%,0402,EMPTY';

PART_NAME
 PC544_P1_3 'Q_CAP_0805-22UF,4V,20%,X6S,TMPA':;

SECTION_NUMBER 1
 '@S9S_MB_2U_LIB.S9S_MB_2U(SCH_1):PAGE587_I58@PURE_QUANTA.Q_CAP(CHIPS)':
 C_PATH='@s9s_mb_2u_lib.s9s_mb_2u(sch_1):page587_i58@pure_quanta.q_cap(chips)';

PART_NAME
 PC543_P1_4 'Q_CAP_0805-22UF,4V,20%,X6S,TMPA':;

SECTION_NUMBER 1
 '@S9S_MB_2U_LIB.S9S_MB_2U(SCH_1):PAGE587_I52@PURE_QUANTA.Q_CAP(CHIPS)':
 C_PATH='@s9s_mb_2u_lib.s9s_mb_2u(sch_1):page587_i52@pure_quanta.q_cap(chips)';

PART_NAME
 PC542_P1_3 'Q_CAP_0805-22UF,4V,20%,X6S,TMPA':;

SECTION_NUMBER 1
 '@S9S_MB_2U_LIB.S9S_MB_2U(SCH_1):PAGE587_I57@PURE_QUANTA.Q_CAP(CHIPS)':
 C_PATH='@s9s_mb_2u_lib.s9s_mb_2u(sch_1):page587_i57@pure_quanta.q_cap(chips)';

PART_NAME
 PC541_P1_4 'Q_CAP_0805-22UF,4V,20%,X6S,TMPA':;

SECTION_NUMBER 1
 '@S9S_MB_2U_LIB.S9S_MB_2U(SCH_1):PAGE587_I51@PURE_QUANTA.Q_CAP(CHIPS)':
 C_PATH='@s9s_mb_2u_lib.s9s_mb_2u(sch_1):page587_i51@pure_quanta.q_cap(chips)';

PART_NAME
 PC538_P1_3 'Q_CAP_C0805-22UF,16V,20%,X6S,CA':;

SECTION_NUMBER 1
 '@S9S_MB_2U_LIB.S9S_MB_2U(SCH_1):PAGE587_I48@PURE_QUANTA.Q_CAP(CHIPS)':
 C_PATH='@s9s_mb_2u_lib.s9s_mb_2u(sch_1):page587_i48@pure_quanta.q_cap(chips)';

PART_NAME
 PC537_P1_4 'Q_CAP_C0805-22UF,16V,20%,X6S,CA':;

SECTION_NUMBER 1
 '@S9S_MB_2U_LIB.S9S_MB_2U(SCH_1):PAGE587_I35@PURE_QUANTA.Q_CAP(CHIPS)':
 C_PATH='@s9s_mb_2u_lib.s9s_mb_2u(sch_1):page587_i35@pure_quanta.q_cap(chips)';

PART_NAME
 PC536_P1_3 'Q_CAP_C0805-22UF,16V,20%,X6S,CA':;

SECTION_NUMBER 1
 '@S9S_MB_2U_LIB.S9S_MB_2U(SCH_1):PAGE587_I47@PURE_QUANTA.Q_CAP(CHIPS)':
 C_PATH='@s9s_mb_2u_lib.s9s_mb_2u(sch_1):page587_i47@pure_quanta.q_cap(chips)';

PART_NAME
 PC535_P1_4 'Q_CAP_C0805-22UF,16V,20%,X6S,CA':;

SECTION_NUMBER 1
 '@S9S_MB_2U_LIB.S9S_MB_2U(SCH_1):PAGE587_I34@PURE_QUANTA.Q_CAP(CHIPS)':
 C_PATH='@s9s_mb_2u_lib.s9s_mb_2u(sch_1):page587_i34@pure_quanta.q_cap(chips)';

PART_NAME
 PC534_P1_3 'Q_CAP_C0805-22UF,16V,20%,X6S,CA':;

SECTION_NUMBER 1
 '@S9S_MB_2U_LIB.S9S_MB_2U(SCH_1):PAGE587_I45@PURE_QUANTA.Q_CAP(CHIPS)':
 C_PATH='@s9s_mb_2u_lib.s9s_mb_2u(sch_1):page587_i45@pure_quanta.q_cap(chips)';

PART_NAME
 PC533_P1_4 'Q_CAP_C0805-22UF,16V,20%,X6S,CA':;

SECTION_NUMBER 1
 '@S9S_MB_2U_LIB.S9S_MB_2U(SCH_1):PAGE587_I33@PURE_QUANTA.Q_CAP(CHIPS)':
 C_PATH='@s9s_mb_2u_lib.s9s_mb_2u(sch_1):page587_i33@pure_quanta.q_cap(chips)';

PART_NAME
 PC532 'Q_CAP_C0402-100NF,50V,10%,X7R,A':;

SECTION_NUMBER 1
 '@S9S_MB_2U_LIB.S9S_MB_2U(SCH_1):PAGE587_I93@PURE_QUANTA.Q_CAP(CHIPS)':
 C_PATH='@s9s_mb_2u_lib.s9s_mb_2u(sch_1):page587_i93@pure_quanta.q_cap(chips)';

PART_NAME
 PC531 'Q_CAP_C0402-100NF,50V,10%,X7R,A':;

SECTION_NUMBER 1
 '@S9S_MB_2U_LIB.S9S_MB_2U(SCH_1):PAGE587_I92@PURE_QUANTA.Q_CAP(CHIPS)':
 C_PATH='@s9s_mb_2u_lib.s9s_mb_2u(sch_1):page587_i92@pure_quanta.q_cap(chips)';

PART_NAME
 PC530_P1_3 'Q_CAP_C0402-1UF,16V,10%,X6S,CHA':;

SECTION_NUMBER 1
 '@S9S_MB_2U_LIB.S9S_MB_2U(SCH_1):PAGE587_I44@PURE_QUANTA.Q_CAP(CHIPS)':
 C_PATH='@s9s_mb_2u_lib.s9s_mb_2u(sch_1):page587_i44@pure_quanta.q_cap(chips)';

PART_NAME
 PC529_P1_4 'Q_CAP_C0402-1UF,16V,10%,X6S,CHA':;

SECTION_NUMBER 1
 '@S9S_MB_2U_LIB.S9S_MB_2U(SCH_1):PAGE587_I32@PURE_QUANTA.Q_CAP(CHIPS)':
 C_PATH='@s9s_mb_2u_lib.s9s_mb_2u(sch_1):page587_i32@pure_quanta.q_cap(chips)';

PART_NAME
 PC528_P1_3 'Q_CAP_0402-3300PF,50V,10%,X7R,A':;

SECTION_NUMBER 1
 '@S9S_MB_2U_LIB.S9S_MB_2U(SCH_1):PAGE587_I43@PURE_QUANTA.Q_CAP(CHIPS)':
 C_PATH='@s9s_mb_2u_lib.s9s_mb_2u(sch_1):page587_i43@pure_quanta.q_cap(chips)';

PART_NAME
 PC527_P1_4 'Q_CAP_0402-3300PF,50V,10%,X7R,A':;

SECTION_NUMBER 1
 '@S9S_MB_2U_LIB.S9S_MB_2U(SCH_1):PAGE587_I27@PURE_QUANTA.Q_CAP(CHIPS)':
 C_PATH='@s9s_mb_2u_lib.s9s_mb_2u(sch_1):page587_i27@pure_quanta.q_cap(chips)';

PART_NAME
 PC526_P1_3 'Q_CAP_C0402-2.2UF,10V,10%,X6S,A':;

SECTION_NUMBER 1
 '@S9S_MB_2U_LIB.S9S_MB_2U(SCH_1):PAGE587_I40@PURE_QUANTA.Q_CAP(CHIPS)':
 C_PATH='@s9s_mb_2u_lib.s9s_mb_2u(sch_1):page587_i40@pure_quanta.q_cap(chips)';

PART_NAME
 PC525_P1_4 'Q_CAP_C0402-2.2UF,10V,10%,X6S,A':;

SECTION_NUMBER 1
 '@S9S_MB_2U_LIB.S9S_MB_2U(SCH_1):PAGE587_I24@PURE_QUANTA.Q_CAP(CHIPS)':
 C_PATH='@s9s_mb_2u_lib.s9s_mb_2u(sch_1):page587_i24@pure_quanta.q_cap(chips)';

PART_NAME
 PC524 'Q_CAP_C0402-2.2UF,10V,10%,X6S,A':;

SECTION_NUMBER 1
 '@S9S_MB_2U_LIB.S9S_MB_2U(SCH_1):PAGE587_I18@PURE_QUANTA.Q_CAP(CHIPS)':
 C_PATH='@s9s_mb_2u_lib.s9s_mb_2u(sch_1):page587_i18@pure_quanta.q_cap(chips)';

PART_NAME
 PC523 'Q_CAP_C0402-2.2UF,10V,10%,X6S,A':;

SECTION_NUMBER 1
 '@S9S_MB_2U_LIB.S9S_MB_2U(SCH_1):PAGE587_I8@PURE_QUANTA.Q_CAP(CHIPS)':
 C_PATH='@s9s_mb_2u_lib.s9s_mb_2u(sch_1):page587_i8@pure_quanta.q_cap(chips)';

PART_NAME
 PU26_P1_5 'ISL99390FRZTR5935-ISL99390FRZ-A':;

SECTION_NUMBER 1
 '@S9S_MB_2U_LIB.S9S_MB_2U(SCH_1):PAGE588_I27@PURE_QUANTA.ISL99390FRZTR5935(CHIPS)':
 C_PATH='@s9s_mb_2u_lib.s9s_mb_2u(sch_1):page588_i27@pure_quanta.isl99390frztr5935~
(chips)',
 VAR_0_ONSEMI='VAR_REPLACED|ISL99390FRZTR5935|VAR_PARTNAME|FDMF5085|VALUE|FDMF50~
85|PART_TYPE|SMLF|MATERIAL|IC|PART_NUMBER|AL005085000|STANDARD||LIFECYCLE||PART_~
NUMBER|AL005085000|JEDEC_TYPE|PQFN21_6X5XB|DESCRIPTION|IC OTHER(39P) FDMF5085(PQ~
FN)|MANUFTR|ONS|MANUF_PN|FDMF5085|RD_CMPLS_LVL|EP(V1)|CMPLS_LVL||FROM_PJ|S9S-KIM~
I|CLASS|IC|DIP_SMD||DATA|ONS_FDMF5085.pdf|EE_CHECK_LIST||FP_ECN||PSL||CREATOR||S~
TATUS||MSD|NA|ESD_CDM|NA|ESD_HBM|NA|ESD_MM|NA|PIN_LENGTH_SHORT_PIN|0 MILS|PIN_LE~
NGTH_LONG_PIN|0 MILS|CREATEDAY|20200423|VARIANT_DEVICE_TYPE|FDMF5085-FDMF5085,SM~
LF,IC,AL00',
 CDSVAR_REPCELL_ONSEMI='pure_quanta|fdmf5085';

PART_NAME
 PU25_P1_6 'ISL99390FRZTR5935-ISL99390FRZ-A':;

SECTION_NUMBER 1
 '@S9S_MB_2U_LIB.S9S_MB_2U(SCH_1):PAGE588_I8@PURE_QUANTA.ISL99390FRZTR5935(CHIPS)':
 C_PATH='@s9s_mb_2u_lib.s9s_mb_2u(sch_1):page588_i8@pure_quanta.isl99390frztr5935(~
chips)',
 VAR_0_ONSEMI='VAR_REPLACED|ISL99390FRZTR5935|VAR_PARTNAME|FDMF5085|VALUE|FDMF50~
85|PART_TYPE|SMLF|MATERIAL|IC|PART_NUMBER|AL005085000|STANDARD||LIFECYCLE||PART_~
NUMBER|AL005085000|JEDEC_TYPE|PQFN21_6X5XB|DESCRIPTION|IC OTHER(39P) FDMF5085(PQ~
FN)|MANUFTR|ONS|MANUF_PN|FDMF5085|RD_CMPLS_LVL|EP(V1)|CMPLS_LVL||FROM_PJ|S9S-KIM~
I|CLASS|IC|DIP_SMD||DATA|ONS_FDMF5085.pdf|EE_CHECK_LIST||FP_ECN||PSL||CREATOR||S~
TATUS||MSD|NA|ESD_CDM|NA|ESD_HBM|NA|ESD_MM|NA|PIN_LENGTH_SHORT_PIN|0 MILS|PIN_LE~
NGTH_LONG_PIN|0 MILS|CREATEDAY|20200423|VARIANT_DEVICE_TYPE|FDMF5085-FDMF5085,SM~
LF,IC,AL00',
 CDSVAR_REPCELL_ONSEMI='pure_quanta|fdmf5085';

PART_NAME
 PR1791 'Q_RES_0402LF-3.3,1%,1/16W,CHIPA':;

SECTION_NUMBER 1
 '@S9S_MB_2U_LIB.S9S_MB_2U(SCH_1):PAGE588_I71@PURE_QUANTA.Q_RES(CHIPS)':
 C_PATH='@s9s_mb_2u_lib.s9s_mb_2u(sch_1):page588_i71@pure_quanta.q_res(chips)',
 CDSVAR_REPCELL_ONSEMI='pure_quanta|Q_res',
 VAR_0_ONSEMI='VALUE|5.1|TOLERANCE|5%|WATTAGE|1/16W|PACK_TYPE|0402LF|MATERIAL|CH~
IP|PART_NUMBER|CS-5102JB03|STANDARD|End of Design|LIFECYCLE|Comp-Approve|PART_NU~
MBER|CS-5102JB03|JEDEC_TYPE|R0402|ALT_SYMBOLS|(R0402-0201)|VALUE|5.1|TOL|5%|WATT~
AGE|1/16W |CLASS|DISCRETE|DESCRIPTION|RES CHIP 5.1 1/16W +-5%(0402)|COMPONENT_TY~
PE|CHIP0402|LEAD_LENGTH||DFM_EXCLUSION||DAY|20100827|VARIANT_DEVICE_TYPE|Q_RES-5~
.1,5%,1/16W,0402LF,CHIP';

PART_NAME
 PR1790 'Q_RES_0402LF-3.3,1%,1/16W,CHIPA':;

SECTION_NUMBER 1
 '@S9S_MB_2U_LIB.S9S_MB_2U(SCH_1):PAGE588_I73@PURE_QUANTA.Q_RES(CHIPS)':
 C_PATH='@s9s_mb_2u_lib.s9s_mb_2u(sch_1):page588_i73@pure_quanta.q_res(chips)',
 CDSVAR_REPCELL_ONSEMI='pure_quanta|Q_res',
 VAR_0_ONSEMI='VALUE|5.1|TOLERANCE|5%|WATTAGE|1/16W|PACK_TYPE|0402LF|MATERIAL|CH~
IP|PART_NUMBER|CS-5102JB03|STANDARD|End of Design|LIFECYCLE|Comp-Approve|PART_NU~
MBER|CS-5102JB03|JEDEC_TYPE|R0402|ALT_SYMBOLS|(R0402-0201)|VALUE|5.1|TOL|5%|WATT~
AGE|1/16W |CLASS|DISCRETE|DESCRIPTION|RES CHIP 5.1 1/16W +-5%(0402)|COMPONENT_TY~
PE|CHIP0402|LEAD_LENGTH||DFM_EXCLUSION||DAY|20100827|VARIANT_DEVICE_TYPE|Q_RES-5~
.1,5%,1/16W,0402LF,CHIP';

PART_NAME
 PR296 'Q_RES_0402LF-0,5%,1/16W,CHIP,CA':;

SECTION_NUMBER 1
 '@S9S_MB_2U_LIB.S9S_MB_2U(SCH_1):PAGE588_I81@PURE_QUANTA.Q_RES(CHIPS)':
 C_PATH='@s9s_mb_2u_lib.s9s_mb_2u(sch_1):page588_i81@pure_quanta.q_res(chips)',
 CDSVAR_REPCELL_ONSEMI='pure_quanta|Q_res',
 VAR_0_ONSEMI='VALUE|0|TOLERANCE|5%|WATTAGE|1/16W|PACK_TYPE|0402LF|MATERIAL|EMPT~
Y|PART_NUMBER|CS00002JB38|STANDARD|End of Design|LIFECYCLE|Comp-Approve|PART_NUM~
BER|CS00002JB38|JEDEC_TYPE|R0402|ALT_SYMBOLS|(R0402-0201)|VALUE|0|TOL|5%|WATTAGE~
|1/16W|CLASS|IO|DESCRIPTION|RESISTOR CHIP 0 1/16W +-5%(0402)|COMPONENT_TYPE|CHIP~
0402|LEAD_LENGTH||DFM_EXCLUSION||DAY|20100618|VARIANT_DEVICE_TYPE|Q_RES-0,5%,1/1~
6W,0402LF,EMPTY,';

PART_NAME
 PR295 'Q_RES_0402LF-0,5%,1/16W,CHIP,CA':;

SECTION_NUMBER 1
 '@S9S_MB_2U_LIB.S9S_MB_2U(SCH_1):PAGE588_I82@PURE_QUANTA.Q_RES(CHIPS)':
 C_PATH='@s9s_mb_2u_lib.s9s_mb_2u(sch_1):page588_i82@pure_quanta.q_res(chips)',
 CDSVAR_REPCELL_ONSEMI='pure_quanta|Q_res',
 VAR_0_ONSEMI='VALUE|0|TOLERANCE|5%|WATTAGE|1/16W|PACK_TYPE|0402LF|MATERIAL|EMPT~
Y|PART_NUMBER|CS00002JB38|STANDARD|End of Design|LIFECYCLE|Comp-Approve|PART_NUM~
BER|CS00002JB38|JEDEC_TYPE|R0402|ALT_SYMBOLS|(R0402-0201)|VALUE|0|TOL|5%|WATTAGE~
|1/16W|CLASS|IO|DESCRIPTION|RESISTOR CHIP 0 1/16W +-5%(0402)|COMPONENT_TYPE|CHIP~
0402|LEAD_LENGTH||DFM_EXCLUSION||DAY|20100618|VARIANT_DEVICE_TYPE|Q_RES-0,5%,1/1~
6W,0402LF,EMPTY,';

PART_NAME
 PR294 'Q_RES_0402LF-2.2,1%,1/16W,CHIPA':;

SECTION_NUMBER 1
 '@S9S_MB_2U_LIB.S9S_MB_2U(SCH_1):PAGE588_I32@PURE_QUANTA.Q_RES(CHIPS)':
 C_PATH='@s9s_mb_2u_lib.s9s_mb_2u(sch_1):page588_i32@pure_quanta.q_res(chips)';

PART_NAME
 PR293 'Q_RES_0402LF-2.2,1%,1/16W,CHIPA':;

SECTION_NUMBER 1
 '@S9S_MB_2U_LIB.S9S_MB_2U(SCH_1):PAGE588_I19@PURE_QUANTA.Q_RES(CHIPS)':
 C_PATH='@s9s_mb_2u_lib.s9s_mb_2u(sch_1):page588_i19@pure_quanta.q_res(chips)';

PART_NAME
 PR292 'Q_RES_0402LF-8.87K,1%,1/16W,EMA':;

SECTION_NUMBER 1
 '@S9S_MB_2U_LIB.S9S_MB_2U(SCH_1):PAGE588_I22@PURE_QUANTA.Q_RES(CHIPS)':
 C_PATH='@s9s_mb_2u_lib.s9s_mb_2u(sch_1):page588_i22@pure_quanta.q_res(chips)';

PART_NAME
 PR291 'Q_RES_0402LF-8.87K,1%,1/16W,EMA':;

SECTION_NUMBER 1
 '@S9S_MB_2U_LIB.S9S_MB_2U(SCH_1):PAGE588_I2@PURE_QUANTA.Q_RES(CHIPS)':
 C_PATH='@s9s_mb_2u_lib.s9s_mb_2u(sch_1):page588_i2@pure_quanta.q_res(chips)';

PART_NAME
 PL27 'Q_INDUCTOR_SMLF-130NH/106A,INDA':;

SECTION_NUMBER 1
 '@S9S_MB_2U_LIB.S9S_MB_2U(SCH_1):PAGE588_I40@PURE_QUANTA.Q_INDUCTOR(CHIPS)':
 C_PATH='@s9s_mb_a_lib.s9s_mb_a(sch_1):page588_i40@pure_quanta.q_inductor(chips)~
';

PART_NAME
 PL26 'Q_INDUCTOR_SMLF-130NH/106A,INDA':;

SECTION_NUMBER 1
 '@S9S_MB_2U_LIB.S9S_MB_2U(SCH_1):PAGE588_I12@PURE_QUANTA.Q_INDUCTOR(CHIPS)':
 C_PATH='@s9s_mb_a_lib.s9s_mb_a(sch_1):page588_i12@pure_quanta.q_inductor(chips)~
';

PART_NAME
 PC1361 'Q_CAP_0402-0.1UF,25V,10%,X7R,CA':;

SECTION_NUMBER 1
 '@S9S_MB_2U_LIB.S9S_MB_2U(SCH_1):PAGE588_I76@PURE_QUANTA.Q_CAP(CHIPS)':
 C_PATH='@s9s_mb_2u_lib.s9s_mb_2u(sch_1):page588_i76@pure_quanta.q_cap(chips)',
 CDSVAR_REPCELL_ONSEMI='pure_quanta|Q_cap',
 VAR_0_ONSEMI='VALUE|0.1UF|VOLTAGE|25V|TOLERANCE|10%|PACK_TYPE|0402|MATERIAL|EMP~
TY|PART_NUMBER|CH4104K1B00|STANDARD||LIFECYCLE||ASS_PART||PART_NUMBER|CH4104K1B0~
0|JEDEC_TYPE|C0402|ALT_SYMBOLS|(C0402_OCTAGONXA,C0402-0201)|VALUE|NA|RATED_VOLTA~
GE|25V|TOL|10%|CLASS|IO|DESCRIPTION|CAP CHIP 0.1U 25V(+-10%,X7R,0402)|COMPONENT_~
TYPE|CHIP0402|LEAD_LENGTH||LPID||DATE|20160113|VARIANT_DEVICE_TYPE|Q_CAP-0.1UF,2~
5V,10%,0402,EMPTY';

PART_NAME
 PC1360 'Q_CAP_0402-0.1UF,25V,10%,X7R,CA':;

SECTION_NUMBER 1
 '@S9S_MB_2U_LIB.S9S_MB_2U(SCH_1):PAGE588_I78@PURE_QUANTA.Q_CAP(CHIPS)':
 C_PATH='@s9s_mb_2u_lib.s9s_mb_2u(sch_1):page588_i78@pure_quanta.q_cap(chips)',
 CDSVAR_REPCELL_ONSEMI='pure_quanta|Q_cap',
 VAR_0_ONSEMI='VALUE|0.1UF|VOLTAGE|25V|TOLERANCE|10%|PACK_TYPE|0402|MATERIAL|EMP~
TY|PART_NUMBER|CH4104K1B00|STANDARD||LIFECYCLE||ASS_PART||PART_NUMBER|CH4104K1B0~
0|JEDEC_TYPE|C0402|ALT_SYMBOLS|(C0402_OCTAGONXA,C0402-0201)|VALUE|NA|RATED_VOLTA~
GE|25V|TOL|10%|CLASS|IO|DESCRIPTION|CAP CHIP 0.1U 25V(+-10%,X7R,0402)|COMPONENT_~
TYPE|CHIP0402|LEAD_LENGTH||LPID||DATE|20160113|VARIANT_DEVICE_TYPE|Q_CAP-0.1UF,2~
5V,10%,0402,EMPTY';

PART_NAME
 PC522_P1_5 'Q_CAP_0805-22UF,4V,20%,X6S,TMPA':;

SECTION_NUMBER 1
 '@S9S_MB_2U_LIB.S9S_MB_2U(SCH_1):PAGE588_I56@PURE_QUANTA.Q_CAP(CHIPS)':
 C_PATH='@s9s_mb_2u_lib.s9s_mb_2u(sch_1):page588_i56@pure_quanta.q_cap(chips)';

PART_NAME
 PC521_P1_6 'Q_CAP_0805-22UF,4V,20%,X6S,TMPA':;

SECTION_NUMBER 1
 '@S9S_MB_2U_LIB.S9S_MB_2U(SCH_1):PAGE588_I15@PURE_QUANTA.Q_CAP(CHIPS)':
 C_PATH='@s9s_mb_2u_lib.s9s_mb_2u(sch_1):page588_i15@pure_quanta.q_cap(chips)';

PART_NAME
 PC520_P1_5 'Q_CAP_0805-22UF,4V,20%,X6S,TMPA':;

SECTION_NUMBER 1
 '@S9S_MB_2U_LIB.S9S_MB_2U(SCH_1):PAGE588_I55@PURE_QUANTA.Q_CAP(CHIPS)':
 C_PATH='@s9s_mb_2u_lib.s9s_mb_2u(sch_1):page588_i55@pure_quanta.q_cap(chips)';

PART_NAME
 PC519_P1_6 'Q_CAP_0805-22UF,4V,20%,X6S,TMPA':;

SECTION_NUMBER 1
 '@S9S_MB_2U_LIB.S9S_MB_2U(SCH_1):PAGE588_I14@PURE_QUANTA.Q_CAP(CHIPS)':
 C_PATH='@s9s_mb_2u_lib.s9s_mb_2u(sch_1):page588_i14@pure_quanta.q_cap(chips)';

PART_NAME
 PC516_P1_5 'Q_CAP_C0805-22UF,16V,20%,X6S,CA':;

SECTION_NUMBER 1
 '@S9S_MB_2U_LIB.S9S_MB_2U(SCH_1):PAGE588_I52@PURE_QUANTA.Q_CAP(CHIPS)':
 C_PATH='@s9s_mb_2u_lib.s9s_mb_2u(sch_1):page588_i52@pure_quanta.q_cap(chips)';

PART_NAME
 PC515_P1_6 'Q_CAP_C0805-22UF,16V,20%,X6S,CA':;

SECTION_NUMBER 1
 '@S9S_MB_2U_LIB.S9S_MB_2U(SCH_1):PAGE588_I47@PURE_QUANTA.Q_CAP(CHIPS)':
 C_PATH='@s9s_mb_2u_lib.s9s_mb_2u(sch_1):page588_i47@pure_quanta.q_cap(chips)';

PART_NAME
 PC514_P1_5 'Q_CAP_C0805-22UF,16V,20%,X6S,CA':;

SECTION_NUMBER 1
 '@S9S_MB_2U_LIB.S9S_MB_2U(SCH_1):PAGE588_I51@PURE_QUANTA.Q_CAP(CHIPS)':
 C_PATH='@s9s_mb_2u_lib.s9s_mb_2u(sch_1):page588_i51@pure_quanta.q_cap(chips)';

PART_NAME
 PC513_P1_6 'Q_CAP_C0805-22UF,16V,20%,X6S,CA':;

SECTION_NUMBER 1
 '@S9S_MB_2U_LIB.S9S_MB_2U(SCH_1):PAGE588_I46@PURE_QUANTA.Q_CAP(CHIPS)':
 C_PATH='@s9s_mb_2u_lib.s9s_mb_2u(sch_1):page588_i46@pure_quanta.q_cap(chips)';

PART_NAME
 PC512_P1_5 'Q_CAP_C0805-22UF,16V,20%,X6S,CA':;

SECTION_NUMBER 1
 '@S9S_MB_2U_LIB.S9S_MB_2U(SCH_1):PAGE588_I45@PURE_QUANTA.Q_CAP(CHIPS)':
 C_PATH='@s9s_mb_2u_lib.s9s_mb_2u(sch_1):page588_i45@pure_quanta.q_cap(chips)';

PART_NAME
 PC511_P1_6 'Q_CAP_C0805-22UF,16V,20%,X6S,CA':;

SECTION_NUMBER 1
 '@S9S_MB_2U_LIB.S9S_MB_2U(SCH_1):PAGE588_I39@PURE_QUANTA.Q_CAP(CHIPS)':
 C_PATH='@s9s_mb_2u_lib.s9s_mb_2u(sch_1):page588_i39@pure_quanta.q_cap(chips)';

PART_NAME
 PC510 'Q_CAP_C0402-100NF,50V,10%,X7R,A':;

SECTION_NUMBER 1
 '@S9S_MB_2U_LIB.S9S_MB_2U(SCH_1):PAGE588_I80@PURE_QUANTA.Q_CAP(CHIPS)':
 C_PATH='@s9s_mb_2u_lib.s9s_mb_2u(sch_1):page588_i80@pure_quanta.q_cap(chips)';

PART_NAME
 PC509 'Q_CAP_C0402-100NF,50V,10%,X7R,A':;

SECTION_NUMBER 1
 '@S9S_MB_2U_LIB.S9S_MB_2U(SCH_1):PAGE588_I79@PURE_QUANTA.Q_CAP(CHIPS)':
 C_PATH='@s9s_mb_2u_lib.s9s_mb_2u(sch_1):page588_i79@pure_quanta.q_cap(chips)';

PART_NAME
 PC508_P1_5 'Q_CAP_C0402-1UF,16V,10%,X6S,CHA':;

SECTION_NUMBER 1
 '@S9S_MB_2U_LIB.S9S_MB_2U(SCH_1):PAGE588_I44@PURE_QUANTA.Q_CAP(CHIPS)':
 C_PATH='@s9s_mb_2u_lib.s9s_mb_2u(sch_1):page588_i44@pure_quanta.q_cap(chips)';

PART_NAME
 PC507_P1_6 'Q_CAP_C0402-1UF,16V,10%,X6S,CHA':;

SECTION_NUMBER 1
 '@S9S_MB_2U_LIB.S9S_MB_2U(SCH_1):PAGE588_I38@PURE_QUANTA.Q_CAP(CHIPS)':
 C_PATH='@s9s_mb_2u_lib.s9s_mb_2u(sch_1):page588_i38@pure_quanta.q_cap(chips)';

PART_NAME
 PC506_P1_5 'Q_CAP_0402-3300PF,50V,10%,X7R,A':;

SECTION_NUMBER 1
 '@S9S_MB_2U_LIB.S9S_MB_2U(SCH_1):PAGE588_I43@PURE_QUANTA.Q_CAP(CHIPS)':
 C_PATH='@s9s_mb_2u_lib.s9s_mb_2u(sch_1):page588_i43@pure_quanta.q_cap(chips)';

PART_NAME
 PC505_P1_6 'Q_CAP_0402-3300PF,50V,10%,X7R,A':;

SECTION_NUMBER 1
 '@S9S_MB_2U_LIB.S9S_MB_2U(SCH_1):PAGE588_I37@PURE_QUANTA.Q_CAP(CHIPS)':
 C_PATH='@s9s_mb_2u_lib.s9s_mb_2u(sch_1):page588_i37@pure_quanta.q_cap(chips)';

PART_NAME
 PC504_P1_5 'Q_CAP_C0402-2.2UF,10V,10%,X6S,A':;

SECTION_NUMBER 1
 '@S9S_MB_2U_LIB.S9S_MB_2U(SCH_1):PAGE588_I35@PURE_QUANTA.Q_CAP(CHIPS)':
 C_PATH='@s9s_mb_2u_lib.s9s_mb_2u(sch_1):page588_i35@pure_quanta.q_cap(chips)';

PART_NAME
 PC503_P1_6 'Q_CAP_C0402-2.2UF,10V,10%,X6S,A':;

SECTION_NUMBER 1
 '@S9S_MB_2U_LIB.S9S_MB_2U(SCH_1):PAGE588_I26@PURE_QUANTA.Q_CAP(CHIPS)':
 C_PATH='@s9s_mb_2u_lib.s9s_mb_2u(sch_1):page588_i26@pure_quanta.q_cap(chips)';

PART_NAME
 PC502 'Q_CAP_C0402-2.2UF,10V,10%,X6S,A':;

SECTION_NUMBER 1
 '@S9S_MB_2U_LIB.S9S_MB_2U(SCH_1):PAGE588_I31@PURE_QUANTA.Q_CAP(CHIPS)':
 C_PATH='@s9s_mb_2u_lib.s9s_mb_2u(sch_1):page588_i31@pure_quanta.q_cap(chips)';

PART_NAME
 PC501 'Q_CAP_C0402-2.2UF,10V,10%,X6S,A':;

SECTION_NUMBER 1
 '@S9S_MB_2U_LIB.S9S_MB_2U(SCH_1):PAGE588_I18@PURE_QUANTA.Q_CAP(CHIPS)':
 C_PATH='@s9s_mb_2u_lib.s9s_mb_2u(sch_1):page588_i18@pure_quanta.q_cap(chips)';

PART_NAME
 PU24_P1_7 'ISL99390FRZTR5935-ISL99390FRZ-A':;

SECTION_NUMBER 1
 '@S9S_MB_2U_LIB.S9S_MB_2U(SCH_1):PAGE589_I25@PURE_QUANTA.ISL99390FRZTR5935(CHIPS)':
 C_PATH='@s9s_mb_2u_lib.s9s_mb_2u(sch_1):page589_i25@pure_quanta.isl99390frztr5935~
(chips)',
 VAR_0_ONSEMI='VAR_REPLACED|ISL99390FRZTR5935|VAR_PARTNAME|FDMF5085|VALUE|FDMF50~
85|PART_TYPE|SMLF|MATERIAL|IC|PART_NUMBER|AL005085000|STANDARD||LIFECYCLE||PART_~
NUMBER|AL005085000|JEDEC_TYPE|PQFN21_6X5XB|DESCRIPTION|IC OTHER(39P) FDMF5085(PQ~
FN)|MANUFTR|ONS|MANUF_PN|FDMF5085|RD_CMPLS_LVL|EP(V1)|CMPLS_LVL||FROM_PJ|S9S-KIM~
I|CLASS|IC|DIP_SMD||DATA|ONS_FDMF5085.pdf|EE_CHECK_LIST||FP_ECN||PSL||CREATOR||S~
TATUS||MSD|NA|ESD_CDM|NA|ESD_HBM|NA|ESD_MM|NA|PIN_LENGTH_SHORT_PIN|0 MILS|PIN_LE~
NGTH_LONG_PIN|0 MILS|CREATEDAY|20200423|VARIANT_DEVICE_TYPE|FDMF5085-FDMF5085,SM~
LF,IC,AL00',
 CDSVAR_REPCELL_ONSEMI='pure_quanta|fdmf5085';

PART_NAME
 PU23_P1_8 'ISL99390FRZTR5935-ISL99390FRZ-A':;

SECTION_NUMBER 1
 '@S9S_MB_2U_LIB.S9S_MB_2U(SCH_1):PAGE589_I7@PURE_QUANTA.ISL99390FRZTR5935(CHIPS)':
 C_PATH='@s9s_mb_2u_lib.s9s_mb_2u(sch_1):page589_i7@pure_quanta.isl99390frztr5935(~
chips)',
 VAR_0_ONSEMI='VAR_REPLACED|ISL99390FRZTR5935|VAR_PARTNAME|FDMF5085|VALUE|FDMF50~
85|PART_TYPE|SMLF|MATERIAL|IC|PART_NUMBER|AL005085000|STANDARD||LIFECYCLE||PART_~
NUMBER|AL005085000|JEDEC_TYPE|PQFN21_6X5XB|DESCRIPTION|IC OTHER(39P) FDMF5085(PQ~
FN)|MANUFTR|ONS|MANUF_PN|FDMF5085|RD_CMPLS_LVL|EP(V1)|CMPLS_LVL||FROM_PJ|S9S-KIM~
I|CLASS|IC|DIP_SMD||DATA|ONS_FDMF5085.pdf|EE_CHECK_LIST||FP_ECN||PSL||CREATOR||S~
TATUS||MSD|NA|ESD_CDM|NA|ESD_HBM|NA|ESD_MM|NA|PIN_LENGTH_SHORT_PIN|0 MILS|PIN_LE~
NGTH_LONG_PIN|0 MILS|CREATEDAY|20200423|VARIANT_DEVICE_TYPE|FDMF5085-FDMF5085,SM~
LF,IC,AL00',
 CDSVAR_REPCELL_ONSEMI='pure_quanta|fdmf5085';

PART_NAME
 PR1793 'Q_RES_0402LF-3.3,1%,1/16W,CHIPA':;

SECTION_NUMBER 1
 '@S9S_MB_2U_LIB.S9S_MB_2U(SCH_1):PAGE589_I71@PURE_QUANTA.Q_RES(CHIPS)':
 C_PATH='@s9s_mb_2u_lib.s9s_mb_2u(sch_1):page589_i71@pure_quanta.q_res(chips)',
 CDSVAR_REPCELL_ONSEMI='pure_quanta|Q_res',
 VAR_0_ONSEMI='VALUE|5.1|TOLERANCE|5%|WATTAGE|1/16W|PACK_TYPE|0402LF|MATERIAL|CH~
IP|PART_NUMBER|CS-5102JB03|STANDARD|End of Design|LIFECYCLE|Comp-Approve|PART_NU~
MBER|CS-5102JB03|JEDEC_TYPE|R0402|ALT_SYMBOLS|(R0402-0201)|VALUE|5.1|TOL|5%|WATT~
AGE|1/16W |CLASS|DISCRETE|DESCRIPTION|RES CHIP 5.1 1/16W +-5%(0402)|COMPONENT_TY~
PE|CHIP0402|LEAD_LENGTH||DFM_EXCLUSION||DAY|20100827|VARIANT_DEVICE_TYPE|Q_RES-5~
.1,5%,1/16W,0402LF,CHIP';

PART_NAME
 PR1792 'Q_RES_0402LF-3.3,1%,1/16W,CHIPA':;

SECTION_NUMBER 1
 '@S9S_MB_2U_LIB.S9S_MB_2U(SCH_1):PAGE589_I73@PURE_QUANTA.Q_RES(CHIPS)':
 C_PATH='@s9s_mb_2u_lib.s9s_mb_2u(sch_1):page589_i73@pure_quanta.q_res(chips)',
 CDSVAR_REPCELL_ONSEMI='pure_quanta|Q_res',
 VAR_0_ONSEMI='VALUE|5.1|TOLERANCE|5%|WATTAGE|1/16W|PACK_TYPE|0402LF|MATERIAL|CH~
IP|PART_NUMBER|CS-5102JB03|STANDARD|End of Design|LIFECYCLE|Comp-Approve|PART_NU~
MBER|CS-5102JB03|JEDEC_TYPE|R0402|ALT_SYMBOLS|(R0402-0201)|VALUE|5.1|TOL|5%|WATT~
AGE|1/16W |CLASS|DISCRETE|DESCRIPTION|RES CHIP 5.1 1/16W +-5%(0402)|COMPONENT_TY~
PE|CHIP0402|LEAD_LENGTH||DFM_EXCLUSION||DAY|20100827|VARIANT_DEVICE_TYPE|Q_RES-5~
.1,5%,1/16W,0402LF,CHIP';

PART_NAME
 PR290 'Q_RES_0402LF-0,5%,1/16W,CHIP,CA':;

SECTION_NUMBER 1
 '@S9S_MB_2U_LIB.S9S_MB_2U(SCH_1):PAGE589_I81@PURE_QUANTA.Q_RES(CHIPS)':
 C_PATH='@s9s_mb_2u_lib.s9s_mb_2u(sch_1):page589_i81@pure_quanta.q_res(chips)',
 CDSVAR_REPCELL_ONSEMI='pure_quanta|Q_res',
 VAR_0_ONSEMI='VALUE|0|TOLERANCE|5%|WATTAGE|1/16W|PACK_TYPE|0402LF|MATERIAL|EMPT~
Y|PART_NUMBER|CS00002JB38|STANDARD|End of Design|LIFECYCLE|Comp-Approve|PART_NUM~
BER|CS00002JB38|JEDEC_TYPE|R0402|ALT_SYMBOLS|(R0402-0201)|VALUE|0|TOL|5%|WATTAGE~
|1/16W|CLASS|IO|DESCRIPTION|RESISTOR CHIP 0 1/16W +-5%(0402)|COMPONENT_TYPE|CHIP~
0402|LEAD_LENGTH||DFM_EXCLUSION||DAY|20100618|VARIANT_DEVICE_TYPE|Q_RES-0,5%,1/1~
6W,0402LF,EMPTY,';

PART_NAME
 PR289 'Q_RES_0402LF-0,5%,1/16W,CHIP,CA':;

SECTION_NUMBER 1
 '@S9S_MB_2U_LIB.S9S_MB_2U(SCH_1):PAGE589_I82@PURE_QUANTA.Q_RES(CHIPS)':
 C_PATH='@s9s_mb_2u_lib.s9s_mb_2u(sch_1):page589_i82@pure_quanta.q_res(chips)',
 CDSVAR_REPCELL_ONSEMI='pure_quanta|Q_res',
 VAR_0_ONSEMI='VALUE|0|TOLERANCE|5%|WATTAGE|1/16W|PACK_TYPE|0402LF|MATERIAL|EMPT~
Y|PART_NUMBER|CS00002JB38|STANDARD|End of Design|LIFECYCLE|Comp-Approve|PART_NUM~
BER|CS00002JB38|JEDEC_TYPE|R0402|ALT_SYMBOLS|(R0402-0201)|VALUE|0|TOL|5%|WATTAGE~
|1/16W|CLASS|IO|DESCRIPTION|RESISTOR CHIP 0 1/16W +-5%(0402)|COMPONENT_TYPE|CHIP~
0402|LEAD_LENGTH||DFM_EXCLUSION||DAY|20100618|VARIANT_DEVICE_TYPE|Q_RES-0,5%,1/1~
6W,0402LF,EMPTY,';

PART_NAME
 PR288 'Q_RES_0402LF-2.2,1%,1/16W,CHIPA':;

SECTION_NUMBER 1
 '@S9S_MB_2U_LIB.S9S_MB_2U(SCH_1):PAGE589_I22@PURE_QUANTA.Q_RES(CHIPS)':
 C_PATH='@s9s_mb_2u_lib.s9s_mb_2u(sch_1):page589_i22@pure_quanta.q_res(chips)';

PART_NAME
 PR287 'Q_RES_0402LF-2.2,1%,1/16W,CHIPA':;

SECTION_NUMBER 1
 '@S9S_MB_2U_LIB.S9S_MB_2U(SCH_1):PAGE589_I10@PURE_QUANTA.Q_RES(CHIPS)':
 C_PATH='@s9s_mb_2u_lib.s9s_mb_2u(sch_1):page589_i10@pure_quanta.q_res(chips)';

PART_NAME
 PR286 'Q_RES_0402LF-8.87K,1%,1/16W,EMA':;

SECTION_NUMBER 1
 '@S9S_MB_2U_LIB.S9S_MB_2U(SCH_1):PAGE589_I16@PURE_QUANTA.Q_RES(CHIPS)':
 C_PATH='@s9s_mb_2u_lib.s9s_mb_2u(sch_1):page589_i16@pure_quanta.q_res(chips)';

PART_NAME
 PR285 'Q_RES_0402LF-8.87K,1%,1/16W,EMA':;

SECTION_NUMBER 1
 '@S9S_MB_2U_LIB.S9S_MB_2U(SCH_1):PAGE589_I2@PURE_QUANTA.Q_RES(CHIPS)':
 C_PATH='@s9s_mb_2u_lib.s9s_mb_2u(sch_1):page589_i2@pure_quanta.q_res(chips)';

PART_NAME
 PL25 'Q_INDUCTOR_SMLF-130NH/106A,INDA':;

SECTION_NUMBER 1
 '@S9S_MB_2U_LIB.S9S_MB_2U(SCH_1):PAGE589_I48@PURE_QUANTA.Q_INDUCTOR(CHIPS)':
 C_PATH='@s9s_mb_a_lib.s9s_mb_a(sch_1):page589_i48@pure_quanta.q_inductor(chips)~
';

PART_NAME
 PL24 'Q_INDUCTOR_SMLF-130NH/106A,INDA':;

SECTION_NUMBER 1
 '@S9S_MB_2U_LIB.S9S_MB_2U(SCH_1):PAGE589_I32@PURE_QUANTA.Q_INDUCTOR(CHIPS)':
 C_PATH='@s9s_mb_a_lib.s9s_mb_a(sch_1):page589_i32@pure_quanta.q_inductor(chips)~
';

PART_NAME
 PC1363 'Q_CAP_0402-0.1UF,25V,10%,X7R,CA':;

SECTION_NUMBER 1
 '@S9S_MB_2U_LIB.S9S_MB_2U(SCH_1):PAGE589_I78@PURE_QUANTA.Q_CAP(CHIPS)':
 C_PATH='@s9s_mb_2u_lib.s9s_mb_2u(sch_1):page589_i78@pure_quanta.q_cap(chips)',
 CDSVAR_REPCELL_ONSEMI='pure_quanta|Q_cap',
 VAR_0_ONSEMI='VALUE|0.1UF|VOLTAGE|25V|TOLERANCE|10%|PACK_TYPE|0402|MATERIAL|EMP~
TY|PART_NUMBER|CH4104K1B00|STANDARD||LIFECYCLE||ASS_PART||PART_NUMBER|CH4104K1B0~
0|JEDEC_TYPE|C0402|ALT_SYMBOLS|(C0402_OCTAGONXA,C0402-0201)|VALUE|NA|RATED_VOLTA~
GE|25V|TOL|10%|CLASS|IO|DESCRIPTION|CAP CHIP 0.1U 25V(+-10%,X7R,0402)|COMPONENT_~
TYPE|CHIP0402|LEAD_LENGTH||LPID||DATE|20160113|VARIANT_DEVICE_TYPE|Q_CAP-0.1UF,2~
5V,10%,0402,EMPTY';

PART_NAME
 PC1362 'Q_CAP_0402-0.1UF,25V,10%,X7R,CA':;

SECTION_NUMBER 1
 '@S9S_MB_2U_LIB.S9S_MB_2U(SCH_1):PAGE589_I76@PURE_QUANTA.Q_CAP(CHIPS)':
 C_PATH='@s9s_mb_2u_lib.s9s_mb_2u(sch_1):page589_i76@pure_quanta.q_cap(chips)',
 CDSVAR_REPCELL_ONSEMI='pure_quanta|Q_cap',
 VAR_0_ONSEMI='VALUE|0.1UF|VOLTAGE|25V|TOLERANCE|10%|PACK_TYPE|0402|MATERIAL|EMP~
TY|PART_NUMBER|CH4104K1B00|STANDARD||LIFECYCLE||ASS_PART||PART_NUMBER|CH4104K1B0~
0|JEDEC_TYPE|C0402|ALT_SYMBOLS|(C0402_OCTAGONXA,C0402-0201)|VALUE|NA|RATED_VOLTA~
GE|25V|TOL|10%|CLASS|IO|DESCRIPTION|CAP CHIP 0.1U 25V(+-10%,X7R,0402)|COMPONENT_~
TYPE|CHIP0402|LEAD_LENGTH||LPID||DATE|20160113|VARIANT_DEVICE_TYPE|Q_CAP-0.1UF,2~
5V,10%,0402,EMPTY';

PART_NAME
 PC500_P1_7 'Q_CAP_0805-22UF,4V,20%,X6S,TMPA':;

SECTION_NUMBER 1
 '@S9S_MB_2U_LIB.S9S_MB_2U(SCH_1):PAGE589_I55@PURE_QUANTA.Q_CAP(CHIPS)':
 C_PATH='@s9s_mb_2u_lib.s9s_mb_2u(sch_1):page589_i55@pure_quanta.q_cap(chips)';

PART_NAME
 PC499_P1_8 'Q_CAP_0805-22UF,4V,20%,X6S,TMPA':;

SECTION_NUMBER 1
 '@S9S_MB_2U_LIB.S9S_MB_2U(SCH_1):PAGE589_I41@PURE_QUANTA.Q_CAP(CHIPS)':
 C_PATH='@s9s_mb_2u_lib.s9s_mb_2u(sch_1):page589_i41@pure_quanta.q_cap(chips)';

PART_NAME
 PC498_P1_7 'Q_CAP_0805-22UF,4V,20%,X6S,TMPA':;

SECTION_NUMBER 1
 '@S9S_MB_2U_LIB.S9S_MB_2U(SCH_1):PAGE589_I53@PURE_QUANTA.Q_CAP(CHIPS)':
 C_PATH='@s9s_mb_2u_lib.s9s_mb_2u(sch_1):page589_i53@pure_quanta.q_cap(chips)';

PART_NAME
 PC497_P1_8 'Q_CAP_0805-22UF,4V,20%,X6S,TMPA':;

SECTION_NUMBER 1
 '@S9S_MB_2U_LIB.S9S_MB_2U(SCH_1):PAGE589_I39@PURE_QUANTA.Q_CAP(CHIPS)':
 C_PATH='@s9s_mb_2u_lib.s9s_mb_2u(sch_1):page589_i39@pure_quanta.q_cap(chips)';

PART_NAME
 PC496_P1_7 'Q_CAP_C0402-1UF,16V,10%,X6S,CHA':;

SECTION_NUMBER 1
 '@S9S_MB_2U_LIB.S9S_MB_2U(SCH_1):PAGE589_I52@PURE_QUANTA.Q_CAP(CHIPS)':
 C_PATH='@s9s_mb_2u_lib.s9s_mb_2u(sch_1):page589_i52@pure_quanta.q_cap(chips)';

PART_NAME
 PC495_P1_8 'Q_CAP_C0402-1UF,16V,10%,X6S,CHA':;

SECTION_NUMBER 1
 '@S9S_MB_2U_LIB.S9S_MB_2U(SCH_1):PAGE589_I37@PURE_QUANTA.Q_CAP(CHIPS)':
 C_PATH='@s9s_mb_2u_lib.s9s_mb_2u(sch_1):page589_i37@pure_quanta.q_cap(chips)';

PART_NAME
 PC494_P1_7 'Q_CAP_C0805-22UF,16V,20%,X6S,CA':;

SECTION_NUMBER 1
 '@S9S_MB_2U_LIB.S9S_MB_2U(SCH_1):PAGE589_I51@PURE_QUANTA.Q_CAP(CHIPS)':
 C_PATH='@s9s_mb_2u_lib.s9s_mb_2u(sch_1):page589_i51@pure_quanta.q_cap(chips)';

PART_NAME
 PC493_P1_8 'Q_CAP_C0805-22UF,16V,20%,X6S,CA':;

SECTION_NUMBER 1
 '@S9S_MB_2U_LIB.S9S_MB_2U(SCH_1):PAGE589_I35@PURE_QUANTA.Q_CAP(CHIPS)':
 C_PATH='@s9s_mb_2u_lib.s9s_mb_2u(sch_1):page589_i35@pure_quanta.q_cap(chips)';

PART_NAME
 PC492_P1_7 'Q_CAP_C0805-22UF,16V,20%,X6S,CA':;

SECTION_NUMBER 1
 '@S9S_MB_2U_LIB.S9S_MB_2U(SCH_1):PAGE589_I50@PURE_QUANTA.Q_CAP(CHIPS)':
 C_PATH='@s9s_mb_2u_lib.s9s_mb_2u(sch_1):page589_i50@pure_quanta.q_cap(chips)';

PART_NAME
 PC491_P1_8 'Q_CAP_C0805-22UF,16V,20%,X6S,CA':;

SECTION_NUMBER 1
 '@S9S_MB_2U_LIB.S9S_MB_2U(SCH_1):PAGE589_I34@PURE_QUANTA.Q_CAP(CHIPS)':
 C_PATH='@s9s_mb_2u_lib.s9s_mb_2u(sch_1):page589_i34@pure_quanta.q_cap(chips)';

PART_NAME
 PC490_P1_7 'Q_CAP_C0805-22UF,16V,20%,X6S,CA':;

SECTION_NUMBER 1
 '@S9S_MB_2U_LIB.S9S_MB_2U(SCH_1):PAGE589_I49@PURE_QUANTA.Q_CAP(CHIPS)':
 C_PATH='@s9s_mb_2u_lib.s9s_mb_2u(sch_1):page589_i49@pure_quanta.q_cap(chips)';

PART_NAME
 PC489_P1_8 'Q_CAP_C0805-22UF,16V,20%,X6S,CA':;

SECTION_NUMBER 1
 '@S9S_MB_2U_LIB.S9S_MB_2U(SCH_1):PAGE589_I33@PURE_QUANTA.Q_CAP(CHIPS)':
 C_PATH='@s9s_mb_2u_lib.s9s_mb_2u(sch_1):page589_i33@pure_quanta.q_cap(chips)';

PART_NAME
 PC488 'Q_CAP_C0402-100NF,50V,10%,X7R,A':;

SECTION_NUMBER 1
 '@S9S_MB_2U_LIB.S9S_MB_2U(SCH_1):PAGE589_I80@PURE_QUANTA.Q_CAP(CHIPS)':
 C_PATH='@s9s_mb_2u_lib.s9s_mb_2u(sch_1):page589_i80@pure_quanta.q_cap(chips)';

PART_NAME
 PC487 'Q_CAP_C0402-100NF,50V,10%,X7R,A':;

SECTION_NUMBER 1
 '@S9S_MB_2U_LIB.S9S_MB_2U(SCH_1):PAGE589_I79@PURE_QUANTA.Q_CAP(CHIPS)':
 C_PATH='@s9s_mb_2u_lib.s9s_mb_2u(sch_1):page589_i79@pure_quanta.q_cap(chips)';

PART_NAME
 PC486_P1_7 'Q_CAP_C0402-1UF,16V,10%,X6S,CHA':;

SECTION_NUMBER 1
 '@S9S_MB_2U_LIB.S9S_MB_2U(SCH_1):PAGE589_I46@PURE_QUANTA.Q_CAP(CHIPS)':
 C_PATH='@s9s_mb_2u_lib.s9s_mb_2u(sch_1):page589_i46@pure_quanta.q_cap(chips)';

PART_NAME
 PC485_P1_8 'Q_CAP_C0402-1UF,16V,10%,X6S,CHA':;

SECTION_NUMBER 1
 '@S9S_MB_2U_LIB.S9S_MB_2U(SCH_1):PAGE589_I30@PURE_QUANTA.Q_CAP(CHIPS)':
 C_PATH='@s9s_mb_2u_lib.s9s_mb_2u(sch_1):page589_i30@pure_quanta.q_cap(chips)';

PART_NAME
 PC484_P1_7 'Q_CAP_0402-3300PF,50V,10%,X7R,A':;

SECTION_NUMBER 1
 '@S9S_MB_2U_LIB.S9S_MB_2U(SCH_1):PAGE589_I44@PURE_QUANTA.Q_CAP(CHIPS)':
 C_PATH='@s9s_mb_2u_lib.s9s_mb_2u(sch_1):page589_i44@pure_quanta.q_cap(chips)';

PART_NAME
 PC483_P1_8 'Q_CAP_0402-3300PF,50V,10%,X7R,A':;

SECTION_NUMBER 1
 '@S9S_MB_2U_LIB.S9S_MB_2U(SCH_1):PAGE589_I29@PURE_QUANTA.Q_CAP(CHIPS)':
 C_PATH='@s9s_mb_2u_lib.s9s_mb_2u(sch_1):page589_i29@pure_quanta.q_cap(chips)';

PART_NAME
 PC482_P1_7 'Q_CAP_C0402-2.2UF,10V,10%,X6S,A':;

SECTION_NUMBER 1
 '@S9S_MB_2U_LIB.S9S_MB_2U(SCH_1):PAGE589_I23@PURE_QUANTA.Q_CAP(CHIPS)':
 C_PATH='@s9s_mb_2u_lib.s9s_mb_2u(sch_1):page589_i23@pure_quanta.q_cap(chips)';

PART_NAME
 PC481_P1_8 'Q_CAP_C0402-2.2UF,10V,10%,X6S,A':;

SECTION_NUMBER 1
 '@S9S_MB_2U_LIB.S9S_MB_2U(SCH_1):PAGE589_I11@PURE_QUANTA.Q_CAP(CHIPS)':
 C_PATH='@s9s_mb_2u_lib.s9s_mb_2u(sch_1):page589_i11@pure_quanta.q_cap(chips)';

PART_NAME
 PC480 'Q_CAP_C0402-2.2UF,10V,10%,X6S,A':;

SECTION_NUMBER 1
 '@S9S_MB_2U_LIB.S9S_MB_2U(SCH_1):PAGE589_I21@PURE_QUANTA.Q_CAP(CHIPS)':
 C_PATH='@s9s_mb_2u_lib.s9s_mb_2u(sch_1):page589_i21@pure_quanta.q_cap(chips)';

PART_NAME
 PC479 'Q_CAP_C0402-2.2UF,10V,10%,X6S,A':;

SECTION_NUMBER 1
 '@S9S_MB_2U_LIB.S9S_MB_2U(SCH_1):PAGE589_I9@PURE_QUANTA.Q_CAP(CHIPS)':
 C_PATH='@s9s_mb_2u_lib.s9s_mb_2u(sch_1):page589_i9@pure_quanta.q_cap(chips)';

PART_NAME
 R1769 'Q_RES_0402LF-100,1%,1/16W,EMPTA':;

SECTION_NUMBER 1
 '@S9S_MB_2U_LIB.S9S_MB_2U(SCH_1):PAGE591_I410@PURE_QUANTA.Q_RES(CHIPS)':
 C_PATH='@s9s_mb_2u_lib.s9s_mb_2u(sch_1):page591_i410@pure_quanta.q_res(chips)';

PART_NAME
 R1768 'Q_RES_0402LF-49.9     ,1%  ,1/B':;

SECTION_NUMBER 1
 '@S9S_MB_2U_LIB.S9S_MB_2U(SCH_1):PAGE591_I409@PURE_QUANTA.Q_RES(CHIPS)':
 C_PATH='@s9s_mb_2u_lib.s9s_mb_2u(sch_1):page591_i409@pure_quanta.q_res(chips)';

PART_NAME
 PU22 'ISL69260IRAZT-ISL69260IRAZ-T,SA':;

SECTION_NUMBER 1
 '@S9S_MB_2U_LIB.S9S_MB_2U(SCH_1):PAGE591_I412@PURE_QUANTA.ISL69260IRAZT(CHIPS)':
 C_PATH='@s9s_mb_2u_lib.s9s_mb_2u(sch_1):page591_i412@pure_quanta.isl69260irazt(ch~
ips)',
 CDSVAR_REPCELL_ONSEMI='pure_quanta|fd5001',
 VAR_0_ONSEMI='VAR_REPLACED|ISL69260IRAZT|VAR_PARTNAME|FD5001|VALUE|FD5001|PART_~
TYPE|SMLF|MATERIAL|IC|PART_NUMBER|AL005001004|STANDARD||LIFECYCLE||PART_NUMBER|A~
L005001004|JEDEC_TYPE|VFQFPN40_TH_0-4_5X5XC|DESCRIPTION|IC OTHER(40P) FD5001(QFN~
)|MANUFTR|ONS|MANUF_PN|FD5001|RD_CMPLS_LVL|EP(V1)|CMPLS_LVL||FROM_PJ|S9S-KIMI|CL~
ASS|IC|DIP_SMD||DATA|ONS_FD5001.pdf|EE_CHECK_LIST||FP_ECN|FD5001.msg|PSL||CREATO~
R||STATUS||MSD|NA|ESD_CDM|NA|ESD_HBM|NA|ESD_MM|NA|PIN_LENGTH_SHORT_PIN|0 MILS|PI~
N_LENGTH_LONG_PIN|0 MILS|CREATEDAY|20200421|VARIANT_DEVICE_TYPE|FD5001-FD5001,SM~
LF,IC,AL005001';

PART_NAME
 PR571 'Q_RES_0402LF-1K,1%,1/16W,CHIP,A':;

SECTION_NUMBER 1
 '@S9S_MB_2U_LIB.S9S_MB_2U(SCH_1):PAGE591_I298@PURE_QUANTA.Q_RES(CHIPS)':
 C_PATH='@s9s_mb_2u_lib.s9s_mb_2u(sch_1):page591_i298@pure_quanta.q_res(chips)';

PART_NAME
 PR570 'Q_RES_0402LF-1K,1%,1/16W,CHIP,A':;

SECTION_NUMBER 1
 '@S9S_MB_2U_LIB.S9S_MB_2U(SCH_1):PAGE591_I297@PURE_QUANTA.Q_RES(CHIPS)':
 C_PATH='@s9s_mb_2u_lib.s9s_mb_2u(sch_1):page591_i297@pure_quanta.q_res(chips)';

PART_NAME
 PR569 'Q_RES_0402LF-100,1%,1/16W,CHIPA':;

SECTION_NUMBER 1
 '@S9S_MB_2U_LIB.S9S_MB_2U(SCH_1):PAGE591_I261@PURE_QUANTA.Q_RES(CHIPS)':
 C_PATH='@s9s_mb_2u_lib.s9s_mb_2u(sch_1):page591_i261@pure_quanta.q_res(chips)';

PART_NAME
 PR568 'Q_RES_0402LF-100,1%,1/16W,CHIPA':;

SECTION_NUMBER 1
 '@S9S_MB_2U_LIB.S9S_MB_2U(SCH_1):PAGE591_I252@PURE_QUANTA.Q_RES(CHIPS)':
 C_PATH='@s9s_mb_2u_lib.s9s_mb_2u(sch_1):page591_i252@pure_quanta.q_res(chips)';

PART_NAME
 PR567 'Q_RES_0402LF-100,1%,1/16W,CHIPA':;

SECTION_NUMBER 1
 '@S9S_MB_2U_LIB.S9S_MB_2U(SCH_1):PAGE591_I265@PURE_QUANTA.Q_RES(CHIPS)':
 C_PATH='@s9s_mb_2u_lib.s9s_mb_2u(sch_1):page591_i265@pure_quanta.q_res(chips)';

PART_NAME
 PR566 'Q_RES_0402LF-100,1%,1/16W,CHIPA':;

SECTION_NUMBER 1
 '@S9S_MB_2U_LIB.S9S_MB_2U(SCH_1):PAGE591_I256@PURE_QUANTA.Q_RES(CHIPS)':
 C_PATH='@s9s_mb_2u_lib.s9s_mb_2u(sch_1):page591_i256@pure_quanta.q_res(chips)';

PART_NAME
 PR284 'Q_RES_0402LF-1K,1%,1/16W,EMPTYA':;

SECTION_NUMBER 1
 '@S9S_MB_2U_LIB.S9S_MB_2U(SCH_1):PAGE591_I386@PURE_QUANTA.Q_RES(CHIPS)':
 C_PATH='@s9s_mb_2u_lib.s9s_mb_2u(sch_1):page591_i386@pure_quanta.q_res(chips)';

PART_NAME
 PR283 'Q_RES_0402LF-1,1%,1/16W,CHIP,CA':;

SECTION_NUMBER 1
 '@S9S_MB_2U_LIB.S9S_MB_2U(SCH_1):PAGE591_I335@PURE_QUANTA.Q_RES(CHIPS)':
 C_PATH='@s9s_mb_2u_lib.s9s_mb_2u(sch_1):page591_i335@pure_quanta.q_res(chips)';

PART_NAME
 PR276 'Q_RES_0402LF-1K,1%,1/16W,EMPTYA':;

SECTION_NUMBER 1
 '@S9S_MB_2U_LIB.S9S_MB_2U(SCH_1):PAGE591_I316@PURE_QUANTA.Q_RES(CHIPS)':
 C_PATH='@s9s_mb_2u_lib.s9s_mb_2u(sch_1):page591_i316@pure_quanta.q_res(chips)';

PART_NAME
 PR275 'Q_RES_0402LF-1K,1%,1/16W,EMPTYA':;

SECTION_NUMBER 1
 '@S9S_MB_2U_LIB.S9S_MB_2U(SCH_1):PAGE591_I317@PURE_QUANTA.Q_RES(CHIPS)':
 C_PATH='@s9s_mb_2u_lib.s9s_mb_2u(sch_1):page591_i317@pure_quanta.q_res(chips)';

PART_NAME
 PR274 'Q_RES_0402LF-0,5%,1/16W,CHIP,CA':;

SECTION_NUMBER 1
 '@S9S_MB_2U_LIB.S9S_MB_2U(SCH_1):PAGE591_I259@PURE_QUANTA.Q_RES(CHIPS)':
 C_PATH='@s9s_mb_2u_lib.s9s_mb_2u(sch_1):page591_i259@pure_quanta.q_res(chips)';

PART_NAME
 PR273 'Q_RES_0402LF-0,5%,1/16W,CHIP,CA':;

SECTION_NUMBER 1
 '@S9S_MB_2U_LIB.S9S_MB_2U(SCH_1):PAGE591_I250@PURE_QUANTA.Q_RES(CHIPS)':
 C_PATH='@s9s_mb_2u_lib.s9s_mb_2u(sch_1):page591_i250@pure_quanta.q_res(chips)';

PART_NAME
 PR272 'Q_RES_0402LF-0,5%,1/16W,CHIP,CA':;

SECTION_NUMBER 1
 '@S9S_MB_2U_LIB.S9S_MB_2U(SCH_1):PAGE591_I301@PURE_QUANTA.Q_RES(CHIPS)':
 C_PATH='@s9s_mb_2u_lib.s9s_mb_2u(sch_1):page591_i301@pure_quanta.q_res(chips)';

PART_NAME
 PR271 'Q_RES_0402LF-0,5%,1/16W,CHIP,CA':;

SECTION_NUMBER 1
 '@S9S_MB_2U_LIB.S9S_MB_2U(SCH_1):PAGE591_I304@PURE_QUANTA.Q_RES(CHIPS)':
 C_PATH='@s9s_mb_2u_lib.s9s_mb_2u(sch_1):page591_i304@pure_quanta.q_res(chips)';

PART_NAME
 PR270 'Q_RES_0402LF-1K,1%,1/16W,CHIP,A':;

SECTION_NUMBER 1
 '@S9S_MB_2U_LIB.S9S_MB_2U(SCH_1):PAGE591_I306@PURE_QUANTA.Q_RES(CHIPS)':
 C_PATH='@s9s_mb_2u_lib.s9s_mb_2u(sch_1):page591_i306@pure_quanta.q_res(chips)';

PART_NAME
 PR269 'Q_RES_0402LF-33.2,1%,1/16W,CHIA':;

SECTION_NUMBER 1
 '@S9S_MB_2U_LIB.S9S_MB_2U(SCH_1):PAGE591_I227@PURE_QUANTA.Q_RES(CHIPS)':
 C_PATH='@s9s_mb_2u_lib.s9s_mb_2u(sch_1):page591_i227@pure_quanta.q_res(chips)';

PART_NAME
 PR268 'Q_RES_0402LF-0,5%,1/16W,CHIP,CA':;

SECTION_NUMBER 1
 '@S9S_MB_2U_LIB.S9S_MB_2U(SCH_1):PAGE591_I226@PURE_QUANTA.Q_RES(CHIPS)':
 C_PATH='@s9s_mb_2u_lib.s9s_mb_2u(sch_1):page591_i226@pure_quanta.q_res(chips)';

PART_NAME
 PR267 'Q_RES_0402LF-0,5%,1/16W,CHIP,CA':;

SECTION_NUMBER 1
 '@S9S_MB_2U_LIB.S9S_MB_2U(SCH_1):PAGE591_I213@PURE_QUANTA.Q_RES(CHIPS)':
 C_PATH='@s9s_mb_2u_lib.s9s_mb_2u(sch_1):page591_i213@pure_quanta.q_res(chips)';

PART_NAME
 PR266 'Q_RES_0402LF-0,5%,1/16W,CHIP,CA':;

SECTION_NUMBER 1
 '@S9S_MB_2U_LIB.S9S_MB_2U(SCH_1):PAGE591_I223@PURE_QUANTA.Q_RES(CHIPS)':
 C_PATH='@s9s_mb_2u_lib.s9s_mb_2u(sch_1):page591_i223@pure_quanta.q_res(chips)';

PART_NAME
 PR265 'Q_RES_0402LF-150,1%,1/16W,CHIPA':;

SECTION_NUMBER 1
 '@S9S_MB_2U_LIB.S9S_MB_2U(SCH_1):PAGE591_I222@PURE_QUANTA.Q_RES(CHIPS)':
 C_PATH='@s9s_mb_2u_lib.s9s_mb_2u(sch_1):page591_i222@pure_quanta.q_res(chips)';

PART_NAME
 PR264 'Q_RES_0402LF-0,5%,1/16W,CHIP,CA':;

SECTION_NUMBER 1
 '@S9S_MB_2U_LIB.S9S_MB_2U(SCH_1):PAGE591_I214@PURE_QUANTA.Q_RES(CHIPS)':
 C_PATH='@s9s_mb_2u_lib.s9s_mb_2u(sch_1):page591_i214@pure_quanta.q_res(chips)';

PART_NAME
 PR263 'Q_RES_0402LF-0,5%,1/16W,CHIP,CA':;

SECTION_NUMBER 1
 '@S9S_MB_2U_LIB.S9S_MB_2U(SCH_1):PAGE591_I215@PURE_QUANTA.Q_RES(CHIPS)':
 C_PATH='@s9s_mb_2u_lib.s9s_mb_2u(sch_1):page591_i215@pure_quanta.q_res(chips)';

PART_NAME
 PR262 'Q_RES_0402LF-1K,1%,1/16W,CHIP,A':;

SECTION_NUMBER 1
 '@S9S_MB_2U_LIB.S9S_MB_2U(SCH_1):PAGE591_I216@PURE_QUANTA.Q_RES(CHIPS)':
 C_PATH='@s9s_mb_2u_lib.s9s_mb_2u(sch_1):page591_i216@pure_quanta.q_res(chips)';

PART_NAME
 PR261 'Q_RES_0402LF-0,5%,1/16W,CHIP,CA':;

SECTION_NUMBER 1
 '@S9S_MB_2U_LIB.S9S_MB_2U(SCH_1):PAGE591_I314@PURE_QUANTA.Q_RES(CHIPS)':
 C_PATH='@s9s_mb_2u_lib.s9s_mb_2u(sch_1):page591_i314@pure_quanta.q_res(chips)';

PART_NAME
 PR260 'Q_RES_0402LF-0,5%,1/16W,CHIP,CA':;

SECTION_NUMBER 1
 '@S9S_MB_2U_LIB.S9S_MB_2U(SCH_1):PAGE591_I320@PURE_QUANTA.Q_RES(CHIPS)':
 C_PATH='@s9s_mb_2u_lib.s9s_mb_2u(sch_1):page591_i320@pure_quanta.q_res(chips)';

PART_NAME
 PR259 'Q_RES_0402LF -9.53K,1%,1/16W ,A':;

SECTION_NUMBER 1
 '@S9S_MB_2U_LIB.S9S_MB_2U(SCH_1):PAGE591_I323@PURE_QUANTA.Q_RES(CHIPS)':
 C_PATH='@s9s_mb_2u_lib.s9s_mb_2u(sch_1):page591_i323@pure_quanta.q_res(chips)',
 CDSVAR_REPCELL_ONSEMI='pure_quanta|Q_res',
 VAR_0_ONSEMI='VALUE|11.3K|TOLERANCE|0.1%|WATTAGE|1/16W|PACK_TYPE|0402LF|MATERIA~
L|CHIP|PART_NUMBER|CS31132BB00|STANDARD||LIFECYCLE||PART_NUMBER|CS31132BB00|JEDE~
C_TYPE|R0402|ALT_SYMBOLS|(R0402-0201)|VALUE|11.3K|TOL|0.1%|WATTAGE|1/16W|CLASS|D~
ISCRETE|DESCRIPTION|RES CHIP 11.3K 1/16W +-0.1%(0402)|COMPONENT_TYPE|CHIP0402|LE~
AD_LENGTH||DFM_EXCLUSION||DAY|20140813|VARIANT_DEVICE_TYPE|Q_RES-11.3K,0.1%,1/16~
W,0402LF,';

PART_NAME
 PR258 'Q_RES_0402LF-28K,1%,1/16W,EMPTA':;

SECTION_NUMBER 1
 '@S9S_MB_2U_LIB.S9S_MB_2U(SCH_1):PAGE591_I322@PURE_QUANTA.Q_RES(CHIPS)':
 C_PATH='@s9s_mb_2u_lib.s9s_mb_2u(sch_1):page591_i322@pure_quanta.q_res(chips)';

PART_NAME
 PJ51 'Q_SHORT_SM-EMPTY,SHORT6':;

SECTION_NUMBER 1
 '@S9S_MB_2U_LIB.S9S_MB_2U(SCH_1):PAGE591_I262@PURE_QUANTA.Q_SHORT(CHIPS)':
 C_PATH='@s9s_mb_2u_lib.s9s_mb_2u(sch_1):page591_i262@pure_quanta.q_short(chips)';

PART_NAME
 PJ50 'Q_SHORT_SM-EMPTY,SHORT6':;

SECTION_NUMBER 1
 '@S9S_MB_2U_LIB.S9S_MB_2U(SCH_1):PAGE591_I253@PURE_QUANTA.Q_SHORT(CHIPS)':
 C_PATH='@s9s_mb_2u_lib.s9s_mb_2u(sch_1):page591_i253@pure_quanta.q_short(chips)';

PART_NAME
 PC1292 'Q_CAP_0402-470PF,50V,10%,X7R,TA':;

SECTION_NUMBER 1
 '@S9S_MB_2U_LIB.S9S_MB_2U(SCH_1):PAGE591_I390@PURE_QUANTA.Q_CAP(CHIPS)':
 C_PATH='@s9s_mb_2u_lib.s9s_mb_2u(sch_1):page591_i390@pure_quanta.q_cap(chips)',
 CDSVAR_REPCELL_ONSEMI='pure_quanta|Q_cap',
 VAR_0_ONSEMI='VALUE|2200PF|VOLTAGE|50V|TOLERANCE|10%|PACK_TYPE|C0402|MATERIAL|X~
7R|PART_NUMBER|CH2226K1B06|STANDARD||LIFECYCLE||ASS_PART||PART_NUMBER|CH2226K1B0~
6|JEDEC_TYPE|C0402|ALT_SYMBOLS|(C0402-0201)|VALUE|2200PF|RATED_VOLTAGE|50V|TOL|1~
0%|CLASS|DISCRETE|DESCRIPTION|CAP CHIP 2200P 50V(+-10%,X7R,0402)MUR|COMPONENT_TY~
PE|CHIP0402|LEAD_LENGTH||LPID||DATE|20150614|VARIANT_DEVICE_TYPE|Q_CAP-2200PF,50~
V,10%,C0402,X7R';

PART_NAME
 PC1193 'Q_CAP_C0402-1UF,16V,10%,X6S,CHA':;

SECTION_NUMBER 1
 '@S9S_MB_2U_LIB.S9S_MB_2U(SCH_1):PAGE591_I339@PURE_QUANTA.Q_CAP(CHIPS)':
 C_PATH='@s9s_mb_2u_lib.s9s_mb_2u(sch_1):page591_i339@pure_quanta.q_cap(chips)';

PART_NAME
 PC478 'Q_CAP_C0402-1UF,16V,10%,X6S,CHA':;

SECTION_NUMBER 1
 '@S9S_MB_2U_LIB.S9S_MB_2U(SCH_1):PAGE591_I334@PURE_QUANTA.Q_CAP(CHIPS)':
 C_PATH='@s9s_mb_2u_lib.s9s_mb_2u(sch_1):page591_i334@pure_quanta.q_cap(chips)';

PART_NAME
 PC477 'Q_CAP_0402-4.7UF,6.3V,20%,X6S,A':;

SECTION_NUMBER 1
 '@S9S_MB_2U_LIB.S9S_MB_2U(SCH_1):PAGE591_I340@PURE_QUANTA.Q_CAP(CHIPS)':
 C_PATH='@s9s_mb_2u_lib.s9s_mb_2u(sch_1):page591_i340@pure_quanta.q_cap(chips)',
 CDSVAR_REPCELL_ONSEMI='pure_quanta|Q_cap',
 VAR_0_ONSEMI='VALUE|4.7UF|VOLTAGE|6.3V|TOLERANCE|20%|PACK_TYPE|0402|MATERIAL|EM~
PTY|PART_NUMBER|CH5471MEB01|STANDARD||LIFECYCLE||ASS_PART||PART_NUMBER|CH5471MEB~
01|JEDEC_TYPE|C0402|ALT_SYMBOLS|(C0402_OCTAGON,C0402_OCTAGONXA,C0402-0201)|VALUE~
|NA|RATED_VOLTAGE|6.3V|TOL|20%|CLASS|IO|DESCRIPTION|CAP CHIP 4.7UF 6.3V(+-20%,X6~
S,0402)|COMPONENT_TYPE|CHIP0402|LEAD_LENGTH||LPID||DATE|20151211|VARIANT_DEVICE_~
TYPE|Q_CAP-4.7UF,6.3V,20%,0402,EMPT';

PART_NAME
 PC476 'Q_CAP_C0402-100NF,50V,10%,EMPTA':;

SECTION_NUMBER 1
 '@S9S_MB_2U_LIB.S9S_MB_2U(SCH_1):PAGE591_I333@PURE_QUANTA.Q_CAP(CHIPS)':
 C_PATH='@s9s_mb_2u_lib.s9s_mb_2u(sch_1):page591_i333@pure_quanta.q_cap(chips)';

PART_NAME
 PC475 'Q_CAP_0402-470PF,50V,10%,X7R,TA':;

SECTION_NUMBER 1
 '@S9S_MB_2U_LIB.S9S_MB_2U(SCH_1):PAGE591_I368@PURE_QUANTA.Q_CAP(CHIPS)':
 C_PATH='@s9s_mb_2u_lib.s9s_mb_2u(sch_1):page591_i368@pure_quanta.q_cap(chips)',
 CDSVAR_REPCELL_ONSEMI='pure_quanta|Q_cap',
 VAR_0_ONSEMI='VALUE|2200PF|VOLTAGE|50V|TOLERANCE|10%|PACK_TYPE|C0402|MATERIAL|X~
7R|PART_NUMBER|CH2226K1B06|STANDARD||LIFECYCLE||ASS_PART||PART_NUMBER|CH2226K1B0~
6|JEDEC_TYPE|C0402|ALT_SYMBOLS|(C0402-0201)|VALUE|2200PF|RATED_VOLTAGE|50V|TOL|1~
0%|CLASS|DISCRETE|DESCRIPTION|CAP CHIP 2200P 50V(+-10%,X7R,0402)MUR|COMPONENT_TY~
PE|CHIP0402|LEAD_LENGTH||LPID||DATE|20150614|VARIANT_DEVICE_TYPE|Q_CAP-2200PF,50~
V,10%,C0402,X7R';

PART_NAME
 PC474 'Q_CAP_C0402-1UF,16V,10%,X6S,CHA':;

SECTION_NUMBER 1
 '@S9S_MB_2U_LIB.S9S_MB_2U(SCH_1):PAGE591_I313@PURE_QUANTA.Q_CAP(CHIPS)':
 C_PATH='@s9s_mb_2u_lib.s9s_mb_2u(sch_1):page591_i313@pure_quanta.q_cap(chips)';

PART_NAME
 PC473 'Q_CAP_0402-1000PF,50V,5%,EMPTYA':;

SECTION_NUMBER 1
 '@S9S_MB_2U_LIB.S9S_MB_2U(SCH_1):PAGE591_I307@PURE_QUANTA.Q_CAP(CHIPS)':
 C_PATH='@s9s_mb_2u_lib.s9s_mb_2u(sch_1):page591_i307@pure_quanta.q_cap(chips)';

PART_NAME
 PC472 'Q_CAP_0402-1000PF,50V,5%,X7R,TA':;

SECTION_NUMBER 1
 '@S9S_MB_2U_LIB.S9S_MB_2U(SCH_1):PAGE591_I302@PURE_QUANTA.Q_CAP(CHIPS)':
 C_PATH='@s9s_mb_2u_lib.s9s_mb_2u(sch_1):page591_i302@pure_quanta.q_cap(chips)';

PART_NAME
 PC471 'Q_CAP_0402-1000PF,50V,5%,EMPTYA':;

SECTION_NUMBER 1
 '@S9S_MB_2U_LIB.S9S_MB_2U(SCH_1):PAGE591_I219@PURE_QUANTA.Q_CAP(CHIPS)':
 C_PATH='@s9s_mb_2u_lib.s9s_mb_2u(sch_1):page591_i219@pure_quanta.q_cap(chips)';

PART_NAME
 PC470 'Q_CAP_0402-1000PF,50V,5%,X7R,TA':;

SECTION_NUMBER 1
 '@S9S_MB_2U_LIB.S9S_MB_2U(SCH_1):PAGE591_I218@PURE_QUANTA.Q_CAP(CHIPS)':
 C_PATH='@s9s_mb_2u_lib.s9s_mb_2u(sch_1):page591_i218@pure_quanta.q_cap(chips)';

PART_NAME
 PC469 'Q_CAP_0402-3300PF,50V,10%,X7R,A':;

SECTION_NUMBER 1
 '@S9S_MB_2U_LIB.S9S_MB_2U(SCH_1):PAGE591_I263@PURE_QUANTA.Q_CAP(CHIPS)':
 C_PATH='@s9s_mb_2u_lib.s9s_mb_2u(sch_1):page591_i263@pure_quanta.q_cap(chips)',
 CDSVAR_REPCELL_ONSEMI='pure_quanta|Q_cap',
 VAR_0_ONSEMI='VALUE|1NF|VOLTAGE|50V|TOLERANCE|10%|PACK_TYPE|0402|MATERIAL|X7R|P~
ART_NUMBER|CH21006KB16|STANDARD||LIFECYCLE||ASS_PART||PART_NUMBER|CH21006KB16|JE~
DEC_TYPE|C0402|ALT_SYMBOLS|(C0402-0201)|VALUE|1NF|RATED_VOLTAGE|50V|TOL|10%|CLAS~
S|DISCRETE|DESCRIPTION|CAP CHIP 1N 50V(+-10%,X7R,0402)EP|COMPONENT_TYPE|CHIP0402~
|LEAD_LENGTH||LPID||DATE|20100811|VARIANT_DEVICE_TYPE|Q_CAP-1NF,50V,10%,0402,X7R~
,CH2';

PART_NAME
 PC468 'Q_CAP_0402-3300PF,50V,10%,X7R,A':;

SECTION_NUMBER 1
 '@S9S_MB_2U_LIB.S9S_MB_2U(SCH_1):PAGE591_I254@PURE_QUANTA.Q_CAP(CHIPS)':
 C_PATH='@s9s_mb_2u_lib.s9s_mb_2u(sch_1):page591_i254@pure_quanta.q_cap(chips)',
 CDSVAR_REPCELL_ONSEMI='pure_quanta|Q_cap',
 VAR_0_ONSEMI='VALUE|1NF|VOLTAGE|50V|TOLERANCE|10%|PACK_TYPE|0402|MATERIAL|X7R|P~
ART_NUMBER|CH21006KB16|STANDARD||LIFECYCLE||ASS_PART||PART_NUMBER|CH21006KB16|JE~
DEC_TYPE|C0402|ALT_SYMBOLS|(C0402-0201)|VALUE|1NF|RATED_VOLTAGE|50V|TOL|10%|CLAS~
S|DISCRETE|DESCRIPTION|CAP CHIP 1N 50V(+-10%,X7R,0402)EP|COMPONENT_TYPE|CHIP0402~
|LEAD_LENGTH||LPID||DATE|20100811|VARIANT_DEVICE_TYPE|Q_CAP-1NF,50V,10%,0402,X7R~
,CH2';

PART_NAME
 PC467 'Q_CAP_C0402-1UF,16V,10%,X6S,CHA':;

SECTION_NUMBER 1
 '@S9S_MB_2U_LIB.S9S_MB_2U(SCH_1):PAGE591_I318@PURE_QUANTA.Q_CAP(CHIPS)':
 C_PATH='@s9s_mb_2u_lib.s9s_mb_2u(sch_1):page591_i318@pure_quanta.q_cap(chips)';

PART_NAME
 PU51_P1_2 'RAA2213404GNPHB0-RAA2213404GNPA':;

SECTION_NUMBER 1
 '@S9S_MB_2U_LIB.S9S_MB_2U(SCH_1):PAGE593_I183@PURE_QUANTA.RAA2213404GNPHB0(CHIPS)':
 C_PATH='@s9s_mb_2u_lib.s9s_mb_2u(sch_1):page593_i183@pure_quanta.raa2213404gnphb0~
(chips)',
 CDSVAR_REPCELL_ONSEMI='pure_quanta|fdmf5076',
 VAR_0_ONSEMI='VAR_REPLACED|RAA2213404GNPHB0|VAR_PARTNAME|FDMF5076|VALUE|FDMF507~
6|PART_TYPE|SMLF|MATERIAL|IC|PART_NUMBER|AL005076000|STANDARD||LIFECYCLE||PART_N~
UMBER|AL005076000|JEDEC_TYPE|PQFN17_TH_5X4XA|DESCRIPTION|IC OTHER(27P)FDMF5076(P~
QFN)|MANUFTR|ONS|MANUF_PN|FDMF5076|RD_CMPLS_LVL|EP(V1)|CMPLS_LVL|EP(V1)|FROM_PJ|~
S9S-KIMI|CLASS|IC|DIP_SMD||DATA|ONS_FDMF5076.pdf|EE_CHECK_LIST||FP_ECN|FDMF5076.~
msg|PSL||CREATOR||STATUS||MSD|NA|ESD_CDM|NA|ESD_HBM|NA|ESD_MM|NA|PIN_LENGTH_SHOR~
T_PIN|0 MILS|PIN_LENGTH_LONG_PIN|0 MILS|CREATEDAY|20200416|VARIANT_DEVICE_TYPE|F~
DMF5076-FDMF5076,SMLF,IC,AL00';

PART_NAME
 PU50_P1_1 'RAA2213404GNPHB0-RAA2213404GNPA':;

SECTION_NUMBER 1
 '@S9S_MB_2U_LIB.S9S_MB_2U(SCH_1):PAGE593_I148@PURE_QUANTA.RAA2213404GNPHB0(CHIPS)':
 C_PATH='@s9s_mb_2u_lib.s9s_mb_2u(sch_1):page593_i148@pure_quanta.raa2213404gnphb0~
(chips)',
 CDSVAR_REPCELL_ONSEMI='pure_quanta|fdmf5076',
 VAR_0_ONSEMI='VAR_REPLACED|RAA2213404GNPHB0|VAR_PARTNAME|FDMF5076|VALUE|FDMF507~
6|PART_TYPE|SMLF|MATERIAL|IC|PART_NUMBER|AL005076000|STANDARD||LIFECYCLE||PART_N~
UMBER|AL005076000|JEDEC_TYPE|PQFN17_TH_5X4XA|DESCRIPTION|IC OTHER(27P)FDMF5076(P~
QFN)|MANUFTR|ONS|MANUF_PN|FDMF5076|RD_CMPLS_LVL|EP(V1)|CMPLS_LVL|EP(V1)|FROM_PJ|~
S9S-KIMI|CLASS|IC|DIP_SMD||DATA|ONS_FDMF5076.pdf|EE_CHECK_LIST||FP_ECN|FDMF5076.~
msg|PSL||CREATOR||STATUS||MSD|NA|ESD_CDM|NA|ESD_HBM|NA|ESD_MM|NA|PIN_LENGTH_SHOR~
T_PIN|0 MILS|PIN_LENGTH_LONG_PIN|0 MILS|CREATEDAY|20200416|VARIANT_DEVICE_TYPE|F~
DMF5076-FDMF5076,SMLF,IC,AL00';

PART_NAME
 PR1797 'Q_RES_0402LF-0,5%,1/16W,CHIP,CA':;

SECTION_NUMBER 1
 '@S9S_MB_2U_LIB.S9S_MB_2U(SCH_1):PAGE593_I215@PURE_QUANTA.Q_RES(CHIPS)':
 C_PATH='@s9s_mb_2u_lib.s9s_mb_2u(sch_1):page593_i215@pure_quanta.q_res(chips)',
 CDSVAR_REPCELL_ONSEMI='pure_quanta|Q_res',
 VAR_0_ONSEMI='VALUE|0|TOLERANCE|5%|WATTAGE|1/16W|PACK_TYPE|0402LF|MATERIAL|EMPT~
Y|PART_NUMBER|CS00002JB38|STANDARD|End of Design|LIFECYCLE|Comp-Approve|PART_NUM~
BER|CS00002JB38|JEDEC_TYPE|R0402|ALT_SYMBOLS|(R0402-0201)|VALUE|0|TOL|5%|WATTAGE~
|1/16W|CLASS|IO|DESCRIPTION|RESISTOR CHIP 0 1/16W +-5%(0402)|COMPONENT_TYPE|CHIP~
0402|LEAD_LENGTH||DFM_EXCLUSION||DAY|20100618|VARIANT_DEVICE_TYPE|Q_RES-0,5%,1/1~
6W,0402LF,EMPTY,';

PART_NAME
 PR1796 'Q_RES_0402LF-0,5%,1/16W,CHIP,CA':;

SECTION_NUMBER 1
 '@S9S_MB_2U_LIB.S9S_MB_2U(SCH_1):PAGE593_I219@PURE_QUANTA.Q_RES(CHIPS)':
 C_PATH='@s9s_mb_2u_lib.s9s_mb_2u(sch_1):page593_i219@pure_quanta.q_res(chips)',
 CDSVAR_REPCELL_ONSEMI='pure_quanta|Q_res',
 VAR_0_ONSEMI='VALUE|0|TOLERANCE|5%|WATTAGE|1/16W|PACK_TYPE|0402LF|MATERIAL|EMPT~
Y|PART_NUMBER|CS00002JB38|STANDARD|End of Design|LIFECYCLE|Comp-Approve|PART_NUM~
BER|CS00002JB38|JEDEC_TYPE|R0402|ALT_SYMBOLS|(R0402-0201)|VALUE|0|TOL|5%|WATTAGE~
|1/16W|CLASS|IO|DESCRIPTION|RESISTOR CHIP 0 1/16W +-5%(0402)|COMPONENT_TYPE|CHIP~
0402|LEAD_LENGTH||DFM_EXCLUSION||DAY|20100618|VARIANT_DEVICE_TYPE|Q_RES-0,5%,1/1~
6W,0402LF,EMPTY,';

PART_NAME
 PR1795 'Q_RES_0402LF-4.7,1%,1/16W,CHIPA':;

SECTION_NUMBER 1
 '@S9S_MB_2U_LIB.S9S_MB_2U(SCH_1):PAGE593_I213@PURE_QUANTA.Q_RES(CHIPS)':
 C_PATH='@s9s_mb_2u_lib.s9s_mb_2u(sch_1):page593_i213@pure_quanta.q_res(chips)',
 CDSVAR_REPCELL_ONSEMI='pure_quanta|Q_res',
 VAR_0_ONSEMI='VALUE|0|TOLERANCE|5%|WATTAGE|1/16W|PACK_TYPE|0402LF|MATERIAL|CHIP~
|PART_NUMBER|CS00002JB38|STANDARD|End of Design|LIFECYCLE|Comp-Approve|PART_NUMB~
ER|CS00002JB38|JEDEC_TYPE|R0402|ALT_SYMBOLS|(R0402-0201)|VALUE|0|TOL|5%|WATTAGE|~
1/16W|CLASS|DISCRETE|DESCRIPTION|RESISTOR CHIP 0 1/16W +-5%(0402)|COMPONENT_TYPE~
|CHIP0402|LEAD_LENGTH||DFM_EXCLUSION||DAY|20100618|VARIANT_DEVICE_TYPE|Q_RES-0,5~
%,1/16W,0402LF,CHIP,C';

PART_NAME
 PR1794 'Q_RES_0402LF-4.7,1%,1/16W,CHIPA':;

SECTION_NUMBER 1
 '@S9S_MB_2U_LIB.S9S_MB_2U(SCH_1):PAGE593_I212@PURE_QUANTA.Q_RES(CHIPS)':
 C_PATH='@s9s_mb_2u_lib.s9s_mb_2u(sch_1):page593_i212@pure_quanta.q_res(chips)',
 CDSVAR_REPCELL_ONSEMI='pure_quanta|Q_res',
 VAR_0_ONSEMI='VALUE|0|TOLERANCE|5%|WATTAGE|1/16W|PACK_TYPE|0402LF|MATERIAL|CHIP~
|PART_NUMBER|CS00002JB38|STANDARD|End of Design|LIFECYCLE|Comp-Approve|PART_NUMB~
ER|CS00002JB38|JEDEC_TYPE|R0402|ALT_SYMBOLS|(R0402-0201)|VALUE|0|TOL|5%|WATTAGE|~
1/16W|CLASS|DISCRETE|DESCRIPTION|RESISTOR CHIP 0 1/16W +-5%(0402)|COMPONENT_TYPE~
|CHIP0402|LEAD_LENGTH||DFM_EXCLUSION||DAY|20100618|VARIANT_DEVICE_TYPE|Q_RES-0,5~
%,1/16W,0402LF,CHIP,C';

PART_NAME
 PR1727 'Q_RES_0402LF-8.87K,1%,1/16W,EMA':;

SECTION_NUMBER 1
 '@S9S_MB_2U_LIB.S9S_MB_2U(SCH_1):PAGE593_I230@PURE_QUANTA.Q_RES(CHIPS)':
 C_PATH='@s9s_mb_2u_lib.s9s_mb_2u(sch_1):page593_i230@pure_quanta.q_res(chips)';

PART_NAME
 PR1726 'Q_RES_0402LF-8.87K,1%,1/16W,EMA':;

SECTION_NUMBER 1
 '@S9S_MB_2U_LIB.S9S_MB_2U(SCH_1):PAGE593_I228@PURE_QUANTA.Q_RES(CHIPS)':
 C_PATH='@s9s_mb_2u_lib.s9s_mb_2u(sch_1):page593_i228@pure_quanta.q_res(chips)';

PART_NAME
 PR255 'Q_RES_0402LF-2.2,1%,1/16W,CHIPA':;

SECTION_NUMBER 1
 '@S9S_MB_2U_LIB.S9S_MB_2U(SCH_1):PAGE593_I165@PURE_QUANTA.Q_RES(CHIPS)':
 C_PATH='@s9s_mb_2u_lib.s9s_mb_2u(sch_1):page593_i165@pure_quanta.q_res(chips)';

PART_NAME
 PR254 'Q_RES_0402LF-2.2,1%,1/16W,CHIPA':;

SECTION_NUMBER 1
 '@S9S_MB_2U_LIB.S9S_MB_2U(SCH_1):PAGE593_I154@PURE_QUANTA.Q_RES(CHIPS)':
 C_PATH='@s9s_mb_2u_lib.s9s_mb_2u(sch_1):page593_i154@pure_quanta.q_res(chips)';

PART_NAME
 PL23 'Q_INDUCTOR_SMLF-100NH/16A,IND,A':;

SECTION_NUMBER 1
 '@S9S_MB_2U_LIB.S9S_MB_2U(SCH_1):PAGE593_I141@PURE_QUANTA.Q_INDUCTOR(CHIPS)':
 C_PATH='@s9s_mb_2u_lib.s9s_mb_2u(sch_1):page593_i141@pure_quanta.q_inductor(chips~
)';

PART_NAME
 PL22 'Q_INDUCTOR_SMLF-130NH/95A,IND,A':;

SECTION_NUMBER 1
 '@S9S_MB_2U_LIB.S9S_MB_2U(SCH_1):PAGE593_I182@PURE_QUANTA.Q_INDUCTOR(CHIPS)':
 C_PATH='@s9s_mb_2u_lib.s9s_mb_2u(sch_1):page593_i182@pure_quanta.q_inductor(chips~
)';

PART_NAME
 PL21 'Q_INDUCTOR_SMLF-130NH/95A,IND,A':;

SECTION_NUMBER 1
 '@S9S_MB_2U_LIB.S9S_MB_2U(SCH_1):PAGE593_I150@PURE_QUANTA.Q_INDUCTOR(CHIPS)':
 C_PATH='@s9s_mb_2u_lib.s9s_mb_2u(sch_1):page593_i150@pure_quanta.q_inductor(chips~
)';

PART_NAME
 PC1596 'Q_CAPP_RDLF-560UF,2.5V,20%,ALUA':;

SECTION_NUMBER 1
 '@S9S_MB_2U_LIB.S9S_MB_2U(SCH_1):PAGE593_I205@PURE_QUANTA.Q_CAPP(CHIPS)':
 C_PATH='@s9s_mb_2u_lib.s9s_mb_2u(sch_1):page593_i205@pure_quanta.q_capp(chips)';

PART_NAME
 PC1595 'Q_CAPP_RDLF-560UF,2.5V,20%,ALUA':;

SECTION_NUMBER 1
 '@S9S_MB_2U_LIB.S9S_MB_2U(SCH_1):PAGE593_I207@PURE_QUANTA.Q_CAPP(CHIPS)':
 C_PATH='@s9s_mb_2u_lib.s9s_mb_2u(sch_1):page593_i207@pure_quanta.q_capp(chips)';

PART_NAME
 PC1594 'Q_CAPP_RDLLF-330UF,2V,35%,C_POA':;

SECTION_NUMBER 1
 '@S9S_MB_2U_LIB.S9S_MB_2U(SCH_1):PAGE593_I206@PURE_QUANTA.Q_CAPP(CHIPS)':
 C_PATH='@s9s_mb_2u_lib.s9s_mb_2u(sch_1):page593_i206@pure_quanta.q_capp(chips)';

PART_NAME
 PC1593 'Q_CAPP_RDLF-560UF,2.5V,20%,ALUA':;

SECTION_NUMBER 1
 '@S9S_MB_2U_LIB.S9S_MB_2U(SCH_1):PAGE593_I210@PURE_QUANTA.Q_CAPP(CHIPS)':
 C_PATH='@s9s_mb_2u_lib.s9s_mb_2u(sch_1):page593_i210@pure_quanta.q_capp(chips)';

PART_NAME
 PC1588 'Q_CAPP_RDLLF-330UF,2V,35%,C_POA':;

SECTION_NUMBER 1
 '@S9S_MB_2U_LIB.S9S_MB_2U(SCH_1):PAGE593_I209@PURE_QUANTA.Q_CAPP(CHIPS)':
 C_PATH='@s9s_mb_2u_lib.s9s_mb_2u(sch_1):page593_i209@pure_quanta.q_capp(chips)';

PART_NAME
 PC1365 'Q_CAP_0402-0.1UF,25V,10%,X7R,CA':;

SECTION_NUMBER 1
 '@S9S_MB_2U_LIB.S9S_MB_2U(SCH_1):PAGE593_I221@PURE_QUANTA.Q_CAP(CHIPS)':
 C_PATH='@s9s_mb_2u_lib.s9s_mb_2u(sch_1):page593_i221@pure_quanta.q_cap(chips)',
 CDSVAR_REPCELL_ONSEMI='pure_quanta|Q_cap',
 VAR_0_ONSEMI='VALUE|0.1UF|VOLTAGE|25V|TOLERANCE|10%|PACK_TYPE|0402|MATERIAL|EMP~
TY|PART_NUMBER|CH4104K1B00|STANDARD||LIFECYCLE||ASS_PART||PART_NUMBER|CH4104K1B0~
0|JEDEC_TYPE|C0402|ALT_SYMBOLS|(C0402_OCTAGONXA,C0402-0201)|VALUE|NA|RATED_VOLTA~
GE|25V|TOL|10%|CLASS|IO|DESCRIPTION|CAP CHIP 0.1U 25V(+-10%,X7R,0402)|COMPONENT_~
TYPE|CHIP0402|LEAD_LENGTH||LPID||DATE|20160113|VARIANT_DEVICE_TYPE|Q_CAP-0.1UF,2~
5V,10%,0402,EMPTY';

PART_NAME
 PC1364 'Q_CAP_0402-0.1UF,25V,10%,X7R,CA':;

SECTION_NUMBER 1
 '@S9S_MB_2U_LIB.S9S_MB_2U(SCH_1):PAGE593_I223@PURE_QUANTA.Q_CAP(CHIPS)':
 C_PATH='@s9s_mb_2u_lib.s9s_mb_2u(sch_1):page593_i223@pure_quanta.q_cap(chips)',
 CDSVAR_REPCELL_ONSEMI='pure_quanta|Q_cap',
 VAR_0_ONSEMI='VALUE|0.1UF|VOLTAGE|25V|TOLERANCE|10%|PACK_TYPE|0402|MATERIAL|EMP~
TY|PART_NUMBER|CH4104K1B00|STANDARD||LIFECYCLE||ASS_PART||PART_NUMBER|CH4104K1B0~
0|JEDEC_TYPE|C0402|ALT_SYMBOLS|(C0402_OCTAGONXA,C0402-0201)|VALUE|NA|RATED_VOLTA~
GE|25V|TOL|10%|CLASS|IO|DESCRIPTION|CAP CHIP 0.1U 25V(+-10%,X7R,0402)|COMPONENT_~
TYPE|CHIP0402|LEAD_LENGTH||LPID||DATE|20160113|VARIANT_DEVICE_TYPE|Q_CAP-0.1UF,2~
5V,10%,0402,EMPTY';

PART_NAME
 PC461 'Q_CAPP_THLF-270UF,16V,20%,OSCOA':;

SECTION_NUMBER 1
 '@S9S_MB_2U_LIB.S9S_MB_2U(SCH_1):PAGE593_I143@PURE_QUANTA.Q_CAPP(CHIPS)':
 C_PATH='@s9s_mb_2u_lib.s9s_mb_2u(sch_1):page593_i143@pure_quanta.q_capp(chips)';

PART_NAME
 PC460 'Q_CAPP_THLF-270UF,16V,20%,OSCOA':;

SECTION_NUMBER 1
 '@S9S_MB_2U_LIB.S9S_MB_2U(SCH_1):PAGE593_I142@PURE_QUANTA.Q_CAPP(CHIPS)':
 C_PATH='@s9s_mb_2u_lib.s9s_mb_2u(sch_1):page593_i142@pure_quanta.q_capp(chips)';

PART_NAME
 PC458_P1_2 'Q_CAP_0805-22UF,4V,20%,X6S,TMPA':;

SECTION_NUMBER 1
 '@S9S_MB_2U_LIB.S9S_MB_2U(SCH_1):PAGE593_I178@PURE_QUANTA.Q_CAP(CHIPS)':
 C_PATH='@s9s_mb_2u_lib.s9s_mb_2u(sch_1):page593_i178@pure_quanta.q_cap(chips)';

PART_NAME
 PC457_P1_1 'Q_CAP_0805-22UF,4V,20%,X6S,TMPA':;

SECTION_NUMBER 1
 '@S9S_MB_2U_LIB.S9S_MB_2U(SCH_1):PAGE593_I126@PURE_QUANTA.Q_CAP(CHIPS)':
 C_PATH='@s9s_mb_2u_lib.s9s_mb_2u(sch_1):page593_i126@pure_quanta.q_cap(chips)';

PART_NAME
 PC456_P1_2 'Q_CAP_0805-22UF,4V,20%,X6S,TMPA':;

SECTION_NUMBER 1
 '@S9S_MB_2U_LIB.S9S_MB_2U(SCH_1):PAGE593_I177@PURE_QUANTA.Q_CAP(CHIPS)':
 C_PATH='@s9s_mb_2u_lib.s9s_mb_2u(sch_1):page593_i177@pure_quanta.q_cap(chips)';

PART_NAME
 PC455_P1_1 'Q_CAP_0805-22UF,4V,20%,X6S,TMPA':;

SECTION_NUMBER 1
 '@S9S_MB_2U_LIB.S9S_MB_2U(SCH_1):PAGE593_I125@PURE_QUANTA.Q_CAP(CHIPS)':
 C_PATH='@s9s_mb_2u_lib.s9s_mb_2u(sch_1):page593_i125@pure_quanta.q_cap(chips)';

PART_NAME
 PC452_P1_1 'Q_CAP_C0402-100NF,50V,10%,X7R,A':;

SECTION_NUMBER 1
 '@S9S_MB_2U_LIB.S9S_MB_2U(SCH_1):PAGE593_I105@PURE_QUANTA.Q_CAP(CHIPS)':
 C_PATH='@s9s_mb_2u_lib.s9s_mb_2u(sch_1):page593_i105@pure_quanta.q_cap(chips)';

PART_NAME
 PC451_P1_2 'Q_CAP_C0805-22UF,16V,20%,X6S,CA':;

SECTION_NUMBER 1
 '@S9S_MB_2U_LIB.S9S_MB_2U(SCH_1):PAGE593_I173@PURE_QUANTA.Q_CAP(CHIPS)':
 C_PATH='@s9s_mb_2u_lib.s9s_mb_2u(sch_1):page593_i173@pure_quanta.q_cap(chips)';

PART_NAME
 PC450_P1_1 'Q_CAP_C0805-22UF,16V,20%,X6S,CA':;

SECTION_NUMBER 1
 '@S9S_MB_2U_LIB.S9S_MB_2U(SCH_1):PAGE593_I115@PURE_QUANTA.Q_CAP(CHIPS)':
 C_PATH='@s9s_mb_2u_lib.s9s_mb_2u(sch_1):page593_i115@pure_quanta.q_cap(chips)';

PART_NAME
 PC449_P1_2 'Q_CAP_C0805-22UF,16V,20%,X6S,CA':;

SECTION_NUMBER 1
 '@S9S_MB_2U_LIB.S9S_MB_2U(SCH_1):PAGE593_I172@PURE_QUANTA.Q_CAP(CHIPS)':
 C_PATH='@s9s_mb_2u_lib.s9s_mb_2u(sch_1):page593_i172@pure_quanta.q_cap(chips)';

PART_NAME
 PC448_P1_1 'Q_CAP_C0805-22UF,16V,20%,X6S,CA':;

SECTION_NUMBER 1
 '@S9S_MB_2U_LIB.S9S_MB_2U(SCH_1):PAGE593_I113@PURE_QUANTA.Q_CAP(CHIPS)':
 C_PATH='@s9s_mb_2u_lib.s9s_mb_2u(sch_1):page593_i113@pure_quanta.q_cap(chips)';

PART_NAME
 PC447 'Q_CAP_C0402-100NF,50V,10%,X7R,A':;

SECTION_NUMBER 1
 '@S9S_MB_2U_LIB.S9S_MB_2U(SCH_1):PAGE593_I226@PURE_QUANTA.Q_CAP(CHIPS)':
 C_PATH='@s9s_mb_2u_lib.s9s_mb_2u(sch_1):page593_i226@pure_quanta.q_cap(chips)';

PART_NAME
 PC446 'Q_CAP_C0402-100NF,50V,10%,X7R,A':;

SECTION_NUMBER 1
 '@S9S_MB_2U_LIB.S9S_MB_2U(SCH_1):PAGE593_I225@PURE_QUANTA.Q_CAP(CHIPS)':
 C_PATH='@s9s_mb_2u_lib.s9s_mb_2u(sch_1):page593_i225@pure_quanta.q_cap(chips)';

PART_NAME
 PC445_P1_2 'Q_CAP_C0402-1UF,16V,10%,X6S,CHA':;

SECTION_NUMBER 1
 '@S9S_MB_2U_LIB.S9S_MB_2U(SCH_1):PAGE593_I170@PURE_QUANTA.Q_CAP(CHIPS)':
 C_PATH='@s9s_mb_2u_lib.s9s_mb_2u(sch_1):page593_i170@pure_quanta.q_cap(chips)';

PART_NAME
 PC444_P1_1 'Q_CAP_C0402-1UF,16V,10%,X6S,CHA':;

SECTION_NUMBER 1
 '@S9S_MB_2U_LIB.S9S_MB_2U(SCH_1):PAGE593_I112@PURE_QUANTA.Q_CAP(CHIPS)':
 C_PATH='@s9s_mb_2u_lib.s9s_mb_2u(sch_1):page593_i112@pure_quanta.q_cap(chips)';

PART_NAME
 PC443_P1_2 'Q_CAP_0402-3300PF,50V,10%,X7R,A':;

SECTION_NUMBER 1
 '@S9S_MB_2U_LIB.S9S_MB_2U(SCH_1):PAGE593_I171@PURE_QUANTA.Q_CAP(CHIPS)':
 C_PATH='@s9s_mb_2u_lib.s9s_mb_2u(sch_1):page593_i171@pure_quanta.q_cap(chips)';

PART_NAME
 PC442_P1_1 'Q_CAP_0402-3300PF,50V,10%,X7R,A':;

SECTION_NUMBER 1
 '@S9S_MB_2U_LIB.S9S_MB_2U(SCH_1):PAGE593_I111@PURE_QUANTA.Q_CAP(CHIPS)':
 C_PATH='@s9s_mb_2u_lib.s9s_mb_2u(sch_1):page593_i111@pure_quanta.q_cap(chips)';

PART_NAME
 PC441 'Q_CAP_C0402-2.2UF,10V,10%,X6S,A':;

SECTION_NUMBER 1
 '@S9S_MB_2U_LIB.S9S_MB_2U(SCH_1):PAGE593_I164@PURE_QUANTA.Q_CAP(CHIPS)':
 C_PATH='@s9s_mb_2u_lib.s9s_mb_2u(sch_1):page593_i164@pure_quanta.q_cap(chips)';

PART_NAME
 PC440 'Q_CAP_C0402-2.2UF,10V,10%,X6S,A':;

SECTION_NUMBER 1
 '@S9S_MB_2U_LIB.S9S_MB_2U(SCH_1):PAGE593_I151@PURE_QUANTA.Q_CAP(CHIPS)':
 C_PATH='@s9s_mb_2u_lib.s9s_mb_2u(sch_1):page593_i151@pure_quanta.q_cap(chips)';

PART_NAME
 PU49 'RAA2213404GNPHB0-RAA2213404GNPA':;

SECTION_NUMBER 1
 '@S9S_MB_2U_LIB.S9S_MB_2U(SCH_1):PAGE595_I26@PURE_QUANTA.RAA2213404GNPHB0(CHIPS)':
 C_PATH='@s9s_mb_2u_lib.s9s_mb_2u(sch_1):page595_i26@pure_quanta.raa2213404gnphb0(~
chips)',
 CDSVAR_REPCELL_ONSEMI='pure_quanta|fdmf5076',
 VAR_0_ONSEMI='VAR_REPLACED|RAA2213404GNPHB0|VAR_PARTNAME|FDMF5076|VALUE|FDMF507~
6|PART_TYPE|SMLF|MATERIAL|IC|PART_NUMBER|AL005076000|STANDARD||LIFECYCLE||PART_N~
UMBER|AL005076000|JEDEC_TYPE|PQFN17_TH_5X4XA|DESCRIPTION|IC OTHER(27P)FDMF5076(P~
QFN)|MANUFTR|ONS|MANUF_PN|FDMF5076|RD_CMPLS_LVL|EP(V1)|CMPLS_LVL|EP(V1)|FROM_PJ|~
S9S-KIMI|CLASS|IC|DIP_SMD||DATA|ONS_FDMF5076.pdf|EE_CHECK_LIST||FP_ECN|FDMF5076.~
msg|PSL||CREATOR||STATUS||MSD|NA|ESD_CDM|NA|ESD_HBM|NA|ESD_MM|NA|PIN_LENGTH_SHOR~
T_PIN|0 MILS|PIN_LENGTH_LONG_PIN|0 MILS|CREATEDAY|20200416|VARIANT_DEVICE_TYPE|F~
DMF5076-FDMF5076,SMLF,IC,AL00';

PART_NAME
 PR1799 'Q_RES_0402LF-0,5%,1/16W,CHIP,CA':;

SECTION_NUMBER 1
 '@S9S_MB_2U_LIB.S9S_MB_2U(SCH_1):PAGE595_I49@PURE_QUANTA.Q_RES(CHIPS)':
 C_PATH='@s9s_mb_2u_lib.s9s_mb_2u(sch_1):page595_i49@pure_quanta.q_res(chips)',
 CDSVAR_REPCELL_ONSEMI='pure_quanta|Q_res',
 VAR_0_ONSEMI='VALUE|0|TOLERANCE|5%|WATTAGE|1/16W|PACK_TYPE|0402LF|MATERIAL|EMPT~
Y|PART_NUMBER|CS00002JB38|STANDARD|End of Design|LIFECYCLE|Comp-Approve|PART_NUM~
BER|CS00002JB38|JEDEC_TYPE|R0402|ALT_SYMBOLS|(R0402-0201)|VALUE|0|TOL|5%|WATTAGE~
|1/16W|CLASS|IO|DESCRIPTION|RESISTOR CHIP 0 1/16W +-5%(0402)|COMPONENT_TYPE|CHIP~
0402|LEAD_LENGTH||DFM_EXCLUSION||DAY|20100618|VARIANT_DEVICE_TYPE|Q_RES-0,5%,1/1~
6W,0402LF,EMPTY,';

PART_NAME
 PR1798 'Q_RES_0402LF-4.7,1%,1/16W,CHIPA':;

SECTION_NUMBER 1
 '@S9S_MB_2U_LIB.S9S_MB_2U(SCH_1):PAGE595_I47@PURE_QUANTA.Q_RES(CHIPS)':
 C_PATH='@s9s_mb_2u_lib.s9s_mb_2u(sch_1):page595_i47@pure_quanta.q_res(chips)',
 CDSVAR_REPCELL_ONSEMI='pure_quanta|Q_res',
 VAR_0_ONSEMI='VALUE|0|TOLERANCE|5%|WATTAGE|1/16W|PACK_TYPE|0402LF|MATERIAL|CHIP~
|PART_NUMBER|CS00002JB38|STANDARD|End of Design|LIFECYCLE|Comp-Approve|PART_NUMB~
ER|CS00002JB38|JEDEC_TYPE|R0402|ALT_SYMBOLS|(R0402-0201)|VALUE|0|TOL|5%|WATTAGE|~
1/16W|CLASS|DISCRETE|DESCRIPTION|RESISTOR CHIP 0 1/16W +-5%(0402)|COMPONENT_TYPE~
|CHIP0402|LEAD_LENGTH||DFM_EXCLUSION||DAY|20100618|VARIANT_DEVICE_TYPE|Q_RES-0,5~
%,1/16W,0402LF,CHIP,C';

PART_NAME
 PR1728 'Q_RES_0402LF-8.87K,1%,1/16W,EMA':;

SECTION_NUMBER 1
 '@S9S_MB_2U_LIB.S9S_MB_2U(SCH_1):PAGE595_I55@PURE_QUANTA.Q_RES(CHIPS)':
 C_PATH='@s9s_mb_2u_lib.s9s_mb_2u(sch_1):page595_i55@pure_quanta.q_res(chips)';

PART_NAME
 PR250 'Q_RES_0402LF-2.2,1%,1/16W,CHIPA':;

SECTION_NUMBER 1
 '@S9S_MB_2U_LIB.S9S_MB_2U(SCH_1):PAGE595_I19@PURE_QUANTA.Q_RES(CHIPS)':
 C_PATH='@s9s_mb_2u_lib.s9s_mb_2u(sch_1):page595_i19@pure_quanta.q_res(chips)';

PART_NAME
 PL20 'Q_INDUCTOR_SMLF-320NH/38A,IND,A':;

SECTION_NUMBER 1
 '@S9S_MB_2U_LIB.S9S_MB_2U(SCH_1):PAGE595_I40@PURE_QUANTA.Q_INDUCTOR(CHIPS)':
 C_PATH='@s9s_mb_a_lib.s9s_mb_a(sch_1):page595_i40@pure_quanta.q_inductor(chips)~
';

PART_NAME
 PC2199 'Q_CAPP_RDLF-560UF,2.5V,20%,ALUA':;

SECTION_NUMBER 1
 '@S9S_MB_2U_LIB.S9S_MB_2U(SCH_1):PAGE595_I42@PURE_QUANTA.Q_CAPP(CHIPS)':
 C_PATH='@s9s_mb_2u_lib.s9s_mb_2u(sch_1):page595_i42@pure_quanta.q_capp(chips)';

PART_NAME
 PC1930 'Q_CAPP_SMLF-470UF,2.5V,20%,POSA':;

SECTION_NUMBER 1
 '@S9S_MB_2U_LIB.S9S_MB_2U(SCH_1):PAGE595_I43@PURE_QUANTA.Q_CAPP(CHIPS)':
 C_PATH='@s9s_mb_2u_lib.s9s_mb_2u(sch_1):page595_i43@pure_quanta.q_capp(chips)';

PART_NAME
 PC1366 'Q_CAP_0402-0.1UF,25V,10%,X7R,CA':;

SECTION_NUMBER 1
 '@S9S_MB_2U_LIB.S9S_MB_2U(SCH_1):PAGE595_I52@PURE_QUANTA.Q_CAP(CHIPS)':
 C_PATH='@s9s_mb_2u_lib.s9s_mb_2u(sch_1):page595_i52@pure_quanta.q_cap(chips)',
 CDSVAR_REPCELL_ONSEMI='pure_quanta|Q_cap',
 VAR_0_ONSEMI='VALUE|0.1UF|VOLTAGE|25V|TOLERANCE|10%|PACK_TYPE|0402|MATERIAL|EMP~
TY|PART_NUMBER|CH4104K1B00|STANDARD||LIFECYCLE||ASS_PART||PART_NUMBER|CH4104K1B0~
0|JEDEC_TYPE|C0402|ALT_SYMBOLS|(C0402_OCTAGONXA,C0402-0201)|VALUE|NA|RATED_VOLTA~
GE|25V|TOL|10%|CLASS|IO|DESCRIPTION|CAP CHIP 0.1U 25V(+-10%,X7R,0402)|COMPONENT_~
TYPE|CHIP0402|LEAD_LENGTH||LPID||DATE|20160113|VARIANT_DEVICE_TYPE|Q_CAP-0.1UF,2~
5V,10%,0402,EMPTY';

PART_NAME
 PC437 'Q_CAP_0805-22UF,4V,20%,X6S,TMPA':;

SECTION_NUMBER 1
 '@S9S_MB_2U_LIB.S9S_MB_2U(SCH_1):PAGE595_I6@PURE_QUANTA.Q_CAP(CHIPS)':
 C_PATH='@s9s_mb_2u_lib.s9s_mb_2u(sch_1):page595_i6@pure_quanta.q_cap(chips)';

PART_NAME
 PC435 'Q_CAP_0805-22UF,4V,20%,X6S,TMPA':;

SECTION_NUMBER 1
 '@S9S_MB_2U_LIB.S9S_MB_2U(SCH_1):PAGE595_I41@PURE_QUANTA.Q_CAP(CHIPS)':
 C_PATH='@s9s_mb_2u_lib.s9s_mb_2u(sch_1):page595_i41@pure_quanta.q_cap(chips)';

PART_NAME
 PC434 'Q_CAP_C0402-100NF,50V,10%,X7R,A':;

SECTION_NUMBER 1
 '@S9S_MB_2U_LIB.S9S_MB_2U(SCH_1):PAGE595_I8@PURE_QUANTA.Q_CAP(CHIPS)':
 C_PATH='@s9s_mb_2u_lib.s9s_mb_2u(sch_1):page595_i8@pure_quanta.q_cap(chips)';

PART_NAME
 PC433 'Q_CAP_C0805-22UF,16V,20%,X6S,CA':;

SECTION_NUMBER 1
 '@S9S_MB_2U_LIB.S9S_MB_2U(SCH_1):PAGE595_I14@PURE_QUANTA.Q_CAP(CHIPS)':
 C_PATH='@s9s_mb_2u_lib.s9s_mb_2u(sch_1):page595_i14@pure_quanta.q_cap(chips)';

PART_NAME
 PC432 'Q_CAP_C0805-22UF,16V,20%,X6S,CA':;

SECTION_NUMBER 1
 '@S9S_MB_2U_LIB.S9S_MB_2U(SCH_1):PAGE595_I15@PURE_QUANTA.Q_CAP(CHIPS)':
 C_PATH='@s9s_mb_2u_lib.s9s_mb_2u(sch_1):page595_i15@pure_quanta.q_cap(chips)';

PART_NAME
 PC431 'Q_CAP_C0402-100NF,50V,10%,X7R,A':;

SECTION_NUMBER 1
 '@S9S_MB_2U_LIB.S9S_MB_2U(SCH_1):PAGE595_I53@PURE_QUANTA.Q_CAP(CHIPS)':
 C_PATH='@s9s_mb_2u_lib.s9s_mb_2u(sch_1):page595_i53@pure_quanta.q_cap(chips)';

PART_NAME
 PC430 'Q_CAP_C0402-1UF,16V,10%,X6S,CHA':;

SECTION_NUMBER 1
 '@S9S_MB_2U_LIB.S9S_MB_2U(SCH_1):PAGE595_I16@PURE_QUANTA.Q_CAP(CHIPS)':
 C_PATH='@s9s_mb_2u_lib.s9s_mb_2u(sch_1):page595_i16@pure_quanta.q_cap(chips)';

PART_NAME
 PC429 'Q_CAP_0402-3300PF,50V,10%,X7R,A':;

SECTION_NUMBER 1
 '@S9S_MB_2U_LIB.S9S_MB_2U(SCH_1):PAGE595_I17@PURE_QUANTA.Q_CAP(CHIPS)':
 C_PATH='@s9s_mb_2u_lib.s9s_mb_2u(sch_1):page595_i17@pure_quanta.q_cap(chips)';

PART_NAME
 PC428 'Q_CAP_C0402-2.2UF,10V,10%,X6S,A':;

SECTION_NUMBER 1
 '@S9S_MB_2U_LIB.S9S_MB_2U(SCH_1):PAGE595_I20@PURE_QUANTA.Q_CAP(CHIPS)':
 C_PATH='@s9s_mb_2u_lib.s9s_mb_2u(sch_1):page595_i20@pure_quanta.q_cap(chips)';

PART_NAME
 R1771 'Q_RES_0402LF-100,1%,1/16W,EMPTA':;

SECTION_NUMBER 1
 '@S9S_MB_2U_LIB.S9S_MB_2U(SCH_1):PAGE597_I216@PURE_QUANTA.Q_RES(CHIPS)':
 C_PATH='@s9s_mb_2u_lib.s9s_mb_2u(sch_1):page597_i216@pure_quanta.q_res(chips)';

PART_NAME
 R1770 'Q_RES_0402LF-49.9     ,1%  ,1/B':;

SECTION_NUMBER 1
 '@S9S_MB_2U_LIB.S9S_MB_2U(SCH_1):PAGE597_I215@PURE_QUANTA.Q_RES(CHIPS)':
 C_PATH='@s9s_mb_2u_lib.s9s_mb_2u(sch_1):page597_i215@pure_quanta.q_res(chips)';

PART_NAME
 PU21 'ISL69260IRAZT-ISL69260IRAZ-T,SA':;

SECTION_NUMBER 1
 '@S9S_MB_2U_LIB.S9S_MB_2U(SCH_1):PAGE597_I220@PURE_QUANTA.ISL69260IRAZT(CHIPS)':
 C_PATH='@s9s_mb_2u_lib.s9s_mb_2u(sch_1):page597_i220@pure_quanta.isl69260irazt(ch~
ips)',
 CDSVAR_REPCELL_ONSEMI='pure_quanta|fd5001',
 VAR_0_ONSEMI='VAR_REPLACED|ISL69260IRAZT|VAR_PARTNAME|FD5001|VALUE|FD5001|PART_~
TYPE|SMLF|MATERIAL|IC|PART_NUMBER|AL005001004|STANDARD||LIFECYCLE||PART_NUMBER|A~
L005001004|JEDEC_TYPE|VFQFPN40_TH_0-4_5X5XC|DESCRIPTION|IC OTHER(40P) FD5001(QFN~
)|MANUFTR|ONS|MANUF_PN|FD5001|RD_CMPLS_LVL|EP(V1)|CMPLS_LVL||FROM_PJ|S9S-KIMI|CL~
ASS|IC|DIP_SMD||DATA|ONS_FD5001.pdf|EE_CHECK_LIST||FP_ECN|FD5001.msg|PSL||CREATO~
R||STATUS||MSD|NA|ESD_CDM|NA|ESD_HBM|NA|ESD_MM|NA|PIN_LENGTH_SHORT_PIN|0 MILS|PI~
N_LENGTH_LONG_PIN|0 MILS|CREATEDAY|20200421|VARIANT_DEVICE_TYPE|FD5001-FD5001,SM~
LF,IC,AL005001';

PART_NAME
 PR1312 'Q_RES_0402LF-0,5%,1/16W,CHIP,CA':;

SECTION_NUMBER 1
 '@S9S_MB_2U_LIB.S9S_MB_2U(SCH_1):PAGE597_I214@PURE_QUANTA.Q_RES(CHIPS)':
 C_PATH='@s9s_mb_2u_lib.s9s_mb_2u(sch_1):page597_i214@pure_quanta.q_res(chips)';

PART_NAME
 PR561 'Q_RES_0402LF-100,1%,1/16W,CHIPA':;

SECTION_NUMBER 1
 '@S9S_MB_2U_LIB.S9S_MB_2U(SCH_1):PAGE597_I128@PURE_QUANTA.Q_RES(CHIPS)':
 C_PATH='@s9s_mb_2u_lib.s9s_mb_2u(sch_1):page597_i128@pure_quanta.q_res(chips)';

PART_NAME
 PR560 'Q_RES_0402LF-100,1%,1/16W,CHIPA':;

SECTION_NUMBER 1
 '@S9S_MB_2U_LIB.S9S_MB_2U(SCH_1):PAGE597_I117@PURE_QUANTA.Q_RES(CHIPS)':
 C_PATH='@s9s_mb_2u_lib.s9s_mb_2u(sch_1):page597_i117@pure_quanta.q_res(chips)';

PART_NAME
 PR249 'Q_RES_0402LF-1K,1%,1/16W,EMPTYA':;

SECTION_NUMBER 1
 '@S9S_MB_2U_LIB.S9S_MB_2U(SCH_1):PAGE597_I167@PURE_QUANTA.Q_RES(CHIPS)':
 C_PATH='@s9s_mb_2u_lib.s9s_mb_2u(sch_1):page597_i167@pure_quanta.q_res(chips)';

PART_NAME
 PR248 'Q_RES_0402LF-1,1%,1/16W,CHIP,CA':;

SECTION_NUMBER 1
 '@S9S_MB_2U_LIB.S9S_MB_2U(SCH_1):PAGE597_I184@PURE_QUANTA.Q_RES(CHIPS)':
 C_PATH='@s9s_mb_2u_lib.s9s_mb_2u(sch_1):page597_i184@pure_quanta.q_res(chips)';

PART_NAME
 PR244 'Q_RES_0402LF-1K,1%,1/16W,EMPTYA':;

SECTION_NUMBER 1
 '@S9S_MB_2U_LIB.S9S_MB_2U(SCH_1):PAGE597_I191@PURE_QUANTA.Q_RES(CHIPS)':
 C_PATH='@s9s_mb_2u_lib.s9s_mb_2u(sch_1):page597_i191@pure_quanta.q_res(chips)';

PART_NAME
 PR243 'Q_RES_0402LF-1K,1%,1/16W,CHIP,A':;

SECTION_NUMBER 1
 '@S9S_MB_2U_LIB.S9S_MB_2U(SCH_1):PAGE597_I122@PURE_QUANTA.Q_RES(CHIPS)':
 C_PATH='@s9s_mb_2u_lib.s9s_mb_2u(sch_1):page597_i122@pure_quanta.q_res(chips)';

PART_NAME
 PR242 'Q_RES_0402LF-0,5%,1/16W,CHIP,CA':;

SECTION_NUMBER 1
 '@S9S_MB_2U_LIB.S9S_MB_2U(SCH_1):PAGE597_I135@PURE_QUANTA.Q_RES(CHIPS)':
 C_PATH='@s9s_mb_2u_lib.s9s_mb_2u(sch_1):page597_i135@pure_quanta.q_res(chips)';

PART_NAME
 PR241 'Q_RES_0402LF-1K,1%,1/16W,CHIP,A':;

SECTION_NUMBER 1
 '@S9S_MB_2U_LIB.S9S_MB_2U(SCH_1):PAGE597_I120@PURE_QUANTA.Q_RES(CHIPS)':
 C_PATH='@s9s_mb_2u_lib.s9s_mb_2u(sch_1):page597_i120@pure_quanta.q_res(chips)';

PART_NAME
 PR240 'Q_RES_0402LF-1K,1%,1/16W,EMPTYA':;

SECTION_NUMBER 1
 '@S9S_MB_2U_LIB.S9S_MB_2U(SCH_1):PAGE597_I188@PURE_QUANTA.Q_RES(CHIPS)':
 C_PATH='@s9s_mb_2u_lib.s9s_mb_2u(sch_1):page597_i188@pure_quanta.q_res(chips)';

PART_NAME
 PR239 'Q_RES_0402LF-33.2,1%,1/16W,CHIA':;

SECTION_NUMBER 1
 '@S9S_MB_2U_LIB.S9S_MB_2U(SCH_1):PAGE597_I136@PURE_QUANTA.Q_RES(CHIPS)':
 C_PATH='@s9s_mb_2u_lib.s9s_mb_2u(sch_1):page597_i136@pure_quanta.q_res(chips)';

PART_NAME
 PR238 'Q_RES_0402LF-0,5%,1/16W,CHIP,CA':;

SECTION_NUMBER 1
 '@S9S_MB_2U_LIB.S9S_MB_2U(SCH_1):PAGE597_I137@PURE_QUANTA.Q_RES(CHIPS)':
 C_PATH='@s9s_mb_2u_lib.s9s_mb_2u(sch_1):page597_i137@pure_quanta.q_res(chips)';

PART_NAME
 PR237 'Q_RES_0402LF-0,5%,1/16W,CHIP,CA':;

SECTION_NUMBER 1
 '@S9S_MB_2U_LIB.S9S_MB_2U(SCH_1):PAGE597_I132@PURE_QUANTA.Q_RES(CHIPS)':
 C_PATH='@s9s_mb_2u_lib.s9s_mb_2u(sch_1):page597_i132@pure_quanta.q_res(chips)';

PART_NAME
 PR236 'Q_RES_0402LF-0,5%,1/16W,CHIP,CA':;

SECTION_NUMBER 1
 '@S9S_MB_2U_LIB.S9S_MB_2U(SCH_1):PAGE597_I131@PURE_QUANTA.Q_RES(CHIPS)':
 C_PATH='@s9s_mb_2u_lib.s9s_mb_2u(sch_1):page597_i131@pure_quanta.q_res(chips)';

PART_NAME
 PR235 'Q_RES_0402LF-150,1%,1/16W,CHIPA':;

SECTION_NUMBER 1
 '@S9S_MB_2U_LIB.S9S_MB_2U(SCH_1):PAGE597_I134@PURE_QUANTA.Q_RES(CHIPS)':
 C_PATH='@s9s_mb_2u_lib.s9s_mb_2u(sch_1):page597_i134@pure_quanta.q_res(chips)';

PART_NAME
 PR234 'Q_RES_0402LF-0,5%,1/16W,CHIP,CA':;

SECTION_NUMBER 1
 '@S9S_MB_2U_LIB.S9S_MB_2U(SCH_1):PAGE597_I133@PURE_QUANTA.Q_RES(CHIPS)':
 C_PATH='@s9s_mb_2u_lib.s9s_mb_2u(sch_1):page597_i133@pure_quanta.q_res(chips)';

PART_NAME
 PR233 'Q_RES_0402LF-0,5%,1/16W,CHIP,CA':;

SECTION_NUMBER 1
 '@S9S_MB_2U_LIB.S9S_MB_2U(SCH_1):PAGE597_I141@PURE_QUANTA.Q_RES(CHIPS)':
 C_PATH='@s9s_mb_2u_lib.s9s_mb_2u(sch_1):page597_i141@pure_quanta.q_res(chips)';

PART_NAME
 PR232 'Q_RES_0402LF-1K,1%,1/16W,CHIP,A':;

SECTION_NUMBER 1
 '@S9S_MB_2U_LIB.S9S_MB_2U(SCH_1):PAGE597_I140@PURE_QUANTA.Q_RES(CHIPS)':
 C_PATH='@s9s_mb_2u_lib.s9s_mb_2u(sch_1):page597_i140@pure_quanta.q_res(chips)';

PART_NAME
 PR231 'Q_RES_0402LF-0,5%,1/16W,CHIP,CA':;

SECTION_NUMBER 1
 '@S9S_MB_2U_LIB.S9S_MB_2U(SCH_1):PAGE597_I195@PURE_QUANTA.Q_RES(CHIPS)':
 C_PATH='@s9s_mb_2u_lib.s9s_mb_2u(sch_1):page597_i195@pure_quanta.q_res(chips)';

PART_NAME
 PR230 'Q_RES_0402LF-0,5%,1/16W,CHIP,CA':;

SECTION_NUMBER 1
 '@S9S_MB_2U_LIB.S9S_MB_2U(SCH_1):PAGE597_I194@PURE_QUANTA.Q_RES(CHIPS)':
 C_PATH='@s9s_mb_2u_lib.s9s_mb_2u(sch_1):page597_i194@pure_quanta.q_res(chips)';

PART_NAME
 PR229 'Q_RES_0402LF-17.4K,1%,1/16W,CHA':;

SECTION_NUMBER 1
 '@S9S_MB_2U_LIB.S9S_MB_2U(SCH_1):PAGE597_I197@PURE_QUANTA.Q_RES(CHIPS)':
 C_PATH='@s9s_mb_2u_lib.s9s_mb_2u(sch_1):page597_i197@pure_quanta.q_res(chips)',
 CDSVAR_REPCELL_ONSEMI='pure_quanta|Q_res',
 VAR_0_ONSEMI='VALUE|75K|TOLERANCE|1%|WATTAGE|1/16W|PACK_TYPE|0402LF|MATERIAL|CH~
IP|PART_NUMBER|CS37502FB12|STANDARD|End of Design|LIFECYCLE|Comp-Approve|PART_NU~
MBER|CS37502FB12|JEDEC_TYPE|R0402|ALT_SYMBOLS|(R0402-0201)|VALUE|75K|TOL|1%|WATT~
AGE|1/16W|CLASS|DISCRETE|DESCRIPTION|RES CHIP 75K 1/16W +-1%(0402)|COMPONENT_TYP~
E|CHIP0402|LEAD_LENGTH||DFM_EXCLUSION||DAY|20111130|VARIANT_DEVICE_TYPE|Q_RES-75~
K,1%,1/16W,0402LF,CHIP';

PART_NAME
 PR228 'Q_RES_0402LF-28K,1%,1/16W,EMPTA':;

SECTION_NUMBER 1
 '@S9S_MB_2U_LIB.S9S_MB_2U(SCH_1):PAGE597_I198@PURE_QUANTA.Q_RES(CHIPS)':
 C_PATH='@s9s_mb_2u_lib.s9s_mb_2u(sch_1):page597_i198@pure_quanta.q_res(chips)';

PART_NAME
 PJ49 'Q_SHORT_SM-EMPTY,SHORT6':;

SECTION_NUMBER 1
 '@S9S_MB_2U_LIB.S9S_MB_2U(SCH_1):PAGE597_I129@PURE_QUANTA.Q_SHORT(CHIPS)':
 C_PATH='@s9s_mb_2u_lib.s9s_mb_2u(sch_1):page597_i129@pure_quanta.q_short(chips)';

PART_NAME
 PC1190 'Q_CAP_C0402-1UF,16V,10%,X6S,CHA':;

SECTION_NUMBER 1
 '@S9S_MB_2U_LIB.S9S_MB_2U(SCH_1):PAGE597_I173@PURE_QUANTA.Q_CAP(CHIPS)':
 C_PATH='@s9s_mb_2u_lib.s9s_mb_2u(sch_1):page597_i173@pure_quanta.q_cap(chips)';

PART_NAME
 PC427 'Q_CAP_C0402-1UF,16V,10%,X6S,CHA':;

SECTION_NUMBER 1
 '@S9S_MB_2U_LIB.S9S_MB_2U(SCH_1):PAGE597_I175@PURE_QUANTA.Q_CAP(CHIPS)':
 C_PATH='@s9s_mb_2u_lib.s9s_mb_2u(sch_1):page597_i175@pure_quanta.q_cap(chips)';

PART_NAME
 PC426 'Q_CAP_0402-470PF,50V,10%,X7R,TA':;

SECTION_NUMBER 1
 '@S9S_MB_2U_LIB.S9S_MB_2U(SCH_1):PAGE597_I145@PURE_QUANTA.Q_CAP(CHIPS)':
 C_PATH='@s9s_mb_2u_lib.s9s_mb_2u(sch_1):page597_i145@pure_quanta.q_cap(chips)',
 CDSVAR_REPCELL_ONSEMI='pure_quanta|Q_cap',
 VAR_0_ONSEMI='VALUE|2200PF|VOLTAGE|50V|TOLERANCE|10%|PACK_TYPE|C0402|MATERIAL|X~
7R|PART_NUMBER|CH2226K1B06|STANDARD||LIFECYCLE||ASS_PART||PART_NUMBER|CH2226K1B0~
6|JEDEC_TYPE|C0402|ALT_SYMBOLS|(C0402-0201)|VALUE|2200PF|RATED_VOLTAGE|50V|TOL|1~
0%|CLASS|DISCRETE|DESCRIPTION|CAP CHIP 2200P 50V(+-10%,X7R,0402)MUR|COMPONENT_TY~
PE|CHIP0402|LEAD_LENGTH||LPID||DATE|20150614|VARIANT_DEVICE_TYPE|Q_CAP-2200PF,50~
V,10%,C0402,X7R';

PART_NAME
 PC425 'Q_CAP_0402-4.7UF,6.3V,20%,X6S,A':;

SECTION_NUMBER 1
 '@S9S_MB_2U_LIB.S9S_MB_2U(SCH_1):PAGE597_I172@PURE_QUANTA.Q_CAP(CHIPS)':
 C_PATH='@s9s_mb_2u_lib.s9s_mb_2u(sch_1):page597_i172@pure_quanta.q_cap(chips)',
 CDSVAR_REPCELL_ONSEMI='pure_quanta|Q_cap',
 VAR_0_ONSEMI='VALUE|4.7UF|VOLTAGE|6.3V|TOLERANCE|20%|PACK_TYPE|0402|MATERIAL|EM~
PTY|PART_NUMBER|CH5471MEB01|STANDARD||LIFECYCLE||ASS_PART||PART_NUMBER|CH5471MEB~
01|JEDEC_TYPE|C0402|ALT_SYMBOLS|(C0402_OCTAGON,C0402_OCTAGONXA,C0402-0201)|VALUE~
|NA|RATED_VOLTAGE|6.3V|TOL|20%|CLASS|IO|DESCRIPTION|CAP CHIP 4.7UF 6.3V(+-20%,X6~
S,0402)|COMPONENT_TYPE|CHIP0402|LEAD_LENGTH||LPID||DATE|20151211|VARIANT_DEVICE_~
TYPE|Q_CAP-4.7UF,6.3V,20%,0402,EMPT';

PART_NAME
 PC424 'Q_CAP_C0402-100NF,50V,10%,EMPTA':;

SECTION_NUMBER 1
 '@S9S_MB_2U_LIB.S9S_MB_2U(SCH_1):PAGE597_I174@PURE_QUANTA.Q_CAP(CHIPS)':
 C_PATH='@s9s_mb_2u_lib.s9s_mb_2u(sch_1):page597_i174@pure_quanta.q_cap(chips)';

PART_NAME
 PC423 'Q_CAP_C0402-1UF,16V,10%,X6S,CHA':;

SECTION_NUMBER 1
 '@S9S_MB_2U_LIB.S9S_MB_2U(SCH_1):PAGE597_I189@PURE_QUANTA.Q_CAP(CHIPS)':
 C_PATH='@s9s_mb_2u_lib.s9s_mb_2u(sch_1):page597_i189@pure_quanta.q_cap(chips)';

PART_NAME
 PC422 'Q_CAP_0402-3300PF,50V,10%,X7R,A':;

SECTION_NUMBER 1
 '@S9S_MB_2U_LIB.S9S_MB_2U(SCH_1):PAGE597_I123@PURE_QUANTA.Q_CAP(CHIPS)':
 C_PATH='@s9s_mb_2u_lib.s9s_mb_2u(sch_1):page597_i123@pure_quanta.q_cap(chips)',
 CDSVAR_REPCELL_ONSEMI='pure_quanta|Q_cap',
 VAR_0_ONSEMI='VALUE|1NF|VOLTAGE|50V|TOLERANCE|10%|PACK_TYPE|0402|MATERIAL|X7R|P~
ART_NUMBER|CH21006KB16|STANDARD||LIFECYCLE||ASS_PART||PART_NUMBER|CH21006KB16|JE~
DEC_TYPE|C0402|ALT_SYMBOLS|(C0402-0201)|VALUE|1NF|RATED_VOLTAGE|50V|TOL|10%|CLAS~
S|DISCRETE|DESCRIPTION|CAP CHIP 1N 50V(+-10%,X7R,0402)EP|COMPONENT_TYPE|CHIP0402~
|LEAD_LENGTH||LPID||DATE|20100811|VARIANT_DEVICE_TYPE|Q_CAP-1NF,50V,10%,0402,X7R~
,CH2';

PART_NAME
 PC421 'Q_CAP_0402-1000PF,50V,5%,EMPTYA':;

SECTION_NUMBER 1
 '@S9S_MB_2U_LIB.S9S_MB_2U(SCH_1):PAGE597_I142@PURE_QUANTA.Q_CAP(CHIPS)':
 C_PATH='@s9s_mb_2u_lib.s9s_mb_2u(sch_1):page597_i142@pure_quanta.q_cap(chips)';

PART_NAME
 PC420 'Q_CAP_0402-0.01UF,25V,10%,X7R,A':;

SECTION_NUMBER 1
 '@S9S_MB_2U_LIB.S9S_MB_2U(SCH_1):PAGE597_I138@PURE_QUANTA.Q_CAP(CHIPS)':
 C_PATH='@s9s_mb_2u_lib.s9s_mb_2u(sch_1):page597_i138@pure_quanta.q_cap(chips)';

PART_NAME
 PC419 'Q_CAP_C0402-1UF,16V,10%,X6S,CHA':;

SECTION_NUMBER 1
 '@S9S_MB_2U_LIB.S9S_MB_2U(SCH_1):PAGE597_I192@PURE_QUANTA.Q_CAP(CHIPS)':
 C_PATH='@s9s_mb_2u_lib.s9s_mb_2u(sch_1):page597_i192@pure_quanta.q_cap(chips)';

PART_NAME
 PU78_P1_4 'ISL99390FRZTR5935-ISL99390FRZ-A':;

SECTION_NUMBER 1
 '@S9S_MB_2U_LIB.S9S_MB_2U(SCH_1):PAGE599_I25@PURE_QUANTA.ISL99390FRZTR5935(CHIPS)':
 C_PATH='@s9s_mb_2u_lib.s9s_mb_2u(sch_1):page599_i25@pure_quanta.isl99390frztr5935~
(chips)',
 VAR_0_ONSEMI='VAR_REPLACED|ISL99390FRZTR5935|VAR_PARTNAME|FDMF5085|VALUE|FDMF50~
85|PART_TYPE|SMLF|MATERIAL|IC|PART_NUMBER|AL005085000|STANDARD||LIFECYCLE||PART_~
NUMBER|AL005085000|JEDEC_TYPE|PQFN21_6X5XB|DESCRIPTION|IC OTHER(39P) FDMF5085(PQ~
FN)|MANUFTR|ONS|MANUF_PN|FDMF5085|RD_CMPLS_LVL|EP(V1)|CMPLS_LVL||FROM_PJ|S9S-KIM~
I|CLASS|IC|DIP_SMD||DATA|ONS_FDMF5085.pdf|EE_CHECK_LIST||FP_ECN||PSL||CREATOR||S~
TATUS||MSD|NA|ESD_CDM|NA|ESD_HBM|NA|ESD_MM|NA|PIN_LENGTH_SHORT_PIN|0 MILS|PIN_LE~
NGTH_LONG_PIN|0 MILS|CREATEDAY|20200423|VARIANT_DEVICE_TYPE|FDMF5085-FDMF5085,SM~
LF,IC,AL00',
 CDSVAR_REPCELL_ONSEMI='pure_quanta|fdmf5085';

PART_NAME
 PU77_P1_3 'ISL99390FRZTR5935-ISL99390FRZ-A':;

SECTION_NUMBER 1
 '@S9S_MB_2U_LIB.S9S_MB_2U(SCH_1):PAGE599_I28@PURE_QUANTA.ISL99390FRZTR5935(CHIPS)':
 C_PATH='@s9s_mb_2u_lib.s9s_mb_2u(sch_1):page599_i28@pure_quanta.isl99390frztr5935~
(chips)',
 VAR_0_ONSEMI='VAR_REPLACED|ISL99390FRZTR5935|VAR_PARTNAME|FDMF5085|VALUE|FDMF50~
85|PART_TYPE|SMLF|MATERIAL|IC|PART_NUMBER|AL005085000|STANDARD||LIFECYCLE||PART_~
NUMBER|AL005085000|JEDEC_TYPE|PQFN21_6X5XB|DESCRIPTION|IC OTHER(39P) FDMF5085(PQ~
FN)|MANUFTR|ONS|MANUF_PN|FDMF5085|RD_CMPLS_LVL|EP(V1)|CMPLS_LVL||FROM_PJ|S9S-KIM~
I|CLASS|IC|DIP_SMD||DATA|ONS_FDMF5085.pdf|EE_CHECK_LIST||FP_ECN||PSL||CREATOR||S~
TATUS||MSD|NA|ESD_CDM|NA|ESD_HBM|NA|ESD_MM|NA|PIN_LENGTH_SHORT_PIN|0 MILS|PIN_LE~
NGTH_LONG_PIN|0 MILS|CREATEDAY|20200423|VARIANT_DEVICE_TYPE|FDMF5085-FDMF5085,SM~
LF,IC,AL00',
 CDSVAR_REPCELL_ONSEMI='pure_quanta|fdmf5085';

PART_NAME
 PR1803 'Q_RES_0402LF-3.3,1%,1/16W,CHIPA':;

SECTION_NUMBER 1
 '@S9S_MB_2U_LIB.S9S_MB_2U(SCH_1):PAGE599_I97@PURE_QUANTA.Q_RES(CHIPS)':
 C_PATH='@s9s_mb_2u_lib.s9s_mb_2u(sch_1):page599_i97@pure_quanta.q_res(chips)',
 CDSVAR_REPCELL_ONSEMI='pure_quanta|Q_res',
 VAR_0_ONSEMI='VALUE|5.1|TOLERANCE|5%|WATTAGE|1/16W|PACK_TYPE|0402LF|MATERIAL|CH~
IP|PART_NUMBER|CS-5102JB03|STANDARD|End of Design|LIFECYCLE|Comp-Approve|PART_NU~
MBER|CS-5102JB03|JEDEC_TYPE|R0402|ALT_SYMBOLS|(R0402-0201)|VALUE|5.1|TOL|5%|WATT~
AGE|1/16W |CLASS|DISCRETE|DESCRIPTION|RES CHIP 5.1 1/16W +-5%(0402)|COMPONENT_TY~
PE|CHIP0402|LEAD_LENGTH||DFM_EXCLUSION||DAY|20100827|VARIANT_DEVICE_TYPE|Q_RES-5~
.1,5%,1/16W,0402LF,CHIP';

PART_NAME
 PR1802 'Q_RES_0402LF-3.3,1%,1/16W,CHIPA':;

SECTION_NUMBER 1
 '@S9S_MB_2U_LIB.S9S_MB_2U(SCH_1):PAGE599_I95@PURE_QUANTA.Q_RES(CHIPS)':
 C_PATH='@s9s_mb_2u_lib.s9s_mb_2u(sch_1):page599_i95@pure_quanta.q_res(chips)',
 CDSVAR_REPCELL_ONSEMI='pure_quanta|Q_res',
 VAR_0_ONSEMI='VALUE|5.1|TOLERANCE|5%|WATTAGE|1/16W|PACK_TYPE|0402LF|MATERIAL|CH~
IP|PART_NUMBER|CS-5102JB03|STANDARD|End of Design|LIFECYCLE|Comp-Approve|PART_NU~
MBER|CS-5102JB03|JEDEC_TYPE|R0402|ALT_SYMBOLS|(R0402-0201)|VALUE|5.1|TOL|5%|WATT~
AGE|1/16W |CLASS|DISCRETE|DESCRIPTION|RES CHIP 5.1 1/16W +-5%(0402)|COMPONENT_TY~
PE|CHIP0402|LEAD_LENGTH||DFM_EXCLUSION||DAY|20100827|VARIANT_DEVICE_TYPE|Q_RES-5~
.1,5%,1/16W,0402LF,CHIP';

PART_NAME
 PR1334 'Q_RES_0402LF-0,5%,1/16W,CHIP,CA':;

SECTION_NUMBER 1
 '@S9S_MB_2U_LIB.S9S_MB_2U(SCH_1):PAGE599_I30@PURE_QUANTA.Q_RES(CHIPS)':
 C_PATH='@s9s_mb_2u_lib.s9s_mb_2u(sch_1):page599_i30@pure_quanta.q_res(chips)',
 CDSVAR_REPCELL_ONSEMI='pure_quanta|Q_res',
 VAR_0_ONSEMI='VALUE|0|TOLERANCE|5%|WATTAGE|1/16W|PACK_TYPE|0402LF|MATERIAL|EMPT~
Y|PART_NUMBER|CS00002JB38|STANDARD|End of Design|LIFECYCLE|Comp-Approve|PART_NUM~
BER|CS00002JB38|JEDEC_TYPE|R0402|ALT_SYMBOLS|(R0402-0201)|VALUE|0|TOL|5%|WATTAGE~
|1/16W|CLASS|IO|DESCRIPTION|RESISTOR CHIP 0 1/16W +-5%(0402)|COMPONENT_TYPE|CHIP~
0402|LEAD_LENGTH||DFM_EXCLUSION||DAY|20100618|VARIANT_DEVICE_TYPE|Q_RES-0,5%,1/1~
6W,0402LF,EMPTY,';

PART_NAME
 PR1333 'Q_RES_0402LF-0,5%,1/16W,CHIP,CA':;

SECTION_NUMBER 1
 '@S9S_MB_2U_LIB.S9S_MB_2U(SCH_1):PAGE599_I39@PURE_QUANTA.Q_RES(CHIPS)':
 C_PATH='@s9s_mb_2u_lib.s9s_mb_2u(sch_1):page599_i39@pure_quanta.q_res(chips)',
 CDSVAR_REPCELL_ONSEMI='pure_quanta|Q_res',
 VAR_0_ONSEMI='VALUE|0|TOLERANCE|5%|WATTAGE|1/16W|PACK_TYPE|0402LF|MATERIAL|EMPT~
Y|PART_NUMBER|CS00002JB38|STANDARD|End of Design|LIFECYCLE|Comp-Approve|PART_NUM~
BER|CS00002JB38|JEDEC_TYPE|R0402|ALT_SYMBOLS|(R0402-0201)|VALUE|0|TOL|5%|WATTAGE~
|1/16W|CLASS|IO|DESCRIPTION|RESISTOR CHIP 0 1/16W +-5%(0402)|COMPONENT_TYPE|CHIP~
0402|LEAD_LENGTH||DFM_EXCLUSION||DAY|20100618|VARIANT_DEVICE_TYPE|Q_RES-0,5%,1/1~
6W,0402LF,EMPTY,';

PART_NAME
 PR1307 'Q_RES_0402LF-2.2,1%,1/16W,CHIPA':;

SECTION_NUMBER 1
 '@S9S_MB_2U_LIB.S9S_MB_2U(SCH_1):PAGE599_I9@PURE_QUANTA.Q_RES(CHIPS)':
 C_PATH='@s9s_mb_2u_lib.s9s_mb_2u(sch_1):page599_i9@pure_quanta.q_res(chips)';

PART_NAME
 PR1306 'Q_RES_0402LF-2.2,1%,1/16W,CHIPA':;

SECTION_NUMBER 1
 '@S9S_MB_2U_LIB.S9S_MB_2U(SCH_1):PAGE599_I21@PURE_QUANTA.Q_RES(CHIPS)':
 C_PATH='@s9s_mb_2u_lib.s9s_mb_2u(sch_1):page599_i21@pure_quanta.q_res(chips)';

PART_NAME
 PR1305 'Q_RES_0402LF-8.87K,1%,1/16W,EMA':;

SECTION_NUMBER 1
 '@S9S_MB_2U_LIB.S9S_MB_2U(SCH_1):PAGE599_I14@PURE_QUANTA.Q_RES(CHIPS)':
 C_PATH='@s9s_mb_2u_lib.s9s_mb_2u(sch_1):page599_i14@pure_quanta.q_res(chips)';

PART_NAME
 PR1304 'Q_RES_0402LF-8.87K,1%,1/16W,EMA':;

SECTION_NUMBER 1
 '@S9S_MB_2U_LIB.S9S_MB_2U(SCH_1):PAGE599_I2@PURE_QUANTA.Q_RES(CHIPS)':
 C_PATH='@s9s_mb_2u_lib.s9s_mb_2u(sch_1):page599_i2@pure_quanta.q_res(chips)';

PART_NAME
 PL113 'Q_INDUCTOR_SMLF-130NH/106A,INDA':;

SECTION_NUMBER 1
 '@S9S_MB_2U_LIB.S9S_MB_2U(SCH_1):PAGE599_I91@PURE_QUANTA.Q_INDUCTOR(CHIPS)':
 C_PATH='@s9s_mb_a_lib.s9s_mb_a(sch_1):page599_i91@pure_quanta.q_inductor(chips)~
';

PART_NAME
 PL14 'Q_INDUCTOR_SMLF-100NH/16A,IND,A':;

SECTION_NUMBER 1
 '@S9S_MB_2U_LIB.S9S_MB_2U(SCH_1):PAGE599_I65@PURE_QUANTA.Q_INDUCTOR(CHIPS)':
 C_PATH='@s9s_mb_a_lib.s9s_mb_a(sch_1):page599_i65@pure_quanta.q_inductor(chips)~
';

PART_NAME
 PL12 'Q_INDUCTOR_SMLF-130NH/106A,INDA':;

SECTION_NUMBER 1
 '@S9S_MB_2U_LIB.S9S_MB_2U(SCH_1):PAGE599_I90@PURE_QUANTA.Q_INDUCTOR(CHIPS)':
 C_PATH='@s9s_mb_a_lib.s9s_mb_a(sch_1):page599_i90@pure_quanta.q_inductor(chips)~
';

PART_NAME
 PC2172 'Q_CAPP_SMLF-470UF,2.5V,20%,EMPA':;

SECTION_NUMBER 1
 '@S9S_MB_2U_LIB.S9S_MB_2U(SCH_1):PAGE599_I92@PURE_QUANTA.Q_CAPP(CHIPS)':
 C_PATH='@s9s_mb_2u_lib.s9s_mb_2u(sch_1):page599_i92@pure_quanta.q_capp(chips)';

PART_NAME
 PC1370 'Q_CAP_0402-0.1UF,25V,10%,X7R,CA':;

SECTION_NUMBER 1
 '@S9S_MB_2U_LIB.S9S_MB_2U(SCH_1):PAGE599_I102@PURE_QUANTA.Q_CAP(CHIPS)':
 C_PATH='@s9s_mb_2u_lib.s9s_mb_2u(sch_1):page599_i102@pure_quanta.q_cap(chips)',
 CDSVAR_REPCELL_ONSEMI='pure_quanta|Q_cap',
 VAR_0_ONSEMI='VALUE|0.1UF|VOLTAGE|25V|TOLERANCE|10%|PACK_TYPE|0402|MATERIAL|EMP~
TY|PART_NUMBER|CH4104K1B00|STANDARD||LIFECYCLE||ASS_PART||PART_NUMBER|CH4104K1B0~
0|JEDEC_TYPE|C0402|ALT_SYMBOLS|(C0402_OCTAGONXA,C0402-0201)|VALUE|NA|RATED_VOLTA~
GE|25V|TOL|10%|CLASS|IO|DESCRIPTION|CAP CHIP 0.1U 25V(+-10%,X7R,0402)|COMPONENT_~
TYPE|CHIP0402|LEAD_LENGTH||LPID||DATE|20160113|VARIANT_DEVICE_TYPE|Q_CAP-0.1UF,2~
5V,10%,0402,EMPTY';

PART_NAME
 PC1369 'Q_CAP_0402-0.1UF,25V,10%,X7R,CA':;

SECTION_NUMBER 1
 '@S9S_MB_2U_LIB.S9S_MB_2U(SCH_1):PAGE599_I99@PURE_QUANTA.Q_CAP(CHIPS)':
 C_PATH='@s9s_mb_2u_lib.s9s_mb_2u(sch_1):page599_i99@pure_quanta.q_cap(chips)',
 CDSVAR_REPCELL_ONSEMI='pure_quanta|Q_cap',
 VAR_0_ONSEMI='VALUE|0.1UF|VOLTAGE|25V|TOLERANCE|10%|PACK_TYPE|0402|MATERIAL|EMP~
TY|PART_NUMBER|CH4104K1B00|STANDARD||LIFECYCLE||ASS_PART||PART_NUMBER|CH4104K1B0~
0|JEDEC_TYPE|C0402|ALT_SYMBOLS|(C0402_OCTAGONXA,C0402-0201)|VALUE|NA|RATED_VOLTA~
GE|25V|TOL|10%|CLASS|IO|DESCRIPTION|CAP CHIP 0.1U 25V(+-10%,X7R,0402)|COMPONENT_~
TYPE|CHIP0402|LEAD_LENGTH||LPID||DATE|20160113|VARIANT_DEVICE_TYPE|Q_CAP-0.1UF,2~
5V,10%,0402,EMPTY';

PART_NAME
 PC1245_P1_4 'Q_CAP_C0402-2.2UF,10V,10%,X6S,A':;

SECTION_NUMBER 1
 '@S9S_MB_2U_LIB.S9S_MB_2U(SCH_1):PAGE599_I11@PURE_QUANTA.Q_CAP(CHIPS)':
 C_PATH='@s9s_mb_2u_lib.s9s_mb_2u(sch_1):page599_i11@pure_quanta.q_cap(chips)';

PART_NAME
 PC1244_P1_3 'Q_CAP_C0402-2.2UF,10V,10%,X6S,A':;

SECTION_NUMBER 1
 '@S9S_MB_2U_LIB.S9S_MB_2U(SCH_1):PAGE599_I24@PURE_QUANTA.Q_CAP(CHIPS)':
 C_PATH='@s9s_mb_2u_lib.s9s_mb_2u(sch_1):page599_i24@pure_quanta.q_cap(chips)';

PART_NAME
 PC1210 'Q_CAPP_THLF-270UF,16V,20%,OSCOA':;

SECTION_NUMBER 1
 '@S9S_MB_2U_LIB.S9S_MB_2U(SCH_1):PAGE599_I67@PURE_QUANTA.Q_CAPP(CHIPS)':
 C_PATH='@s9s_mb_2u_lib.s9s_mb_2u(sch_1):page599_i67@pure_quanta.q_capp(chips)';

PART_NAME
 PC1209_P1_4 'Q_CAP_0805-22UF,4V,20%,X6S,TMPA':;

SECTION_NUMBER 1
 '@S9S_MB_2U_LIB.S9S_MB_2U(SCH_1):PAGE599_I51@PURE_QUANTA.Q_CAP(CHIPS)':
 C_PATH='@s9s_mb_2u_lib.s9s_mb_2u(sch_1):page599_i51@pure_quanta.q_cap(chips)';

PART_NAME
 PC1208_P1_3 'Q_CAP_0805-22UF,4V,20%,X6S,TMPA':;

SECTION_NUMBER 1
 '@S9S_MB_2U_LIB.S9S_MB_2U(SCH_1):PAGE599_I59@PURE_QUANTA.Q_CAP(CHIPS)':
 C_PATH='@s9s_mb_2u_lib.s9s_mb_2u(sch_1):page599_i59@pure_quanta.q_cap(chips)';

PART_NAME
 PC1207_P1_4 'Q_CAP_0805-22UF,4V,20%,X6S,TMPA':;

SECTION_NUMBER 1
 '@S9S_MB_2U_LIB.S9S_MB_2U(SCH_1):PAGE599_I50@PURE_QUANTA.Q_CAP(CHIPS)':
 C_PATH='@s9s_mb_2u_lib.s9s_mb_2u(sch_1):page599_i50@pure_quanta.q_cap(chips)';

PART_NAME
 PC1206_P1_3 'Q_CAP_0805-22UF,4V,20%,X6S,TMPA':;

SECTION_NUMBER 1
 '@S9S_MB_2U_LIB.S9S_MB_2U(SCH_1):PAGE599_I57@PURE_QUANTA.Q_CAP(CHIPS)':
 C_PATH='@s9s_mb_2u_lib.s9s_mb_2u(sch_1):page599_i57@pure_quanta.q_cap(chips)';

PART_NAME
 PC1205 'Q_CAPP_SMLF-470UF,2.5V,20%,POSA':;

SECTION_NUMBER 1
 '@S9S_MB_2U_LIB.S9S_MB_2U(SCH_1):PAGE599_I85@PURE_QUANTA.Q_CAPP(CHIPS)':
 C_PATH='@s9s_mb_2u_lib.s9s_mb_2u(sch_1):page599_i85@pure_quanta.q_capp(chips)';

PART_NAME
 PC1204_P1_3 'Q_CAP_C0402-1UF,16V,10%,X6S,CHA':;

SECTION_NUMBER 1
 '@S9S_MB_2U_LIB.S9S_MB_2U(SCH_1):PAGE599_I43@PURE_QUANTA.Q_CAP(CHIPS)':
 C_PATH='@s9s_mb_2u_lib.s9s_mb_2u(sch_1):page599_i43@pure_quanta.q_cap(chips)';

PART_NAME
 PC1204 'Q_CAPP_RDLF-560UF,2.5V,20%,ALUA':;

SECTION_NUMBER 1
 '@S9S_MB_2U_LIB.S9S_MB_2U(SCH_1):PAGE599_I86@PURE_QUANTA.Q_CAPP(CHIPS)':
 C_PATH='@s9s_mb_2u_lib.s9s_mb_2u(sch_1):page599_i86@pure_quanta.q_capp(chips)';

PART_NAME
 PC1203_P1_3 'Q_CAP_C0402-100NF,50V,10%,X7R,A':;

SECTION_NUMBER 1
 '@S9S_MB_2U_LIB.S9S_MB_2U(SCH_1):PAGE599_I42@PURE_QUANTA.Q_CAP(CHIPS)':
 C_PATH='@s9s_mb_2u_lib.s9s_mb_2u(sch_1):page599_i42@pure_quanta.q_cap(chips)';

PART_NAME
 PC1203 'Q_CAPP_RDLF-560UF,2.5V,20%,ALUA':;

SECTION_NUMBER 1
 '@S9S_MB_2U_LIB.S9S_MB_2U(SCH_1):PAGE599_I87@PURE_QUANTA.Q_CAPP(CHIPS)':
 C_PATH='@s9s_mb_2u_lib.s9s_mb_2u(sch_1):page599_i87@pure_quanta.q_capp(chips)';

PART_NAME
 PC1202_P1_4 'Q_CAP_C0805-22UF,16V,20%,X6S,CA':;

SECTION_NUMBER 1
 '@S9S_MB_2U_LIB.S9S_MB_2U(SCH_1):PAGE599_I35@PURE_QUANTA.Q_CAP(CHIPS)':
 C_PATH='@s9s_mb_2u_lib.s9s_mb_2u(sch_1):page599_i35@pure_quanta.q_cap(chips)';

PART_NAME
 PC1201_P1_3 'Q_CAP_C0805-22UF,16V,20%,X6S,CA':;

SECTION_NUMBER 1
 '@S9S_MB_2U_LIB.S9S_MB_2U(SCH_1):PAGE599_I47@PURE_QUANTA.Q_CAP(CHIPS)':
 C_PATH='@s9s_mb_2u_lib.s9s_mb_2u(sch_1):page599_i47@pure_quanta.q_cap(chips)';

PART_NAME
 PC1201 'Q_CAPP_RDLF-560UF,2.5V,20%,ALUA':;

SECTION_NUMBER 1
 '@S9S_MB_2U_LIB.S9S_MB_2U(SCH_1):PAGE599_I89@PURE_QUANTA.Q_CAPP(CHIPS)':
 C_PATH='@s9s_mb_2u_lib.s9s_mb_2u(sch_1):page599_i89@pure_quanta.q_capp(chips)';

PART_NAME
 PC1200_P1_4 'Q_CAP_C0805-22UF,16V,20%,X6S,CA':;

SECTION_NUMBER 1
 '@S9S_MB_2U_LIB.S9S_MB_2U(SCH_1):PAGE599_I33@PURE_QUANTA.Q_CAP(CHIPS)':
 C_PATH='@s9s_mb_2u_lib.s9s_mb_2u(sch_1):page599_i33@pure_quanta.q_cap(chips)';

PART_NAME
 PC1199_P1_3 'Q_CAP_C0805-22UF,16V,20%,X6S,CA':;

SECTION_NUMBER 1
 '@S9S_MB_2U_LIB.S9S_MB_2U(SCH_1):PAGE599_I46@PURE_QUANTA.Q_CAP(CHIPS)':
 C_PATH='@s9s_mb_2u_lib.s9s_mb_2u(sch_1):page599_i46@pure_quanta.q_cap(chips)';

PART_NAME
 PC1198 'Q_CAP_C0402-100NF,50V,10%,X7R,A':;

SECTION_NUMBER 1
 '@S9S_MB_2U_LIB.S9S_MB_2U(SCH_1):PAGE599_I104@PURE_QUANTA.Q_CAP(CHIPS)':
 C_PATH='@s9s_mb_2u_lib.s9s_mb_2u(sch_1):page599_i104@pure_quanta.q_cap(chips)';

PART_NAME
 PC1197 'Q_CAP_C0402-100NF,50V,10%,X7R,A':;

SECTION_NUMBER 1
 '@S9S_MB_2U_LIB.S9S_MB_2U(SCH_1):PAGE599_I103@PURE_QUANTA.Q_CAP(CHIPS)':
 C_PATH='@s9s_mb_2u_lib.s9s_mb_2u(sch_1):page599_i103@pure_quanta.q_cap(chips)';

PART_NAME
 PC1196_P1_4 'Q_CAP_C0402-1UF,16V,10%,X6S,CHA':;

SECTION_NUMBER 1
 '@S9S_MB_2U_LIB.S9S_MB_2U(SCH_1):PAGE599_I32@PURE_QUANTA.Q_CAP(CHIPS)':
 C_PATH='@s9s_mb_2u_lib.s9s_mb_2u(sch_1):page599_i32@pure_quanta.q_cap(chips)';

PART_NAME
 PC1195_P1_3 'Q_CAP_C0402-1UF,16V,10%,X6S,CHA':;

SECTION_NUMBER 1
 '@S9S_MB_2U_LIB.S9S_MB_2U(SCH_1):PAGE599_I45@PURE_QUANTA.Q_CAP(CHIPS)':
 C_PATH='@s9s_mb_2u_lib.s9s_mb_2u(sch_1):page599_i45@pure_quanta.q_cap(chips)';

PART_NAME
 PC1194_P1_4 'Q_CAP_0402-3300PF,50V,10%,X7R,A':;

SECTION_NUMBER 1
 '@S9S_MB_2U_LIB.S9S_MB_2U(SCH_1):PAGE599_I27@PURE_QUANTA.Q_CAP(CHIPS)':
 C_PATH='@s9s_mb_2u_lib.s9s_mb_2u(sch_1):page599_i27@pure_quanta.q_cap(chips)';

PART_NAME
 PC1193_P1_3 'Q_CAP_0402-3300PF,50V,10%,X7R,A':;

SECTION_NUMBER 1
 '@S9S_MB_2U_LIB.S9S_MB_2U(SCH_1):PAGE599_I44@PURE_QUANTA.Q_CAP(CHIPS)':
 C_PATH='@s9s_mb_2u_lib.s9s_mb_2u(sch_1):page599_i44@pure_quanta.q_cap(chips)';

PART_NAME
 PC1192 'Q_CAP_C0402-2.2UF,10V,10%,X6S,A':;

SECTION_NUMBER 1
 '@S9S_MB_2U_LIB.S9S_MB_2U(SCH_1):PAGE599_I7@PURE_QUANTA.Q_CAP(CHIPS)':
 C_PATH='@s9s_mb_2u_lib.s9s_mb_2u(sch_1):page599_i7@pure_quanta.q_cap(chips)';

PART_NAME
 PC1191 'Q_CAP_C0402-2.2UF,10V,10%,X6S,A':;

SECTION_NUMBER 1
 '@S9S_MB_2U_LIB.S9S_MB_2U(SCH_1):PAGE599_I19@PURE_QUANTA.Q_CAP(CHIPS)':
 C_PATH='@s9s_mb_2u_lib.s9s_mb_2u(sch_1):page599_i19@pure_quanta.q_cap(chips)';

PART_NAME
 PC408_P1_4 'Q_CAP_C0402-1UF,16V,10%,X6S,CHA':;

SECTION_NUMBER 1
 '@S9S_MB_2U_LIB.S9S_MB_2U(SCH_1):PAGE599_I105@PURE_QUANTA.Q_CAP(CHIPS)':
 C_PATH='@s9s_mb_2u_lib.s9s_mb_2u(sch_1):page599_i105@pure_quanta.q_cap(chips)';

PART_NAME
 PU109_P1_5 'ISL99390FRZTR5935-ISL99390FRZ-B':;

SECTION_NUMBER 1
 '@S9S_MB_2U_LIB.S9S_MB_2U(SCH_1):PAGE663_I1@PURE_QUANTA.ISL99390FRZTR5935(CHIPS)':
 C_PATH='@s9s_mb_2u_lib.s9s_mb_2u(sch_1):page663_i1@pure_quanta.isl99390frztr5935(~
chips)',
 VAR_0_ONSEMI='VAR_REPLACED|ISL99390FRZTR5935|VAR_PARTNAME|FDMF5085|VALUE|FDMF50~
85|PART_TYPE|SMLF|MATERIAL|EMPTY|PART_NUMBER|AL005085000|STANDARD||LIFECYCLE||PA~
RT_NUMBER|AL005085000|JEDEC_TYPE|PQFN21_6X5XB|DESCRIPTION|IC OTHER(39P) FDMF5085~
(PQFN)|MANUFTR|ONS|MANUF_PN|FDMF5085|RD_CMPLS_LVL|EP(V1)|CMPLS_LVL||FROM_PJ|S9S-~
KIMI|CLASS|IC|DIP_SMD||DATA|ONS_FDMF5085.pdf|EE_CHECK_LIST||FP_ECN||PSL||CREATOR~
||STATUS||MSD|NA|ESD_CDM|NA|ESD_HBM|NA|ESD_MM|NA|PIN_LENGTH_SHORT_PIN|0 MILS|PIN~
_LENGTH_LONG_PIN|0 MILS|CREATEDAY|20200423|VARIANT_DEVICE_TYPE|FDMF5085-FDMF5085~
,SMLF,EMPTY,A',
 CDSVAR_REPCELL_ONSEMI='pure_quanta|fdmf5085';

PART_NAME
 PR1894 'Q_RES_0402LF-0,5%,1/16W,EMPTY,A':;

SECTION_NUMBER 1
 '@S9S_MB_2U_LIB.S9S_MB_2U(SCH_1):PAGE663_I12@PURE_QUANTA.Q_RES(CHIPS)':
 C_PATH='@s9s_mb_2u_lib.s9s_mb_2u(sch_1):page663_i12@pure_quanta.q_res(chips)',
 VAR_0_ONSEMI='';

PART_NAME
 PR1893 'Q_RES_0402LF-3.3,1%,1/16W,EMPTA':;

SECTION_NUMBER 1
 '@S9S_MB_2U_LIB.S9S_MB_2U(SCH_1):PAGE663_I21@PURE_QUANTA.Q_RES(CHIPS)':
 C_PATH='@s9s_mb_2u_lib.s9s_mb_2u(sch_1):page663_i21@pure_quanta.q_res(chips)',
 CDSVAR_REPCELL_ONSEMI='pure_quanta|Q_res',
 VAR_0_ONSEMI='VALUE|5.1|TOLERANCE|5%|WATTAGE|1/16W|PACK_TYPE|0402LF|MATERIAL|EM~
PTY|PART_NUMBER|CS-5102JB03|STANDARD|End of Design|LIFECYCLE|Comp-Approve|PART_N~
UMBER|CS-5102JB03|JEDEC_TYPE|R0402|ALT_SYMBOLS|(R0402-0201)|VALUE|5.1|TOL|5%|WAT~
TAGE|1/16W |CLASS|IO|DESCRIPTION|RES CHIP 5.1 1/16W +-5%(0402)|COMPONENT_TYPE|CH~
IP0402|LEAD_LENGTH||DFM_EXCLUSION||DAY|20100827|VARIANT_DEVICE_TYPE|Q_RES-5.1,5%~
,1/16W,0402LF,EMPT';

PART_NAME
 PR1892 'Q_RES_0402LF-2.2,1%,1/16W,EMPTA':;

SECTION_NUMBER 1
 '@S9S_MB_2U_LIB.S9S_MB_2U(SCH_1):PAGE663_I25@PURE_QUANTA.Q_RES(CHIPS)':
 C_PATH='@s9s_mb_2u_lib.s9s_mb_2u(sch_1):page663_i25@pure_quanta.q_res(chips)';

PART_NAME
 PR1891 'Q_RES_0402LF-8.87K,1%,1/16W,EMA':;

SECTION_NUMBER 1
 '@S9S_MB_2U_LIB.S9S_MB_2U(SCH_1):PAGE663_I33@PURE_QUANTA.Q_RES(CHIPS)':
 C_PATH='@s9s_mb_2u_lib.s9s_mb_2u(sch_1):page663_i33@pure_quanta.q_res(chips)';

PART_NAME
 PL58 'Q_INDUCTOR_SMLF-130NH/106A,EMPA':;

SECTION_NUMBER 1
 '@S9S_MB_2U_LIB.S9S_MB_2U(SCH_1):PAGE663_I11@PURE_QUANTA.Q_INDUCTOR(CHIPS)':
 C_PATH='@s9s_mb_a_lib.s9s_mb_a(sch_1):page663_i11@pure_quanta.q_inductor(chips)~
';

PART_NAME
 PC2402 'Q_CAPP_SMLF-470UF,2.5V,20%,EMPA':;

SECTION_NUMBER 1
 '@S9S_MB_2U_LIB.S9S_MB_2U(SCH_1):PAGE663_I3@PURE_QUANTA.Q_CAPP(CHIPS)':
 C_PATH='@s9s_mb_2u_lib.s9s_mb_2u(sch_1):page663_i3@pure_quanta.q_capp(chips)';

PART_NAME
 PC2401 'Q_CAPP_RDLF-560UF,2.5V,20%,EMPA':;

SECTION_NUMBER 1
 '@S9S_MB_2U_LIB.S9S_MB_2U(SCH_1):PAGE663_I5@PURE_QUANTA.Q_CAPP(CHIPS)':
 C_PATH='@s9s_mb_2u_lib.s9s_mb_2u(sch_1):page663_i5@pure_quanta.q_capp(chips)';

PART_NAME
 PC2395_P1_5 'Q_CAP_0805-22UF,4V,20%,EMPTY,TA':;

SECTION_NUMBER 1
 '@S9S_MB_2U_LIB.S9S_MB_2U(SCH_1):PAGE663_I9@PURE_QUANTA.Q_CAP(CHIPS)':
 C_PATH='@s9s_mb_2u_lib.s9s_mb_2u(sch_1):page663_i9@pure_quanta.q_cap(chips)';

PART_NAME
 PC2394_P1_5 'Q_CAP_0805-22UF,4V,20%,EMPTY,TA':;

SECTION_NUMBER 1
 '@S9S_MB_2U_LIB.S9S_MB_2U(SCH_1):PAGE663_I10@PURE_QUANTA.Q_CAP(CHIPS)':
 C_PATH='@s9s_mb_2u_lib.s9s_mb_2u(sch_1):page663_i10@pure_quanta.q_cap(chips)';

PART_NAME
 PC2386 'Q_CAP_C0402-100NF,50V,10%,EMPTA':;

SECTION_NUMBER 1
 '@S9S_MB_2U_LIB.S9S_MB_2U(SCH_1):PAGE663_I20@PURE_QUANTA.Q_CAP(CHIPS)':
 C_PATH='@s9s_mb_2u_lib.s9s_mb_2u(sch_1):page663_i20@pure_quanta.q_cap(chips)';

PART_NAME
 PC2385_P1_5 'Q_CAP_C0805-22UF,16V,20%,EMPTYA':;

SECTION_NUMBER 1
 '@S9S_MB_2U_LIB.S9S_MB_2U(SCH_1):PAGE663_I14@PURE_QUANTA.Q_CAP(CHIPS)':
 C_PATH='@s9s_mb_2u_lib.s9s_mb_2u(sch_1):page663_i14@pure_quanta.q_cap(chips)';

PART_NAME
 PC2384_P1_5 'Q_CAP_C0805-22UF,16V,20%,EMPTYA':;

SECTION_NUMBER 1
 '@S9S_MB_2U_LIB.S9S_MB_2U(SCH_1):PAGE663_I15@PURE_QUANTA.Q_CAP(CHIPS)':
 C_PATH='@s9s_mb_2u_lib.s9s_mb_2u(sch_1):page663_i15@pure_quanta.q_cap(chips)';

PART_NAME
 PC2383_P1_5 'Q_CAP_C0402-1UF,16V,10%,EMPTY,A':;

SECTION_NUMBER 1
 '@S9S_MB_2U_LIB.S9S_MB_2U(SCH_1):PAGE663_I16@PURE_QUANTA.Q_CAP(CHIPS)':
 C_PATH='@s9s_mb_2u_lib.s9s_mb_2u(sch_1):page663_i16@pure_quanta.q_cap(chips)';

PART_NAME
 PC2382_P1_5 'Q_CAP_0402-3300PF,50V,10%,EMPTA':;

SECTION_NUMBER 1
 '@S9S_MB_2U_LIB.S9S_MB_2U(SCH_1):PAGE663_I17@PURE_QUANTA.Q_CAP(CHIPS)':
 C_PATH='@s9s_mb_2u_lib.s9s_mb_2u(sch_1):page663_i17@pure_quanta.q_cap(chips)';

PART_NAME
 PC2381_P1_5 'Q_CAP_C0402-2.2UF,10V,10%,EMPTA':;

SECTION_NUMBER 1
 '@S9S_MB_2U_LIB.S9S_MB_2U(SCH_1):PAGE663_I18@PURE_QUANTA.Q_CAP(CHIPS)':
 C_PATH='@s9s_mb_2u_lib.s9s_mb_2u(sch_1):page663_i18@pure_quanta.q_cap(chips)';

PART_NAME
 PC2380 'Q_CAP_0402-0.1UF,25V,10%,EMPTYA':;

SECTION_NUMBER 1
 '@S9S_MB_2U_LIB.S9S_MB_2U(SCH_1):PAGE663_I23@PURE_QUANTA.Q_CAP(CHIPS)':
 C_PATH='@s9s_mb_2u_lib.s9s_mb_2u(sch_1):page663_i23@pure_quanta.q_cap(chips)',
 VAR_0_ONSEMI='';

PART_NAME
 PC2379 'Q_CAP_C0402-2.2UF,10V,10%,EMPTA':;

SECTION_NUMBER 1
 '@S9S_MB_2U_LIB.S9S_MB_2U(SCH_1):PAGE663_I26@PURE_QUANTA.Q_CAP(CHIPS)':
 C_PATH='@s9s_mb_2u_lib.s9s_mb_2u(sch_1):page663_i26@pure_quanta.q_cap(chips)';

PART_NAME
 PC407_P1_5 'Q_CAP_C0402-100NF,50V,10%,EMPTA':;

SECTION_NUMBER 1
 '@S9S_MB_2U_LIB.S9S_MB_2U(SCH_1):PAGE663_I35@PURE_QUANTA.Q_CAP(CHIPS)':
 C_PATH='@s9s_mb_2u_lib.s9s_mb_2u(sch_1):page663_i35@pure_quanta.q_cap(chips)';

PART_NAME
 PU76_P1_2 'ISL99390FRZTR5935-ISL99390FRZ-A':;

SECTION_NUMBER 1
 '@S9S_MB_2U_LIB.S9S_MB_2U(SCH_1):PAGE598_I48@PURE_QUANTA.ISL99390FRZTR5935(CHIPS)':
 C_PATH='@s9s_mb_2u_lib.s9s_mb_2u(sch_1):page598_i48@pure_quanta.isl99390frztr5935~
(chips)',
 VAR_0_ONSEMI='VAR_REPLACED|ISL99390FRZTR5935|VAR_PARTNAME|FDMF5085|VALUE|FDMF50~
85|PART_TYPE|SMLF|MATERIAL|IC|PART_NUMBER|AL005085000|STANDARD||LIFECYCLE||PART_~
NUMBER|AL005085000|JEDEC_TYPE|PQFN21_6X5XB|DESCRIPTION|IC OTHER(39P) FDMF5085(PQ~
FN)|MANUFTR|ONS|MANUF_PN|FDMF5085|RD_CMPLS_LVL|EP(V1)|CMPLS_LVL||FROM_PJ|S9S-KIM~
I|CLASS|IC|DIP_SMD||DATA|ONS_FDMF5085.pdf|EE_CHECK_LIST||FP_ECN||PSL||CREATOR||S~
TATUS||MSD|NA|ESD_CDM|NA|ESD_HBM|NA|ESD_MM|NA|PIN_LENGTH_SHORT_PIN|0 MILS|PIN_LE~
NGTH_LONG_PIN|0 MILS|CREATEDAY|20200423|VARIANT_DEVICE_TYPE|FDMF5085-FDMF5085,SM~
LF,IC,AL00',
 CDSVAR_REPCELL_ONSEMI='pure_quanta|fdmf5085';

PART_NAME
 PU75_P1_1 'ISL99390FRZTR5935-ISL99390FRZ-A':;

SECTION_NUMBER 1
 '@S9S_MB_2U_LIB.S9S_MB_2U(SCH_1):PAGE598_I44@PURE_QUANTA.ISL99390FRZTR5935(CHIPS)':
 C_PATH='@s9s_mb_2u_lib.s9s_mb_2u(sch_1):page598_i44@pure_quanta.isl99390frztr5935~
(chips)',
 VAR_0_ONSEMI='VAR_REPLACED|ISL99390FRZTR5935|VAR_PARTNAME|FDMF5085|VALUE|FDMF50~
85|PART_TYPE|SMLF|MATERIAL|IC|PART_NUMBER|AL005085000|STANDARD||LIFECYCLE||PART_~
NUMBER|AL005085000|JEDEC_TYPE|PQFN21_6X5XB|DESCRIPTION|IC OTHER(39P) FDMF5085(PQ~
FN)|MANUFTR|ONS|MANUF_PN|FDMF5085|RD_CMPLS_LVL|EP(V1)|CMPLS_LVL||FROM_PJ|S9S-KIM~
I|CLASS|IC|DIP_SMD||DATA|ONS_FDMF5085.pdf|EE_CHECK_LIST||FP_ECN||PSL||CREATOR||S~
TATUS||MSD|NA|ESD_CDM|NA|ESD_HBM|NA|ESD_MM|NA|PIN_LENGTH_SHORT_PIN|0 MILS|PIN_LE~
NGTH_LONG_PIN|0 MILS|CREATEDAY|20200423|VARIANT_DEVICE_TYPE|FDMF5085-FDMF5085,SM~
LF,IC,AL00',
 CDSVAR_REPCELL_ONSEMI='pure_quanta|fdmf5085';

PART_NAME
 PR1801 'Q_RES_0402LF-3.3,1%,1/16W,CHIPA':;

SECTION_NUMBER 1
 '@S9S_MB_2U_LIB.S9S_MB_2U(SCH_1):PAGE598_I91@PURE_QUANTA.Q_RES(CHIPS)':
 C_PATH='@s9s_mb_2u_lib.s9s_mb_2u(sch_1):page598_i91@pure_quanta.q_res(chips)',
 CDSVAR_REPCELL_ONSEMI='pure_quanta|Q_res',
 VAR_0_ONSEMI='VALUE|5.1|TOLERANCE|5%|WATTAGE|1/16W|PACK_TYPE|0402LF|MATERIAL|CH~
IP|PART_NUMBER|CS-5102JB03|STANDARD|End of Design|LIFECYCLE|Comp-Approve|PART_NU~
MBER|CS-5102JB03|JEDEC_TYPE|R0402|ALT_SYMBOLS|(R0402-0201)|VALUE|5.1|TOL|5%|WATT~
AGE|1/16W |CLASS|DISCRETE|DESCRIPTION|RES CHIP 5.1 1/16W +-5%(0402)|COMPONENT_TY~
PE|CHIP0402|LEAD_LENGTH||DFM_EXCLUSION||DAY|20100827|VARIANT_DEVICE_TYPE|Q_RES-5~
.1,5%,1/16W,0402LF,CHIP';

PART_NAME
 PR1800 'Q_RES_0402LF-3.3,1%,1/16W,CHIPA':;

SECTION_NUMBER 1
 '@S9S_MB_2U_LIB.S9S_MB_2U(SCH_1):PAGE598_I89@PURE_QUANTA.Q_RES(CHIPS)':
 C_PATH='@s9s_mb_2u_lib.s9s_mb_2u(sch_1):page598_i89@pure_quanta.q_res(chips)',
 CDSVAR_REPCELL_ONSEMI='pure_quanta|Q_res',
 VAR_0_ONSEMI='VALUE|5.1|TOLERANCE|5%|WATTAGE|1/16W|PACK_TYPE|0402LF|MATERIAL|CH~
IP|PART_NUMBER|CS-5102JB03|STANDARD|End of Design|LIFECYCLE|Comp-Approve|PART_NU~
MBER|CS-5102JB03|JEDEC_TYPE|R0402|ALT_SYMBOLS|(R0402-0201)|VALUE|5.1|TOL|5%|WATT~
AGE|1/16W |CLASS|DISCRETE|DESCRIPTION|RES CHIP 5.1 1/16W +-5%(0402)|COMPONENT_TY~
PE|CHIP0402|LEAD_LENGTH||DFM_EXCLUSION||DAY|20100827|VARIANT_DEVICE_TYPE|Q_RES-5~
.1,5%,1/16W,0402LF,CHIP';

PART_NAME
 PR1332 'Q_RES_0402LF-0,5%,1/16W,CHIP,CA':;

SECTION_NUMBER 1
 '@S9S_MB_2U_LIB.S9S_MB_2U(SCH_1):PAGE598_I42@PURE_QUANTA.Q_RES(CHIPS)':
 C_PATH='@s9s_mb_2u_lib.s9s_mb_2u(sch_1):page598_i42@pure_quanta.q_res(chips)',
 CDSVAR_REPCELL_ONSEMI='pure_quanta|Q_res',
 VAR_0_ONSEMI='VALUE|0|TOLERANCE|5%|WATTAGE|1/16W|PACK_TYPE|0402LF|MATERIAL|EMPT~
Y|PART_NUMBER|CS00002JB38|STANDARD|End of Design|LIFECYCLE|Comp-Approve|PART_NUM~
BER|CS00002JB38|JEDEC_TYPE|R0402|ALT_SYMBOLS|(R0402-0201)|VALUE|0|TOL|5%|WATTAGE~
|1/16W|CLASS|IO|DESCRIPTION|RESISTOR CHIP 0 1/16W +-5%(0402)|COMPONENT_TYPE|CHIP~
0402|LEAD_LENGTH||DFM_EXCLUSION||DAY|20100618|VARIANT_DEVICE_TYPE|Q_RES-0,5%,1/1~
6W,0402LF,EMPTY,';

PART_NAME
 PR1331 'Q_RES_0402LF-0,5%,1/16W,CHIP,CA':;

SECTION_NUMBER 1
 '@S9S_MB_2U_LIB.S9S_MB_2U(SCH_1):PAGE598_I34@PURE_QUANTA.Q_RES(CHIPS)':
 C_PATH='@s9s_mb_2u_lib.s9s_mb_2u(sch_1):page598_i34@pure_quanta.q_res(chips)',
 CDSVAR_REPCELL_ONSEMI='pure_quanta|Q_res',
 VAR_0_ONSEMI='VALUE|0|TOLERANCE|5%|WATTAGE|1/16W|PACK_TYPE|0402LF|MATERIAL|EMPT~
Y|PART_NUMBER|CS00002JB38|STANDARD|End of Design|LIFECYCLE|Comp-Approve|PART_NUM~
BER|CS00002JB38|JEDEC_TYPE|R0402|ALT_SYMBOLS|(R0402-0201)|VALUE|0|TOL|5%|WATTAGE~
|1/16W|CLASS|IO|DESCRIPTION|RESISTOR CHIP 0 1/16W +-5%(0402)|COMPONENT_TYPE|CHIP~
0402|LEAD_LENGTH||DFM_EXCLUSION||DAY|20100618|VARIANT_DEVICE_TYPE|Q_RES-0,5%,1/1~
6W,0402LF,EMPTY,';

PART_NAME
 PR227 'Q_RES_0402LF-2.2,1%,1/16W,CHIPA':;

SECTION_NUMBER 1
 '@S9S_MB_2U_LIB.S9S_MB_2U(SCH_1):PAGE598_I60@PURE_QUANTA.Q_RES(CHIPS)':
 C_PATH='@s9s_mb_2u_lib.s9s_mb_2u(sch_1):page598_i60@pure_quanta.q_res(chips)';

PART_NAME
 PR226 'Q_RES_0402LF-2.2,1%,1/16W,CHIPA':;

SECTION_NUMBER 1
 '@S9S_MB_2U_LIB.S9S_MB_2U(SCH_1):PAGE598_I50@PURE_QUANTA.Q_RES(CHIPS)':
 C_PATH='@s9s_mb_2u_lib.s9s_mb_2u(sch_1):page598_i50@pure_quanta.q_res(chips)';

PART_NAME
 PR225 'Q_RES_0402LF-8.87K,1%,1/16W,EMA':;

SECTION_NUMBER 1
 '@S9S_MB_2U_LIB.S9S_MB_2U(SCH_1):PAGE598_I57@PURE_QUANTA.Q_RES(CHIPS)':
 C_PATH='@s9s_mb_2u_lib.s9s_mb_2u(sch_1):page598_i57@pure_quanta.q_res(chips)';

PART_NAME
 PR224 'Q_RES_0402LF-8.87K,1%,1/16W,EMA':;

SECTION_NUMBER 1
 '@S9S_MB_2U_LIB.S9S_MB_2U(SCH_1):PAGE598_I67@PURE_QUANTA.Q_RES(CHIPS)':
 C_PATH='@s9s_mb_2u_lib.s9s_mb_2u(sch_1):page598_i67@pure_quanta.q_res(chips)';

PART_NAME
 PL43 'Q_INDUCTOR_SMLF-100NH/16A,IND,A':;

SECTION_NUMBER 1
 '@S9S_MB_2U_LIB.S9S_MB_2U(SCH_1):PAGE598_I4@PURE_QUANTA.Q_INDUCTOR(CHIPS)':
 C_PATH='@s9s_mb_2u_lib.s9s_mb_2u(sch_1):page598_i4@pure_quanta.q_inductor(chips)';

PART_NAME
 PL19 'Q_INDUCTOR_SMLF-130NH/106A,INDA':;

SECTION_NUMBER 1
 '@S9S_MB_2U_LIB.S9S_MB_2U(SCH_1):PAGE598_I85@PURE_QUANTA.Q_INDUCTOR(CHIPS)':
 C_PATH='@s9s_mb_a_lib.s9s_mb_a(sch_1):page598_i85@pure_quanta.q_inductor(chips)~
';

PART_NAME
 PL18 'Q_INDUCTOR_SMLF-130NH/106A,INDA':;

SECTION_NUMBER 1
 '@S9S_MB_2U_LIB.S9S_MB_2U(SCH_1):PAGE598_I84@PURE_QUANTA.Q_INDUCTOR(CHIPS)':
 C_PATH='@s9s_mb_a_lib.s9s_mb_a(sch_1):page598_i84@pure_quanta.q_inductor(chips)~
';

PART_NAME
 PC2171 'Q_CAPP_SMLF-470UF,2.5V,20%,EMPA':;

SECTION_NUMBER 1
 '@S9S_MB_2U_LIB.S9S_MB_2U(SCH_1):PAGE598_I86@PURE_QUANTA.Q_CAPP(CHIPS)':
 C_PATH='@s9s_mb_2u_lib.s9s_mb_2u(sch_1):page598_i86@pure_quanta.q_capp(chips)';

PART_NAME
 PC1368 'Q_CAP_0402-0.1UF,25V,10%,X7R,CA':;

SECTION_NUMBER 1
 '@S9S_MB_2U_LIB.S9S_MB_2U(SCH_1):PAGE598_I96@PURE_QUANTA.Q_CAP(CHIPS)':
 C_PATH='@s9s_mb_2u_lib.s9s_mb_2u(sch_1):page598_i96@pure_quanta.q_cap(chips)',
 CDSVAR_REPCELL_ONSEMI='pure_quanta|Q_cap',
 VAR_0_ONSEMI='VALUE|0.1UF|VOLTAGE|25V|TOLERANCE|10%|PACK_TYPE|0402|MATERIAL|EMP~
TY|PART_NUMBER|CH4104K1B00|STANDARD||LIFECYCLE||ASS_PART||PART_NUMBER|CH4104K1B0~
0|JEDEC_TYPE|C0402|ALT_SYMBOLS|(C0402_OCTAGONXA,C0402-0201)|VALUE|NA|RATED_VOLTA~
GE|25V|TOL|10%|CLASS|IO|DESCRIPTION|CAP CHIP 0.1U 25V(+-10%,X7R,0402)|COMPONENT_~
TYPE|CHIP0402|LEAD_LENGTH||LPID||DATE|20160113|VARIANT_DEVICE_TYPE|Q_CAP-0.1UF,2~
5V,10%,0402,EMPTY';

PART_NAME
 PC1367 'Q_CAP_0402-0.1UF,25V,10%,X7R,CA':;

SECTION_NUMBER 1
 '@S9S_MB_2U_LIB.S9S_MB_2U(SCH_1):PAGE598_I94@PURE_QUANTA.Q_CAP(CHIPS)':
 C_PATH='@s9s_mb_2u_lib.s9s_mb_2u(sch_1):page598_i94@pure_quanta.q_cap(chips)',
 CDSVAR_REPCELL_ONSEMI='pure_quanta|Q_cap',
 VAR_0_ONSEMI='VALUE|0.1UF|VOLTAGE|25V|TOLERANCE|10%|PACK_TYPE|0402|MATERIAL|EMP~
TY|PART_NUMBER|CH4104K1B00|STANDARD||LIFECYCLE||ASS_PART||PART_NUMBER|CH4104K1B0~
0|JEDEC_TYPE|C0402|ALT_SYMBOLS|(C0402_OCTAGONXA,C0402-0201)|VALUE|NA|RATED_VOLTA~
GE|25V|TOL|10%|CLASS|IO|DESCRIPTION|CAP CHIP 0.1U 25V(+-10%,X7R,0402)|COMPONENT_~
TYPE|CHIP0402|LEAD_LENGTH||LPID||DATE|20160113|VARIANT_DEVICE_TYPE|Q_CAP-0.1UF,2~
5V,10%,0402,EMPTY';

PART_NAME
 PC1243_P1_2 'Q_CAP_C0402-2.2UF,10V,10%,X6S,A':;

SECTION_NUMBER 1
 '@S9S_MB_2U_LIB.S9S_MB_2U(SCH_1):PAGE598_I46@PURE_QUANTA.Q_CAP(CHIPS)':
 C_PATH='@s9s_mb_2u_lib.s9s_mb_2u(sch_1):page598_i46@pure_quanta.q_cap(chips)';

PART_NAME
 PC1242_P1_1 'Q_CAP_C0402-2.2UF,10V,10%,X6S,A':;

SECTION_NUMBER 1
 '@S9S_MB_2U_LIB.S9S_MB_2U(SCH_1):PAGE598_I28@PURE_QUANTA.Q_CAP(CHIPS)':
 C_PATH='@s9s_mb_2u_lib.s9s_mb_2u(sch_1):page598_i28@pure_quanta.q_cap(chips)';

PART_NAME
 PC418 'Q_CAPP_SMLF-470UF,2.5V,20%,POSA':;

SECTION_NUMBER 1
 '@S9S_MB_2U_LIB.S9S_MB_2U(SCH_1):PAGE598_I7@PURE_QUANTA.Q_CAPP(CHIPS)':
 C_PATH='@s9s_mb_2u_lib.s9s_mb_2u(sch_1):page598_i7@pure_quanta.q_capp(chips)';

PART_NAME
 PC417 'Q_CAPP_THLF-270UF,16V,20%,OSCOA':;

SECTION_NUMBER 1
 '@S9S_MB_2U_LIB.S9S_MB_2U(SCH_1):PAGE598_I2@PURE_QUANTA.Q_CAPP(CHIPS)':
 C_PATH='@s9s_mb_2u_lib.s9s_mb_2u(sch_1):page598_i2@pure_quanta.q_capp(chips)';

PART_NAME
 PC416 'Q_CAPP_RDLF-560UF,2.5V,20%,ALUA':;

SECTION_NUMBER 1
 '@S9S_MB_2U_LIB.S9S_MB_2U(SCH_1):PAGE598_I9@PURE_QUANTA.Q_CAPP(CHIPS)':
 C_PATH='@s9s_mb_2u_lib.s9s_mb_2u(sch_1):page598_i9@pure_quanta.q_capp(chips)';

PART_NAME
 PC415 'Q_CAPP_RDLF-560UF,2.5V,20%,ALUA':;

SECTION_NUMBER 1
 '@S9S_MB_2U_LIB.S9S_MB_2U(SCH_1):PAGE598_I15@PURE_QUANTA.Q_CAPP(CHIPS)':
 C_PATH='@s9s_mb_2u_lib.s9s_mb_2u(sch_1):page598_i15@pure_quanta.q_capp(chips)';

PART_NAME
 PC414 'Q_CAPP_RDLF-560UF,2.5V,20%,ALUA':;

SECTION_NUMBER 1
 '@S9S_MB_2U_LIB.S9S_MB_2U(SCH_1):PAGE598_I16@PURE_QUANTA.Q_CAPP(CHIPS)':
 C_PATH='@s9s_mb_2u_lib.s9s_mb_2u(sch_1):page598_i16@pure_quanta.q_capp(chips)';

PART_NAME
 PC413_P1_2 'Q_CAP_0805-22UF,4V,20%,X6S,TMPA':;

SECTION_NUMBER 1
 '@S9S_MB_2U_LIB.S9S_MB_2U(SCH_1):PAGE598_I19@PURE_QUANTA.Q_CAP(CHIPS)':
 C_PATH='@s9s_mb_2u_lib.s9s_mb_2u(sch_1):page598_i19@pure_quanta.q_cap(chips)';

PART_NAME
 PC412_P1_1 'Q_CAP_0805-22UF,4V,20%,X6S,TMPA':;

SECTION_NUMBER 1
 '@S9S_MB_2U_LIB.S9S_MB_2U(SCH_1):PAGE598_I12@PURE_QUANTA.Q_CAP(CHIPS)':
 C_PATH='@s9s_mb_2u_lib.s9s_mb_2u(sch_1):page598_i12@pure_quanta.q_cap(chips)';

PART_NAME
 PC411_P1_2 'Q_CAP_0805-22UF,4V,20%,X6S,TMPA':;

SECTION_NUMBER 1
 '@S9S_MB_2U_LIB.S9S_MB_2U(SCH_1):PAGE598_I20@PURE_QUANTA.Q_CAP(CHIPS)':
 C_PATH='@s9s_mb_2u_lib.s9s_mb_2u(sch_1):page598_i20@pure_quanta.q_cap(chips)';

PART_NAME
 PC410_P1_1 'Q_CAP_0805-22UF,4V,20%,X6S,TMPA':;

SECTION_NUMBER 1
 '@S9S_MB_2U_LIB.S9S_MB_2U(SCH_1):PAGE598_I13@PURE_QUANTA.Q_CAP(CHIPS)':
 C_PATH='@s9s_mb_2u_lib.s9s_mb_2u(sch_1):page598_i13@pure_quanta.q_cap(chips)';

PART_NAME
 PC406_P1_2 'Q_CAP_C0805-22UF,16V,20%,X6S,CA':;

SECTION_NUMBER 1
 '@S9S_MB_2U_LIB.S9S_MB_2U(SCH_1):PAGE598_I36@PURE_QUANTA.Q_CAP(CHIPS)':
 C_PATH='@s9s_mb_2u_lib.s9s_mb_2u(sch_1):page598_i36@pure_quanta.q_cap(chips)';

PART_NAME
 PC405_P1_1 'Q_CAP_C0805-22UF,16V,20%,X6S,CA':;

SECTION_NUMBER 1
 '@S9S_MB_2U_LIB.S9S_MB_2U(SCH_1):PAGE598_I24@PURE_QUANTA.Q_CAP(CHIPS)':
 C_PATH='@s9s_mb_2u_lib.s9s_mb_2u(sch_1):page598_i24@pure_quanta.q_cap(chips)';

PART_NAME
 PC404_P1_2 'Q_CAP_C0805-22UF,16V,20%,X6S,CA':;

SECTION_NUMBER 1
 '@S9S_MB_2U_LIB.S9S_MB_2U(SCH_1):PAGE598_I37@PURE_QUANTA.Q_CAP(CHIPS)':
 C_PATH='@s9s_mb_2u_lib.s9s_mb_2u(sch_1):page598_i37@pure_quanta.q_cap(chips)';

PART_NAME
 PC403_P1_1 'Q_CAP_C0805-22UF,16V,20%,X6S,CA':;

SECTION_NUMBER 1
 '@S9S_MB_2U_LIB.S9S_MB_2U(SCH_1):PAGE598_I25@PURE_QUANTA.Q_CAP(CHIPS)':
 C_PATH='@s9s_mb_2u_lib.s9s_mb_2u(sch_1):page598_i25@pure_quanta.q_cap(chips)';

PART_NAME
 PC402 'Q_CAP_C0402-100NF,50V,10%,X7R,A':;

SECTION_NUMBER 1
 '@S9S_MB_2U_LIB.S9S_MB_2U(SCH_1):PAGE598_I98@PURE_QUANTA.Q_CAP(CHIPS)':
 C_PATH='@s9s_mb_2u_lib.s9s_mb_2u(sch_1):page598_i98@pure_quanta.q_cap(chips)';

PART_NAME
 PC401 'Q_CAP_C0402-100NF,50V,10%,X7R,A':;

SECTION_NUMBER 1
 '@S9S_MB_2U_LIB.S9S_MB_2U(SCH_1):PAGE598_I97@PURE_QUANTA.Q_CAP(CHIPS)':
 C_PATH='@s9s_mb_2u_lib.s9s_mb_2u(sch_1):page598_i97@pure_quanta.q_cap(chips)';

PART_NAME
 PC400_P1_2 'Q_CAP_C0402-1UF,16V,10%,X6S,CHA':;

SECTION_NUMBER 1
 '@S9S_MB_2U_LIB.S9S_MB_2U(SCH_1):PAGE598_I40@PURE_QUANTA.Q_CAP(CHIPS)':
 C_PATH='@s9s_mb_2u_lib.s9s_mb_2u(sch_1):page598_i40@pure_quanta.q_cap(chips)';

PART_NAME
 PC399_P1_1 'Q_CAP_C0402-1UF,16V,10%,X6S,CHA':;

SECTION_NUMBER 1
 '@S9S_MB_2U_LIB.S9S_MB_2U(SCH_1):PAGE598_I26@PURE_QUANTA.Q_CAP(CHIPS)':
 C_PATH='@s9s_mb_2u_lib.s9s_mb_2u(sch_1):page598_i26@pure_quanta.q_cap(chips)';

PART_NAME
 PC398_P1_2 'Q_CAP_0402-3300PF,50V,10%,X7R,A':;

SECTION_NUMBER 1
 '@S9S_MB_2U_LIB.S9S_MB_2U(SCH_1):PAGE598_I41@PURE_QUANTA.Q_CAP(CHIPS)':
 C_PATH='@s9s_mb_2u_lib.s9s_mb_2u(sch_1):page598_i41@pure_quanta.q_cap(chips)';

PART_NAME
 PC397_P1_1 'Q_CAP_0402-3300PF,50V,10%,X7R,A':;

SECTION_NUMBER 1
 '@S9S_MB_2U_LIB.S9S_MB_2U(SCH_1):PAGE598_I27@PURE_QUANTA.Q_CAP(CHIPS)':
 C_PATH='@s9s_mb_2u_lib.s9s_mb_2u(sch_1):page598_i27@pure_quanta.q_cap(chips)';

PART_NAME
 PC396 'Q_CAP_C0402-2.2UF,10V,10%,X6S,A':;

SECTION_NUMBER 1
 '@S9S_MB_2U_LIB.S9S_MB_2U(SCH_1):PAGE598_I62@PURE_QUANTA.Q_CAP(CHIPS)':
 C_PATH='@s9s_mb_2u_lib.s9s_mb_2u(sch_1):page598_i62@pure_quanta.q_cap(chips)';

PART_NAME
 PC395 'Q_CAP_C0402-2.2UF,10V,10%,X6S,A':;

SECTION_NUMBER 1
 '@S9S_MB_2U_LIB.S9S_MB_2U(SCH_1):PAGE598_I51@PURE_QUANTA.Q_CAP(CHIPS)':
 C_PATH='@s9s_mb_2u_lib.s9s_mb_2u(sch_1):page598_i51@pure_quanta.q_cap(chips)';

PART_NAME
 PU18 'ISL69260IRAZT-ISL69260IRAZ-T,SA':;

SECTION_NUMBER 1
 '@S9S_MB_2U_LIB.S9S_MB_2U(SCH_1):PAGE602_I194@PURE_QUANTA.ISL69260IRAZT(CHIPS)':
 C_PATH='@s9s_mb_2u_lib.s9s_mb_2u(sch_1):page602_i194@pure_quanta.isl69260irazt(ch~
ips)',
 CDSVAR_REPCELL_ONSEMI='pure_quanta|fd5001',
 VAR_0_ONSEMI='VAR_REPLACED|ISL69260IRAZT|VAR_PARTNAME|FD5001|VALUE|FD5001|PART_~
TYPE|SMLF|MATERIAL|IC|PART_NUMBER|AL005001004|STANDARD||LIFECYCLE||PART_NUMBER|A~
L005001004|JEDEC_TYPE|VFQFPN40_TH_0-4_5X5XC|DESCRIPTION|IC OTHER(40P) FD5001(QFN~
)|MANUFTR|ONS|MANUF_PN|FD5001|RD_CMPLS_LVL|EP(V1)|CMPLS_LVL||FROM_PJ|S9S-KIMI|CL~
ASS|IC|DIP_SMD||DATA|ONS_FD5001.pdf|EE_CHECK_LIST||FP_ECN|FD5001.msg|PSL||CREATO~
R||STATUS||MSD|NA|ESD_CDM|NA|ESD_HBM|NA|ESD_MM|NA|PIN_LENGTH_SHORT_PIN|0 MILS|PI~
N_LENGTH_LONG_PIN|0 MILS|CREATEDAY|20200421|VARIANT_DEVICE_TYPE|FD5001-FD5001,SM~
LF,IC,AL005001';

PART_NAME
 PR1747 'Q_RES_0402LF-100,1%,1/16W,CHIPA':;

SECTION_NUMBER 1
 '@S9S_MB_2U_LIB.S9S_MB_2U(SCH_1):PAGE602_I192@PURE_QUANTA.Q_RES(CHIPS)':
 C_PATH='@s9s_mb_2u_lib.s9s_mb_2u(sch_1):page602_i192@pure_quanta.q_res(chips)';

PART_NAME
 PR1718 'Q_RES_0402LF-49.9     ,1%  ,1/A':;

SECTION_NUMBER 1
 '@S9S_MB_2U_LIB.S9S_MB_2U(SCH_1):PAGE602_I191@PURE_QUANTA.Q_RES(CHIPS)':
 C_PATH='@s9s_mb_2u_lib.s9s_mb_2u(sch_1):page602_i191@pure_quanta.q_res(chips)';

PART_NAME
 PR1410 'Q_RES_0402LF-49.9     ,1%  ,1/A':;

SECTION_NUMBER 1
 '@S9S_MB_2U_LIB.S9S_MB_2U(SCH_1):PAGE602_I181@PURE_QUANTA.Q_RES(CHIPS)':
 C_PATH='@s9s_mb_2u_lib.s9s_mb_2u(sch_1):page602_i181@pure_quanta.q_res(chips)',
 CDSVAR_REPCELL_ONSEMI='pure_quanta|Q_res',
 VAR_0_ONSEMI='VALUE|0|TOLERANCE|5%|WATTAGE|1/16W|PACK_TYPE|0402LF|MATERIAL|CHIP~
|PART_NUMBER|CS00002JB38|STANDARD|End of Design|LIFECYCLE|Comp-Approve|PART_NUMB~
ER|CS00002JB38|JEDEC_TYPE|R0402|ALT_SYMBOLS|(R0402-0201)|VALUE|0|TOL|5%|WATTAGE|~
1/16W|CLASS|DISCRETE|DESCRIPTION|RESISTOR CHIP 0 1/16W +-5%(0402)|COMPONENT_TYPE~
|CHIP0402|LEAD_LENGTH||DFM_EXCLUSION||DAY|20100618|VARIANT_DEVICE_TYPE|Q_RES-0,5~
%,1/16W,0402LF,CHIP,C';

PART_NAME
 PR1400 'Q_RES_0402LF-49.9     ,1%  ,1/A':;

SECTION_NUMBER 1
 '@S9S_MB_2U_LIB.S9S_MB_2U(SCH_1):PAGE602_I182@PURE_QUANTA.Q_RES(CHIPS)':
 C_PATH='@s9s_mb_2u_lib.s9s_mb_2u(sch_1):page602_i182@pure_quanta.q_res(chips)',
 CDSVAR_REPCELL_ONSEMI='pure_quanta|Q_res',
 VAR_0_ONSEMI='VALUE|0|TOLERANCE|5%|WATTAGE|1/16W|PACK_TYPE|0402LF|MATERIAL|CHIP~
|PART_NUMBER|CS00002JB38|STANDARD|End of Design|LIFECYCLE|Comp-Approve|PART_NUMB~
ER|CS00002JB38|JEDEC_TYPE|R0402|ALT_SYMBOLS|(R0402-0201)|VALUE|0|TOL|5%|WATTAGE|~
1/16W|CLASS|DISCRETE|DESCRIPTION|RESISTOR CHIP 0 1/16W +-5%(0402)|COMPONENT_TYPE~
|CHIP0402|LEAD_LENGTH||DFM_EXCLUSION||DAY|20100618|VARIANT_DEVICE_TYPE|Q_RES-0,5~
%,1/16W,0402LF,CHIP,C';

PART_NAME
 PR1315 'Q_RES_0402LF-0,5%,1/16W,CHIP,CA':;

SECTION_NUMBER 1
 '@S9S_MB_2U_LIB.S9S_MB_2U(SCH_1):PAGE602_I193@PURE_QUANTA.Q_RES(CHIPS)':
 C_PATH='@s9s_mb_2u_lib.s9s_mb_2u(sch_1):page602_i193@pure_quanta.q_res(chips)';

PART_NAME
 PR559 'Q_RES_0402LF-100,1%,1/16W,CHIPA':;

SECTION_NUMBER 1
 '@S9S_MB_2U_LIB.S9S_MB_2U(SCH_1):PAGE602_I96@PURE_QUANTA.Q_RES(CHIPS)':
 C_PATH='@s9s_mb_2u_lib.s9s_mb_2u(sch_1):page602_i96@pure_quanta.q_res(chips)';

PART_NAME
 PR558 'Q_RES_0402LF-100,1%,1/16W,CHIPA':;

SECTION_NUMBER 1
 '@S9S_MB_2U_LIB.S9S_MB_2U(SCH_1):PAGE602_I94@PURE_QUANTA.Q_RES(CHIPS)':
 C_PATH='@s9s_mb_2u_lib.s9s_mb_2u(sch_1):page602_i94@pure_quanta.q_res(chips)';

PART_NAME
 PR223 'Q_RES_0402LF-1K,1%,1/16W,CHIP,A':;

SECTION_NUMBER 1
 '@S9S_MB_2U_LIB.S9S_MB_2U(SCH_1):PAGE602_I144@PURE_QUANTA.Q_RES(CHIPS)':
 C_PATH='@s9s_mb_2u_lib.s9s_mb_2u(sch_1):page602_i144@pure_quanta.q_res(chips)';

PART_NAME
 PR220 'Q_RES_0402LF-1,1%,1/16W,CHIP,CA':;

SECTION_NUMBER 1
 '@S9S_MB_2U_LIB.S9S_MB_2U(SCH_1):PAGE602_I158@PURE_QUANTA.Q_RES(CHIPS)':
 C_PATH='@s9s_mb_2u_lib.s9s_mb_2u(sch_1):page602_i158@pure_quanta.q_res(chips)';

PART_NAME
 PR218 'Q_RES_0402LF-1K,1%,1/16W,EMPTYA':;

SECTION_NUMBER 1
 '@S9S_MB_2U_LIB.S9S_MB_2U(SCH_1):PAGE602_I106@PURE_QUANTA.Q_RES(CHIPS)':
 C_PATH='@s9s_mb_2u_lib.s9s_mb_2u(sch_1):page602_i106@pure_quanta.q_res(chips)';

PART_NAME
 PR217 'Q_RES_0402LF-1K,1%,1/16W,CHIP,A':;

SECTION_NUMBER 1
 '@S9S_MB_2U_LIB.S9S_MB_2U(SCH_1):PAGE602_I113@PURE_QUANTA.Q_RES(CHIPS)':
 C_PATH='@s9s_mb_2u_lib.s9s_mb_2u(sch_1):page602_i113@pure_quanta.q_res(chips)';

PART_NAME
 PR216 'Q_RES_0402LF-0,5%,1/16W,CHIP,CA':;

SECTION_NUMBER 1
 '@S9S_MB_2U_LIB.S9S_MB_2U(SCH_1):PAGE602_I119@PURE_QUANTA.Q_RES(CHIPS)':
 C_PATH='@s9s_mb_2u_lib.s9s_mb_2u(sch_1):page602_i119@pure_quanta.q_res(chips)';

PART_NAME
 PR215 'Q_RES_0402LF-1K,1%,1/16W,CHIP,A':;

SECTION_NUMBER 1
 '@S9S_MB_2U_LIB.S9S_MB_2U(SCH_1):PAGE602_I112@PURE_QUANTA.Q_RES(CHIPS)':
 C_PATH='@s9s_mb_2u_lib.s9s_mb_2u(sch_1):page602_i112@pure_quanta.q_res(chips)';

PART_NAME
 PR214 'Q_RES_0402LF-1K,1%,1/16W,EMPTYA':;

SECTION_NUMBER 1
 '@S9S_MB_2U_LIB.S9S_MB_2U(SCH_1):PAGE602_I103@PURE_QUANTA.Q_RES(CHIPS)':
 C_PATH='@s9s_mb_2u_lib.s9s_mb_2u(sch_1):page602_i103@pure_quanta.q_res(chips)';

PART_NAME
 PR213 'Q_RES_0402LF-33.2,1%,1/16W,CHIA':;

SECTION_NUMBER 1
 '@S9S_MB_2U_LIB.S9S_MB_2U(SCH_1):PAGE602_I122@PURE_QUANTA.Q_RES(CHIPS)':
 C_PATH='@s9s_mb_2u_lib.s9s_mb_2u(sch_1):page602_i122@pure_quanta.q_res(chips)';

PART_NAME
 PR212 'Q_RES_0402LF-0,5%,1/16W,CHIP,CA':;

SECTION_NUMBER 1
 '@S9S_MB_2U_LIB.S9S_MB_2U(SCH_1):PAGE602_I121@PURE_QUANTA.Q_RES(CHIPS)':
 C_PATH='@s9s_mb_2u_lib.s9s_mb_2u(sch_1):page602_i121@pure_quanta.q_res(chips)';

PART_NAME
 PR211 'Q_RES_0402LF-0,5%,1/16W,CHIP,CA':;

SECTION_NUMBER 1
 '@S9S_MB_2U_LIB.S9S_MB_2U(SCH_1):PAGE602_I124@PURE_QUANTA.Q_RES(CHIPS)':
 C_PATH='@s9s_mb_2u_lib.s9s_mb_2u(sch_1):page602_i124@pure_quanta.q_res(chips)';

PART_NAME
 PR210 'Q_RES_0402LF-0,5%,1/16W,CHIP,CA':;

SECTION_NUMBER 1
 '@S9S_MB_2U_LIB.S9S_MB_2U(SCH_1):PAGE602_I125@PURE_QUANTA.Q_RES(CHIPS)':
 C_PATH='@s9s_mb_2u_lib.s9s_mb_2u(sch_1):page602_i125@pure_quanta.q_res(chips)';

PART_NAME
 PR209 'Q_RES_0402LF-150,1%,1/16W,CHIPA':;

SECTION_NUMBER 1
 '@S9S_MB_2U_LIB.S9S_MB_2U(SCH_1):PAGE602_I127@PURE_QUANTA.Q_RES(CHIPS)':
 C_PATH='@s9s_mb_2u_lib.s9s_mb_2u(sch_1):page602_i127@pure_quanta.q_res(chips)';

PART_NAME
 PR208 'Q_RES_0402LF-0,5%,1/16W,CHIP,CA':;

SECTION_NUMBER 1
 '@S9S_MB_2U_LIB.S9S_MB_2U(SCH_1):PAGE602_I128@PURE_QUANTA.Q_RES(CHIPS)':
 C_PATH='@s9s_mb_2u_lib.s9s_mb_2u(sch_1):page602_i128@pure_quanta.q_res(chips)';

PART_NAME
 PR207 'Q_RES_0402LF-0,5%,1/16W,CHIP,CA':;

SECTION_NUMBER 1
 '@S9S_MB_2U_LIB.S9S_MB_2U(SCH_1):PAGE602_I126@PURE_QUANTA.Q_RES(CHIPS)':
 C_PATH='@s9s_mb_2u_lib.s9s_mb_2u(sch_1):page602_i126@pure_quanta.q_res(chips)';

PART_NAME
 PR206 'Q_RES_0402LF-1K,1%,1/16W,CHIP,A':;

SECTION_NUMBER 1
 '@S9S_MB_2U_LIB.S9S_MB_2U(SCH_1):PAGE602_I129@PURE_QUANTA.Q_RES(CHIPS)':
 C_PATH='@s9s_mb_2u_lib.s9s_mb_2u(sch_1):page602_i129@pure_quanta.q_res(chips)';

PART_NAME
 PR203 'Q_RES_0402LF-30.1K    ,1%  ,1/A':;

SECTION_NUMBER 1
 '@S9S_MB_2U_LIB.S9S_MB_2U(SCH_1):PAGE602_I183@PURE_QUANTA.Q_RES(CHIPS)':
 C_PATH='@s9s_mb_2u_lib.s9s_mb_2u(sch_1):page602_i183@pure_quanta.q_res(chips)',
 CDSVAR_REPCELL_ONSEMI='pure_quanta|Q_res',
 VAR_0_ONSEMI='VALUE|59K|TOLERANCE|1%|WATTAGE|1/16W |PACK_TYPE|0402LF |MATERIAL|~
CHIP|PART_NUMBER|TMP_QCS35902FB03|STANDARD||LIFECYCLE||PART_NUMBER|CS35902FB03|J~
EDEC_TYPE|R0402|ALT_SYMBOLS|(R0402-0201)|VALUE|59K|TOL|1%|WATTAGE|1/16W |CLASS|D~
ISCRETE|DESCRIPTION|RESISTOR CHIP 59K 1/16W +-1%(0402)|COMPONENT_TYPE|CHIP0402 |~
LEAD_LENGTH||DFM_EXCLUSION||DAY||VARIANT_DEVICE_TYPE|Q_RES-59K,1%,1/16W ,0402LF ~
,CH';

PART_NAME
 PR202 'Q_RES_0402LF-28K,1%,1/16W,EMPTA':;

SECTION_NUMBER 1
 '@S9S_MB_2U_LIB.S9S_MB_2U(SCH_1):PAGE602_I84@PURE_QUANTA.Q_RES(CHIPS)':
 C_PATH='@s9s_mb_2u_lib.s9s_mb_2u(sch_1):page602_i84@pure_quanta.q_res(chips)';

PART_NAME
 PJ48 'Q_SHORT_SM-EMPTY,SHORT6':;

SECTION_NUMBER 1
 '@S9S_MB_2U_LIB.S9S_MB_2U(SCH_1):PAGE602_I95@PURE_QUANTA.Q_SHORT(CHIPS)':
 C_PATH='@s9s_mb_2u_lib.s9s_mb_2u(sch_1):page602_i95@pure_quanta.q_short(chips)';

PART_NAME
 PC1337 'Q_CAP_0402-0.1UF,25V,10%,X7R,CA':;

SECTION_NUMBER 1
 '@S9S_MB_2U_LIB.S9S_MB_2U(SCH_1):PAGE602_I188@PURE_QUANTA.Q_CAP(CHIPS)':
 C_PATH='@s9s_mb_2u_lib.s9s_mb_2u(sch_1):page602_i188@pure_quanta.q_cap(chips)';

PART_NAME
 PC1336 'Q_CAP_C0402-10UF,6.3V,20%,X6S,A':;

SECTION_NUMBER 1
 '@S9S_MB_2U_LIB.S9S_MB_2U(SCH_1):PAGE602_I186@PURE_QUANTA.Q_CAP(CHIPS)':
 C_PATH='@s9s_mb_2u_lib.s9s_mb_2u(sch_1):page602_i186@pure_quanta.q_cap(chips)';

PART_NAME
 PC1289 'Q_CAP_C0402-1UF,16V,10%,X6S,CHA':;

SECTION_NUMBER 1
 '@S9S_MB_2U_LIB.S9S_MB_2U(SCH_1):PAGE602_I156@PURE_QUANTA.Q_CAP(CHIPS)':
 C_PATH='@s9s_mb_2u_lib.s9s_mb_2u(sch_1):page602_i156@pure_quanta.q_cap(chips)';

PART_NAME
 PC394 'Q_CAP_C0402-1UF,16V,10%,X6S,CHA':;

SECTION_NUMBER 1
 '@S9S_MB_2U_LIB.S9S_MB_2U(SCH_1):PAGE602_I157@PURE_QUANTA.Q_CAP(CHIPS)':
 C_PATH='@s9s_mb_2u_lib.s9s_mb_2u(sch_1):page602_i157@pure_quanta.q_cap(chips)';

PART_NAME
 PC393 'Q_CAP_0402-470PF,50V,10%,X7R,TA':;

SECTION_NUMBER 1
 '@S9S_MB_2U_LIB.S9S_MB_2U(SCH_1):PAGE602_I141@PURE_QUANTA.Q_CAP(CHIPS)':
 C_PATH='@s9s_mb_2u_lib.s9s_mb_2u(sch_1):page602_i141@pure_quanta.q_cap(chips)',
 CDSVAR_REPCELL_ONSEMI='pure_quanta|Q_cap',
 VAR_0_ONSEMI='VALUE|2200PF|VOLTAGE|50V|TOLERANCE|10%|PACK_TYPE|C0402|MATERIAL|X~
7R|PART_NUMBER|CH2226K1B06|STANDARD||LIFECYCLE||ASS_PART||PART_NUMBER|CH2226K1B0~
6|JEDEC_TYPE|C0402|ALT_SYMBOLS|(C0402-0201)|VALUE|2200PF|RATED_VOLTAGE|50V|TOL|1~
0%|CLASS|DISCRETE|DESCRIPTION|CAP CHIP 2200P 50V(+-10%,X7R,0402)MUR|COMPONENT_TY~
PE|CHIP0402|LEAD_LENGTH||LPID||DATE|20150614|VARIANT_DEVICE_TYPE|Q_CAP-2200PF,50~
V,10%,C0402,X7R';

PART_NAME
 PC392 'Q_CAP_0402-4.7UF,6.3V,20%,X6S,A':;

SECTION_NUMBER 1
 '@S9S_MB_2U_LIB.S9S_MB_2U(SCH_1):PAGE602_I138@PURE_QUANTA.Q_CAP(CHIPS)':
 C_PATH='@s9s_mb_2u_lib.s9s_mb_2u(sch_1):page602_i138@pure_quanta.q_cap(chips)',
 CDSVAR_REPCELL_ONSEMI='pure_quanta|Q_cap',
 VAR_0_ONSEMI='VALUE|4.7UF|VOLTAGE|6.3V|TOLERANCE|20%|PACK_TYPE|0402|MATERIAL|EM~
PTY|PART_NUMBER|CH5471MEB01|STANDARD||LIFECYCLE||ASS_PART||PART_NUMBER|CH5471MEB~
01|JEDEC_TYPE|C0402|ALT_SYMBOLS|(C0402_OCTAGON,C0402_OCTAGONXA,C0402-0201)|VALUE~
|NA|RATED_VOLTAGE|6.3V|TOL|20%|CLASS|IO|DESCRIPTION|CAP CHIP 4.7UF 6.3V(+-20%,X6~
S,0402)|COMPONENT_TYPE|CHIP0402|LEAD_LENGTH||LPID||DATE|20151211|VARIANT_DEVICE_~
TYPE|Q_CAP-4.7UF,6.3V,20%,0402,EMPT';

PART_NAME
 PC391 'Q_CAP_C0402-100NF,50V,10%,EMPTA':;

SECTION_NUMBER 1
 '@S9S_MB_2U_LIB.S9S_MB_2U(SCH_1):PAGE602_I139@PURE_QUANTA.Q_CAP(CHIPS)':
 C_PATH='@s9s_mb_2u_lib.s9s_mb_2u(sch_1):page602_i139@pure_quanta.q_cap(chips)';

PART_NAME
 PC390 'Q_CAP_0402-0.1UF,25V,10%,X7R,CA':;

SECTION_NUMBER 1
 '@S9S_MB_2U_LIB.S9S_MB_2U(SCH_1):PAGE602_I108@PURE_QUANTA.Q_CAP(CHIPS)':
 C_PATH='@s9s_mb_2u_lib.s9s_mb_2u(sch_1):page602_i108@pure_quanta.q_cap(chips)',
 CDSVAR_REPCELL_ONSEMI='pure_quanta|Q_cap',
 VAR_0_ONSEMI='VALUE|1UF|VOLTAGE|16V|TOLERANCE|10%|PACK_TYPE|C0402|MATERIAL|X6S|~
PART_NUMBER|CH5103KEB01|STANDARD||LIFECYCLE||ASS_PART||PART_NUMBER|CH5103KEB01|J~
EDEC_TYPE|C0402|ALT_SYMBOLS|(C0402-0201)|VALUE|1UF|RATED_VOLTAGE|16V|TOL|10%|CLA~
SS|DISCRETE|DESCRIPTION|CAP CHIP 1UF 16V(10%,X6S,0402)|COMPONENT_TYPE|CHIP0402|L~
EAD_LENGTH||LPID||DATE|20140828|VARIANT_DEVICE_TYPE|Q_CAP-1UF,16V,10%,C0402,X6S,~
CH';

PART_NAME
 PC389 'Q_CAP_0402-3300PF,50V,10%,X7R,A':;

SECTION_NUMBER 1
 '@S9S_MB_2U_LIB.S9S_MB_2U(SCH_1):PAGE602_I123@PURE_QUANTA.Q_CAP(CHIPS)':
 C_PATH='@s9s_mb_2u_lib.s9s_mb_2u(sch_1):page602_i123@pure_quanta.q_cap(chips)',
 CDSVAR_REPCELL_ONSEMI='pure_quanta|Q_cap',
 VAR_0_ONSEMI='VALUE|1NF|VOLTAGE|50V|TOLERANCE|10%|PACK_TYPE|0402|MATERIAL|X7R|P~
ART_NUMBER|CH21006KB16|STANDARD||LIFECYCLE||ASS_PART||PART_NUMBER|CH21006KB16|JE~
DEC_TYPE|C0402|ALT_SYMBOLS|(C0402-0201)|VALUE|1NF|RATED_VOLTAGE|50V|TOL|10%|CLAS~
S|DISCRETE|DESCRIPTION|CAP CHIP 1N 50V(+-10%,X7R,0402)EP|COMPONENT_TYPE|CHIP0402~
|LEAD_LENGTH||LPID||DATE|20100811|VARIANT_DEVICE_TYPE|Q_CAP-1NF,50V,10%,0402,X7R~
,CH2';

PART_NAME
 PC388 'Q_CAP_0402-1000PF,50V,5%,EMPTYA':;

SECTION_NUMBER 1
 '@S9S_MB_2U_LIB.S9S_MB_2U(SCH_1):PAGE602_I132@PURE_QUANTA.Q_CAP(CHIPS)':
 C_PATH='@s9s_mb_2u_lib.s9s_mb_2u(sch_1):page602_i132@pure_quanta.q_cap(chips)';

PART_NAME
 PC386 'Q_CAP_0402-0.1UF,25V,10%,X7R,CA':;

SECTION_NUMBER 1
 '@S9S_MB_2U_LIB.S9S_MB_2U(SCH_1):PAGE602_I105@PURE_QUANTA.Q_CAP(CHIPS)':
 C_PATH='@s9s_mb_2u_lib.s9s_mb_2u(sch_1):page602_i105@pure_quanta.q_cap(chips)',
 CDSVAR_REPCELL_ONSEMI='pure_quanta|Q_cap',
 VAR_0_ONSEMI='VALUE|1UF|VOLTAGE|16V|TOLERANCE|10%|PACK_TYPE|C0402|MATERIAL|X6S|~
PART_NUMBER|CH5103KEB01|STANDARD||LIFECYCLE||ASS_PART||PART_NUMBER|CH5103KEB01|J~
EDEC_TYPE|C0402|ALT_SYMBOLS|(C0402-0201)|VALUE|1UF|RATED_VOLTAGE|16V|TOL|10%|CLA~
SS|DISCRETE|DESCRIPTION|CAP CHIP 1UF 16V(10%,X6S,0402)|COMPONENT_TYPE|CHIP0402|L~
EAD_LENGTH||LPID||DATE|20140828|VARIANT_DEVICE_TYPE|Q_CAP-1UF,16V,10%,C0402,X6S,~
CH';

PART_NAME
 PU17 'RAA2213404GNPHB0-RAA2213404GNPA':;

SECTION_NUMBER 1
 '@S9S_MB_2U_LIB.S9S_MB_2U(SCH_1):PAGE603_I110@PURE_QUANTA.RAA2213404GNPHB0(CHIPS)':
 C_PATH='@s9s_mb_2u_lib.s9s_mb_2u(sch_1):page603_i110@pure_quanta.raa2213404gnphb0~
(chips)',
 CDSVAR_REPCELL_ONSEMI='pure_quanta|fdmf5076',
 VAR_0_ONSEMI='VAR_REPLACED|RAA2213404GNPHB0|VAR_PARTNAME|FDMF5076|VALUE|FDMF507~
6|PART_TYPE|SMLF|MATERIAL|IC|PART_NUMBER|AL005076000|STANDARD||LIFECYCLE||PART_N~
UMBER|AL005076000|JEDEC_TYPE|PQFN17_TH_5X4XA|DESCRIPTION|IC OTHER(27P)FDMF5076(P~
QFN)|MANUFTR|ONS|MANUF_PN|FDMF5076|RD_CMPLS_LVL|EP(V1)|CMPLS_LVL|EP(V1)|FROM_PJ|~
S9S-KIMI|CLASS|IC|DIP_SMD||DATA|ONS_FDMF5076.pdf|EE_CHECK_LIST||FP_ECN|FDMF5076.~
msg|PSL||CREATOR||STATUS||MSD|NA|ESD_CDM|NA|ESD_HBM|NA|ESD_MM|NA|PIN_LENGTH_SHOR~
T_PIN|0 MILS|PIN_LENGTH_LONG_PIN|0 MILS|CREATEDAY|20200416|VARIANT_DEVICE_TYPE|F~
DMF5076-FDMF5076,SMLF,IC,AL00';

PART_NAME
 PR1805 'Q_RES_0402LF-0,5%,1/16W,CHIP,CA':;

SECTION_NUMBER 1
 '@S9S_MB_2U_LIB.S9S_MB_2U(SCH_1):PAGE603_I162@PURE_QUANTA.Q_RES(CHIPS)':
 C_PATH='@s9s_mb_2u_lib.s9s_mb_2u(sch_1):page603_i162@pure_quanta.q_res(chips)',
 CDSVAR_REPCELL_ONSEMI='pure_quanta|Q_res',
 VAR_0_ONSEMI='VALUE|0|TOLERANCE|5%|WATTAGE|1/16W|PACK_TYPE|0402LF|MATERIAL|EMPT~
Y|PART_NUMBER|CS00002JB38|STANDARD|End of Design|LIFECYCLE|Comp-Approve|PART_NUM~
BER|CS00002JB38|JEDEC_TYPE|R0402|ALT_SYMBOLS|(R0402-0201)|VALUE|0|TOL|5%|WATTAGE~
|1/16W|CLASS|IO|DESCRIPTION|RESISTOR CHIP 0 1/16W +-5%(0402)|COMPONENT_TYPE|CHIP~
0402|LEAD_LENGTH||DFM_EXCLUSION||DAY|20100618|VARIANT_DEVICE_TYPE|Q_RES-0,5%,1/1~
6W,0402LF,EMPTY,';

PART_NAME
 PR1804 'Q_RES_0402LF-4.7,1%,1/16W,CHIPA':;

SECTION_NUMBER 1
 '@S9S_MB_2U_LIB.S9S_MB_2U(SCH_1):PAGE603_I161@PURE_QUANTA.Q_RES(CHIPS)':
 C_PATH='@s9s_mb_2u_lib.s9s_mb_2u(sch_1):page603_i161@pure_quanta.q_res(chips)',
 CDSVAR_REPCELL_ONSEMI='pure_quanta|Q_res',
 VAR_0_ONSEMI='VALUE|0|TOLERANCE|5%|WATTAGE|1/16W|PACK_TYPE|0402LF|MATERIAL|CHIP~
|PART_NUMBER|CS00002JB38|STANDARD|End of Design|LIFECYCLE|Comp-Approve|PART_NUMB~
ER|CS00002JB38|JEDEC_TYPE|R0402|ALT_SYMBOLS|(R0402-0201)|VALUE|0|TOL|5%|WATTAGE|~
1/16W|CLASS|DISCRETE|DESCRIPTION|RESISTOR CHIP 0 1/16W +-5%(0402)|COMPONENT_TYPE~
|CHIP0402|LEAD_LENGTH||DFM_EXCLUSION||DAY|20100618|VARIANT_DEVICE_TYPE|Q_RES-0,5~
%,1/16W,0402LF,CHIP,C';

PART_NAME
 PR1746 'Q_RES_0402LF-8.87K,1%,1/16W,EMA':;

SECTION_NUMBER 1
 '@S9S_MB_2U_LIB.S9S_MB_2U(SCH_1):PAGE603_I169@PURE_QUANTA.Q_RES(CHIPS)':
 C_PATH='@s9s_mb_2u_lib.s9s_mb_2u(sch_1):page603_i169@pure_quanta.q_res(chips)';

PART_NAME
 PR200 'Q_RES_0402LF-2.2,1%,1/16W,CHIPA':;

SECTION_NUMBER 1
 '@S9S_MB_2U_LIB.S9S_MB_2U(SCH_1):PAGE603_I132@PURE_QUANTA.Q_RES(CHIPS)':
 C_PATH='@s9s_mb_2u_lib.s9s_mb_2u(sch_1):page603_i132@pure_quanta.q_res(chips)';

PART_NAME
 PL17 'Q_INDUCTOR_SMLF-130NH/95A,IND,A':;

SECTION_NUMBER 1
 '@S9S_MB_2U_LIB.S9S_MB_2U(SCH_1):PAGE603_I129@PURE_QUANTA.Q_INDUCTOR(CHIPS)':
 C_PATH='@s9s_mb_2u_lib.s9s_mb_2u(sch_1):page603_i129@pure_quanta.q_inductor(chips~
)';

PART_NAME
 PC1940 'Q_CAPP_RDLLF-330UF,2V,35%,C_POA':;

SECTION_NUMBER 1
 '@S9S_MB_2U_LIB.S9S_MB_2U(SCH_1):PAGE603_I158@PURE_QUANTA.Q_CAPP(CHIPS)':
 C_PATH='@s9s_mb_2u_lib.s9s_mb_2u(sch_1):page603_i158@pure_quanta.q_capp(chips)';

PART_NAME
 PC1371 'Q_CAP_0402-0.1UF,25V,10%,X7R,CA':;

SECTION_NUMBER 1
 '@S9S_MB_2U_LIB.S9S_MB_2U(SCH_1):PAGE603_I166@PURE_QUANTA.Q_CAP(CHIPS)':
 C_PATH='@s9s_mb_2u_lib.s9s_mb_2u(sch_1):page603_i166@pure_quanta.q_cap(chips)',
 CDSVAR_REPCELL_ONSEMI='pure_quanta|Q_cap',
 VAR_0_ONSEMI='VALUE|0.1UF|VOLTAGE|25V|TOLERANCE|10%|PACK_TYPE|0402|MATERIAL|EMP~
TY|PART_NUMBER|CH4104K1B00|STANDARD||LIFECYCLE||ASS_PART||PART_NUMBER|CH4104K1B0~
0|JEDEC_TYPE|C0402|ALT_SYMBOLS|(C0402_OCTAGONXA,C0402-0201)|VALUE|NA|RATED_VOLTA~
GE|25V|TOL|10%|CLASS|IO|DESCRIPTION|CAP CHIP 0.1U 25V(+-10%,X7R,0402)|COMPONENT_~
TYPE|CHIP0402|LEAD_LENGTH||LPID||DATE|20160113|VARIANT_DEVICE_TYPE|Q_CAP-0.1UF,2~
5V,10%,0402,EMPTY';

PART_NAME
 PC385 'Q_CAPP_SMLF-470UF,2.5V,20%,EMPB':;

SECTION_NUMBER 1
 '@S9S_MB_2U_LIB.S9S_MB_2U(SCH_1):PAGE603_I147@PURE_QUANTA.Q_CAPP(CHIPS)':
 C_PATH='@s9s_mb_2u_lib.s9s_mb_2u(sch_1):page603_i147@pure_quanta.q_capp(chips)';

PART_NAME
 PC384 'Q_CAPP_SMLF-470UF,2.5V,20%,OSCA':;

SECTION_NUMBER 1
 '@S9S_MB_2U_LIB.S9S_MB_2U(SCH_1):PAGE603_I145@PURE_QUANTA.Q_CAPP(CHIPS)':
 C_PATH='@s9s_mb_2u_lib.s9s_mb_2u(sch_1):page603_i145@pure_quanta.q_capp(chips)';

PART_NAME
 PC382 'Q_CAP_0805-22UF,4V,20%,X6S,TMPA':;

SECTION_NUMBER 1
 '@S9S_MB_2U_LIB.S9S_MB_2U(SCH_1):PAGE603_I125@PURE_QUANTA.Q_CAP(CHIPS)':
 C_PATH='@s9s_mb_2u_lib.s9s_mb_2u(sch_1):page603_i125@pure_quanta.q_cap(chips)';

PART_NAME
 PC381 'Q_CAP_0805-22UF,4V,20%,X6S,TMPA':;

SECTION_NUMBER 1
 '@S9S_MB_2U_LIB.S9S_MB_2U(SCH_1):PAGE603_I126@PURE_QUANTA.Q_CAP(CHIPS)':
 C_PATH='@s9s_mb_2u_lib.s9s_mb_2u(sch_1):page603_i126@pure_quanta.q_cap(chips)';

PART_NAME
 PC379 'Q_CAP_C0402-100NF,50V,10%,X7R,A':;

SECTION_NUMBER 1
 '@S9S_MB_2U_LIB.S9S_MB_2U(SCH_1):PAGE603_I128@PURE_QUANTA.Q_CAP(CHIPS)':
 C_PATH='@s9s_mb_2u_lib.s9s_mb_2u(sch_1):page603_i128@pure_quanta.q_cap(chips)';

PART_NAME
 PC378 'Q_CAP_C0805-22UF,16V,20%,X6S,CA':;

SECTION_NUMBER 1
 '@S9S_MB_2U_LIB.S9S_MB_2U(SCH_1):PAGE603_I119@PURE_QUANTA.Q_CAP(CHIPS)':
 C_PATH='@s9s_mb_2u_lib.s9s_mb_2u(sch_1):page603_i119@pure_quanta.q_cap(chips)';

PART_NAME
 PC377 'Q_CAP_C0805-22UF,16V,20%,X6S,CA':;

SECTION_NUMBER 1
 '@S9S_MB_2U_LIB.S9S_MB_2U(SCH_1):PAGE603_I120@PURE_QUANTA.Q_CAP(CHIPS)':
 C_PATH='@s9s_mb_2u_lib.s9s_mb_2u(sch_1):page603_i120@pure_quanta.q_cap(chips)';

PART_NAME
 PC376 'Q_CAP_C0402-100NF,50V,10%,X7R,A':;

SECTION_NUMBER 1
 '@S9S_MB_2U_LIB.S9S_MB_2U(SCH_1):PAGE603_I167@PURE_QUANTA.Q_CAP(CHIPS)':
 C_PATH='@s9s_mb_2u_lib.s9s_mb_2u(sch_1):page603_i167@pure_quanta.q_cap(chips)';

PART_NAME
 PC375 'Q_CAP_C0402-1UF,16V,10%,X6S,CHA':;

SECTION_NUMBER 1
 '@S9S_MB_2U_LIB.S9S_MB_2U(SCH_1):PAGE603_I122@PURE_QUANTA.Q_CAP(CHIPS)':
 C_PATH='@s9s_mb_2u_lib.s9s_mb_2u(sch_1):page603_i122@pure_quanta.q_cap(chips)';

PART_NAME
 PC374 'Q_CAP_0402-3300PF,50V,10%,X7R,A':;

SECTION_NUMBER 1
 '@S9S_MB_2U_LIB.S9S_MB_2U(SCH_1):PAGE603_I123@PURE_QUANTA.Q_CAP(CHIPS)':
 C_PATH='@s9s_mb_2u_lib.s9s_mb_2u(sch_1):page603_i123@pure_quanta.q_cap(chips)';

PART_NAME
 PC373 'Q_CAP_C0402-2.2UF,10V,10%,X6S,A':;

SECTION_NUMBER 1
 '@S9S_MB_2U_LIB.S9S_MB_2U(SCH_1):PAGE603_I134@PURE_QUANTA.Q_CAP(CHIPS)':
 C_PATH='@s9s_mb_2u_lib.s9s_mb_2u(sch_1):page603_i134@pure_quanta.q_cap(chips)';

PART_NAME
 PU48 'MOSFET_NCH_DUAL_1D1S-BSG0812NDA':;

SECTION_NUMBER 1
 '@S9S_MB_2U_LIB.S9S_MB_2U(SCH_1):PAGE575_I20@PURE_QUANTA.MOSFET_NCH_DUAL_1D1S(CHIPS)':
 C_PATH='@s9s_mb_2u_lib.s9s_mb_2u(sch_1):page575_i20@pure_quanta.mosfet_nch_dual_1~
d1s(chips)';

PART_NAME
 PU47 'MOSFET_NCH_DUAL_1D1S-BSG0812NDA':;

SECTION_NUMBER 1
 '@S9S_MB_2U_LIB.S9S_MB_2U(SCH_1):PAGE575_I43@PURE_QUANTA.MOSFET_NCH_DUAL_1D1S(CHIPS)':
 C_PATH='@s9s_mb_2u_lib.s9s_mb_2u(sch_1):page575_i43@pure_quanta.mosfet_nch_dual_1~
d1s(chips)';

PART_NAME
 PU16 'TPS51225RUKR-TPS51225RUKR,SMLFA':;

SECTION_NUMBER 1
 '@S9S_MB_2U_LIB.S9S_MB_2U(SCH_1):PAGE575_I32@PURE_QUANTA.TPS51225RUKR(CHIPS)':
 C_PATH='@s9s_mb_2u_lib.s9s_mb_2u(sch_1):page575_i32@pure_quanta.tps51225rukr(chip~
s)';

PART_NAME
 PR557 'Q_RES_0402LF-10K,0.10%,1/16W,CA':;

SECTION_NUMBER 1
 '@S9S_MB_2U_LIB.S9S_MB_2U(SCH_1):PAGE575_I15@PURE_QUANTA.Q_RES(CHIPS)':
 C_PATH='@s9s_mb_2u_lib.s9s_mb_2u(sch_1):page575_i15@pure_quanta.q_res(chips)';

PART_NAME
 PR556 'Q_RES_0402LF -6.49K,0.1%,1/16WA':;

SECTION_NUMBER 1
 '@S9S_MB_2U_LIB.S9S_MB_2U(SCH_1):PAGE575_I13@PURE_QUANTA.Q_RES(CHIPS)':
 C_PATH='@s9s_mb_2u_lib.s9s_mb_2u(sch_1):page575_i13@pure_quanta.q_res(chips)';

PART_NAME
 PR555 'Q_RES_0402LF -30K,0.1%,1/16W,CA':;

SECTION_NUMBER 1
 '@S9S_MB_2U_LIB.S9S_MB_2U(SCH_1):PAGE575_I24@PURE_QUANTA.Q_RES(CHIPS)':
 C_PATH='@s9s_mb_2u_lib.s9s_mb_2u(sch_1):page575_i24@pure_quanta.q_res(chips)';

PART_NAME
 PR554 'Q_RES_0402LF-10K,5%,1/16W,CHIPA':;

SECTION_NUMBER 1
 '@S9S_MB_2U_LIB.S9S_MB_2U(SCH_1):PAGE575_I23@PURE_QUANTA.Q_RES(CHIPS)':
 C_PATH='@s9s_mb_2u_lib.s9s_mb_2u(sch_1):page575_i23@pure_quanta.q_res(chips)';

PART_NAME
 PR553 'Q_RES_0402LF-9.1K,1%,1/16W,CHIA':;

SECTION_NUMBER 1
 '@S9S_MB_2U_LIB.S9S_MB_2U(SCH_1):PAGE575_I35@PURE_QUANTA.Q_RES(CHIPS)':
 C_PATH='@s9s_mb_2u_lib.s9s_mb_2u(sch_1):page575_i35@pure_quanta.q_res(chips)';

PART_NAME
 PR552 'Q_RES_0402LF-100K,1%,1/16W,CHIA':;

SECTION_NUMBER 1
 '@S9S_MB_2U_LIB.S9S_MB_2U(SCH_1):PAGE575_I53@PURE_QUANTA.Q_RES(CHIPS)':
 C_PATH='@s9s_mb_2u_lib.s9s_mb_2u(sch_1):page575_i53@pure_quanta.q_res(chips)';

PART_NAME
 PR551 'Q_RES_0402LF-154K,1%,1/16W,CHIA':;

SECTION_NUMBER 1
 '@S9S_MB_2U_LIB.S9S_MB_2U(SCH_1):PAGE575_I51@PURE_QUANTA.Q_RES(CHIPS)':
 C_PATH='@s9s_mb_2u_lib.s9s_mb_2u(sch_1):page575_i51@pure_quanta.q_res(chips)';

PART_NAME
 PR550 'Q_RES_0402LF-130K,5%,1/16W,CHIA':;

SECTION_NUMBER 1
 '@S9S_MB_2U_LIB.S9S_MB_2U(SCH_1):PAGE575_I64@PURE_QUANTA.Q_RES(CHIPS)':
 C_PATH='@s9s_mb_2u_lib.s9s_mb_2u(sch_1):page575_i64@pure_quanta.q_res(chips)';

PART_NAME
 PR549 'Q_RES_0402LF-510K,5%,1/16W,CHIA':;

SECTION_NUMBER 1
 '@S9S_MB_2U_LIB.S9S_MB_2U(SCH_1):PAGE575_I63@PURE_QUANTA.Q_RES(CHIPS)':
 C_PATH='@s9s_mb_2u_lib.s9s_mb_2u(sch_1):page575_i63@pure_quanta.q_res(chips)';

PART_NAME
 PR548 'Q_RES_0402LF-10K,1%,1/16W,CHIPA':;

SECTION_NUMBER 1
 '@S9S_MB_2U_LIB.S9S_MB_2U(SCH_1):PAGE575_I60@PURE_QUANTA.Q_RES(CHIPS)':
 C_PATH='@s9s_mb_2u_lib.s9s_mb_2u(sch_1):page575_i60@pure_quanta.q_res(chips)';

PART_NAME
 PR547 'Q_RES_0402LF-15K,1%,1/16W,CHIPA':;

SECTION_NUMBER 1
 '@S9S_MB_2U_LIB.S9S_MB_2U(SCH_1):PAGE575_I58@PURE_QUANTA.Q_RES(CHIPS)':
 C_PATH='@s9s_mb_2u_lib.s9s_mb_2u(sch_1):page575_i58@pure_quanta.q_res(chips)';

PART_NAME
 PR505 'Q_RES_0402LF-0,5%,1/16W,CHIP,CA':;

SECTION_NUMBER 1
 '@S9S_MB_2U_LIB.S9S_MB_2U(SCH_1):PAGE575_I52@PURE_QUANTA.Q_RES(CHIPS)':
 C_PATH='@s9s_mb_2u_lib.s9s_mb_2u(sch_1):page575_i52@pure_quanta.q_res(chips)';

PART_NAME
 PR443 'Q_RES_0402LF-0,5%,1/16W,EMPTY,A':;

SECTION_NUMBER 1
 '@S9S_MB_2U_LIB.S9S_MB_2U(SCH_1):PAGE575_I70@PURE_QUANTA.Q_RES(CHIPS)':
 C_PATH='@s9s_mb_2u_lib.s9s_mb_2u(sch_1):page575_i70@pure_quanta.q_res(chips)';

PART_NAME
 PL41 'Q_INDUCTOR_SMLF-70NH/60A,IND,CA':;

SECTION_NUMBER 1
 '@S9S_MB_2U_LIB.S9S_MB_2U(SCH_1):PAGE575_I2@PURE_QUANTA.Q_INDUCTOR(CHIPS)':
 C_PATH='@s9s_mb_2u_lib.s9s_mb_2u(sch_1):page575_i2@pure_quanta.q_inductor(chips)';

PART_NAME
 PL40 'Q_INDUCTOR_SMLF-1.5UH/27A,IND,A':;

SECTION_NUMBER 1
 '@S9S_MB_2U_LIB.S9S_MB_2U(SCH_1):PAGE575_I16@PURE_QUANTA.Q_INDUCTOR(CHIPS)':
 C_PATH='@s9s_mb_a_lib.s9s_mb_a(sch_1):page575_i16@pure_quanta.q_inductor(chips)~
';

PART_NAME
 PL39 'Q_INDUCTOR_SMLF-4.7UH/13.5A,INA':;

SECTION_NUMBER 1
 '@S9S_MB_2U_LIB.S9S_MB_2U(SCH_1):PAGE575_I47@PURE_QUANTA.Q_INDUCTOR(CHIPS)':
 C_PATH='@s9s_mb_a_lib.s9s_mb_a(sch_1):page575_i47@pure_quanta.q_inductor(chips)~
';

PART_NAME
 PC3172 'Q_CAP_C0805-22UF,16V,20%,X6S,CA':;

SECTION_NUMBER 1
 '@S9S_MB_2U_LIB.S9S_MB_2U(SCH_1):PAGE575_I68@PURE_QUANTA.Q_CAP(CHIPS)':
 C_PATH='@s9s_mb_2u_lib.s9s_mb_2u(sch_1):page575_i68@pure_quanta.q_cap(chips)';

PART_NAME
 PC3170 'Q_CAP_C0805-22UF,16V,20%,X6S,CA':;

SECTION_NUMBER 1
 '@S9S_MB_2U_LIB.S9S_MB_2U(SCH_1):PAGE575_I66@PURE_QUANTA.Q_CAP(CHIPS)':
 C_PATH='@s9s_mb_2u_lib.s9s_mb_2u(sch_1):page575_i66@pure_quanta.q_cap(chips)';

PART_NAME
 PC2190 'Q_CAPP_RDLF-560UF,6.3V,20%,ALUA':;

SECTION_NUMBER 1
 '@S9S_MB_2U_LIB.S9S_MB_2U(SCH_1):PAGE575_I11@PURE_QUANTA.Q_CAPP(CHIPS)':
 C_PATH='@s9s_mb_2u_lib.s9s_mb_2u(sch_1):page575_i11@pure_quanta.q_capp(chips)';

PART_NAME
 PC1410 'Q_CAPP_RDLF-560UF,6.3V,20%,ALUA':;

SECTION_NUMBER 1
 '@S9S_MB_2U_LIB.S9S_MB_2U(SCH_1):PAGE575_I71@PURE_QUANTA.Q_CAPP(CHIPS)':
 C_PATH='@s9s_mb_2u_lib.s9s_mb_2u(sch_1):page575_i71@pure_quanta.q_capp(chips)';

PART_NAME
 PC1387 'Q_CAPP_RDLF-560UF,6.3V,20%,ALUA':;

SECTION_NUMBER 1
 '@S9S_MB_2U_LIB.S9S_MB_2U(SCH_1):PAGE575_I12@PURE_QUANTA.Q_CAPP(CHIPS)':
 C_PATH='@s9s_mb_2u_lib.s9s_mb_2u(sch_1):page575_i12@pure_quanta.q_capp(chips)';

PART_NAME
 PC1386 'Q_CAP_C0805-22UF,16V,20%,X6S,CA':;

SECTION_NUMBER 1
 '@S9S_MB_2U_LIB.S9S_MB_2U(SCH_1):PAGE575_I4@PURE_QUANTA.Q_CAP(CHIPS)':
 C_PATH='@s9s_mb_2u_lib.s9s_mb_2u(sch_1):page575_i4@pure_quanta.q_cap(chips)';

PART_NAME
 PC1385 'Q_CAP_0402-0.1UF,25V,10%,X7R,CA':;

SECTION_NUMBER 1
 '@S9S_MB_2U_LIB.S9S_MB_2U(SCH_1):PAGE575_I21@PURE_QUANTA.Q_CAP(CHIPS)':
 C_PATH='@s9s_mb_2u_lib.s9s_mb_2u(sch_1):page575_i21@pure_quanta.q_cap(chips)';

PART_NAME
 PC1384 'Q_CAP_C0402-1UF,25V,10%,X6S,CHA':;

SECTION_NUMBER 1
 '@S9S_MB_2U_LIB.S9S_MB_2U(SCH_1):PAGE575_I26@PURE_QUANTA.Q_CAP(CHIPS)':
 C_PATH='@s9s_mb_2u_lib.s9s_mb_2u(sch_1):page575_i26@pure_quanta.q_cap(chips)';

PART_NAME
 PC1383 'Q_CAP_0402-0.1UF,25V,10%,X7R,CA':;

SECTION_NUMBER 1
 '@S9S_MB_2U_LIB.S9S_MB_2U(SCH_1):PAGE575_I29@PURE_QUANTA.Q_CAP(CHIPS)':
 C_PATH='@s9s_mb_2u_lib.s9s_mb_2u(sch_1):page575_i29@pure_quanta.q_cap(chips)';

PART_NAME
 PC1382 'Q_CAP_C0402-1UF,25V,10%,X6S,CHA':;

SECTION_NUMBER 1
 '@S9S_MB_2U_LIB.S9S_MB_2U(SCH_1):PAGE575_I33@PURE_QUANTA.Q_CAP(CHIPS)':
 C_PATH='@s9s_mb_2u_lib.s9s_mb_2u(sch_1):page575_i33@pure_quanta.q_cap(chips)';

PART_NAME
 PC1378 'Q_CAP_C0402-1UF,25V,10%,EMPTY,A':;

SECTION_NUMBER 1
 '@S9S_MB_2U_LIB.S9S_MB_2U(SCH_1):PAGE575_I55@PURE_QUANTA.Q_CAP(CHIPS)':
 C_PATH='@s9s_mb_2u_lib.s9s_mb_2u(sch_1):page575_i55@pure_quanta.q_cap(chips)';

PART_NAME
 PC1377 'Q_CAPP_RDLF-560UF,6.3V,20%,ALUA':;

SECTION_NUMBER 1
 '@S9S_MB_2U_LIB.S9S_MB_2U(SCH_1):PAGE575_I49@PURE_QUANTA.Q_CAPP(CHIPS)':
 C_PATH='@s9s_mb_2u_lib.s9s_mb_2u(sch_1):page575_i49@pure_quanta.q_capp(chips)';

PART_NAME
 PC1188 'Q_CAP_0402-0.1UF,25V,10%,X7R,CA':;

SECTION_NUMBER 1
 '@S9S_MB_2U_LIB.S9S_MB_2U(SCH_1):PAGE575_I8@PURE_QUANTA.Q_CAP(CHIPS)':
 C_PATH='@s9s_mb_2u_lib.s9s_mb_2u(sch_1):page575_i8@pure_quanta.q_cap(chips)';

PART_NAME
 PC1181 'Q_CAP_0402-0.1UF,25V,10%,X7R,CA':;

SECTION_NUMBER 1
 '@S9S_MB_2U_LIB.S9S_MB_2U(SCH_1):PAGE575_I31@PURE_QUANTA.Q_CAP(CHIPS)':
 C_PATH='@s9s_mb_2u_lib.s9s_mb_2u(sch_1):page575_i31@pure_quanta.q_cap(chips)';

PART_NAME
 PC1179 'Q_CAP_0402-0.1UF,25V,10%,X7R,CA':;

SECTION_NUMBER 1
 '@S9S_MB_2U_LIB.S9S_MB_2U(SCH_1):PAGE575_I46@PURE_QUANTA.Q_CAP(CHIPS)':
 C_PATH='@s9s_mb_2u_lib.s9s_mb_2u(sch_1):page575_i46@pure_quanta.q_cap(chips)';

PART_NAME
 PC372 'Q_CAPP_SMLF-100UF,16V,20%,ALUMA':;

SECTION_NUMBER 1
 '@S9S_MB_2U_LIB.S9S_MB_2U(SCH_1):PAGE575_I3@PURE_QUANTA.Q_CAPP(CHIPS)':
 C_PATH='@s9s_mb_2u_lib.s9s_mb_2u(sch_1):page575_i3@pure_quanta.q_capp(chips)';

PART_NAME
 PC371 'Q_CAP_C0805-22UF,16V,20%,X6S,CA':;

SECTION_NUMBER 1
 '@S9S_MB_2U_LIB.S9S_MB_2U(SCH_1):PAGE575_I5@PURE_QUANTA.Q_CAP(CHIPS)':
 C_PATH='@s9s_mb_2u_lib.s9s_mb_2u(sch_1):page575_i5@pure_quanta.q_cap(chips)';

PART_NAME
 PC370 'Q_CAP_0402-0.1UF,25V,10%,X7R,CA':;

SECTION_NUMBER 1
 '@S9S_MB_2U_LIB.S9S_MB_2U(SCH_1):PAGE575_I6@PURE_QUANTA.Q_CAP(CHIPS)':
 C_PATH='@s9s_mb_2u_lib.s9s_mb_2u(sch_1):page575_i6@pure_quanta.q_cap(chips)';

PART_NAME
 PC369 'Q_CAP_0402-0.1UF,25V,10%,X7R,CA':;

SECTION_NUMBER 1
 '@S9S_MB_2U_LIB.S9S_MB_2U(SCH_1):PAGE575_I37@PURE_QUANTA.Q_CAP(CHIPS)':
 C_PATH='@s9s_mb_2u_lib.s9s_mb_2u(sch_1):page575_i37@pure_quanta.q_cap(chips)';

PART_NAME
 PC368 'Q_CAP_C0805-22UF,16V,20%,X6S,CA':;

SECTION_NUMBER 1
 '@S9S_MB_2U_LIB.S9S_MB_2U(SCH_1):PAGE575_I39@PURE_QUANTA.Q_CAP(CHIPS)':
 C_PATH='@s9s_mb_2u_lib.s9s_mb_2u(sch_1):page575_i39@pure_quanta.q_cap(chips)';

PART_NAME
 PC367 'Q_CAP_C0805-22UF,16V,20%,X6S,CA':;

SECTION_NUMBER 1
 '@S9S_MB_2U_LIB.S9S_MB_2U(SCH_1):PAGE575_I40@PURE_QUANTA.Q_CAP(CHIPS)':
 C_PATH='@s9s_mb_2u_lib.s9s_mb_2u(sch_1):page575_i40@pure_quanta.q_cap(chips)';

PART_NAME
 PC366 'Q_CAPP_SMLF-100UF,16V,20%,ALUMA':;

SECTION_NUMBER 1
 '@S9S_MB_2U_LIB.S9S_MB_2U(SCH_1):PAGE575_I41@PURE_QUANTA.Q_CAPP(CHIPS)':
 C_PATH='@s9s_mb_2u_lib.s9s_mb_2u(sch_1):page575_i41@pure_quanta.q_capp(chips)';

PART_NAME
 PU13_P0_1 'ISL99390FRZTR5935-ISL99390FRZ-A':;

SECTION_NUMBER 1
 '@S9S_MB_2U_LIB.S9S_MB_2U(SCH_1):PAGE585_I21@PURE_QUANTA.ISL99390FRZTR5935(CHIPS)':
 C_PATH='@s9s_mb_2u_lib.s9s_mb_2u(sch_1):page585_i21@pure_quanta.isl99390frztr5935~
(chips)',
 VAR_0_ONSEMI='VAR_REPLACED|ISL99390FRZTR5935|VAR_PARTNAME|FDMF5085|PART_TYPE|SM~
LF|MATERIAL|IC|VALUE|FDMF5085|PART_NUMBER|AL005085000|PIN_LENGTH_LONG_PIN|0 MILS~
|MSD|NA|DESCRIPTION|IC OTHER(39P) FDMF5085(PQFN)|EE_CHECK_LIST||CLASS|IC|MANUFTR~
|ONS|ESD_MM|NA|ESD_CDM|NA|FROM_PJ|S9S-KIMI|DIP_SMD||CREATEDAY|20200423|STANDARD|~
|PIN_LENGTH_SHORT_PIN|0 MILS|ESD_HBM|NA|LIFECYCLE||STATUS||PSL||RD_CMPLS_LVL|EP(~
V1)|FP_ECN||MANUF_PN|FDMF5085|CMPLS_LVL||JEDEC_TYPE|PQFN21_6X5XB|DATA|ONS_FDMF50~
85.pdf|PART_NUMBER|AL005085000|CREATOR||VARIANT_DEVICE_TYPE|FDMF5085',
 CDSVAR_REPCELL_ONSEMI='pure_quanta|fdmf5085';

PART_NAME
 PU12_P0_2 'ISL99390FRZTR5935-ISL99390FRZ-A':;

SECTION_NUMBER 1
 '@S9S_MB_2U_LIB.S9S_MB_2U(SCH_1):PAGE585_I79@PURE_QUANTA.ISL99390FRZTR5935(CHIPS)':
 C_PATH='@s9s_mb_2u_lib.s9s_mb_2u(sch_1):page585_i79@pure_quanta.isl99390frztr5935~
(chips)',
 VAR_0_ONSEMI='VAR_REPLACED|ISL99390FRZTR5935|VAR_PARTNAME|FDMF5085|VALUE|FDMF50~
85|PART_TYPE|SMLF|MATERIAL|IC|PART_NUMBER|AL005085000|STANDARD||LIFECYCLE||PART_~
NUMBER|AL005085000|JEDEC_TYPE|PQFN21_6X5XB|DESCRIPTION|IC OTHER(39P) FDMF5085(PQ~
FN)|MANUFTR|ONS|MANUF_PN|FDMF5085|RD_CMPLS_LVL|EP(V1)|CMPLS_LVL||FROM_PJ|S9S-KIM~
I|CLASS|IC|DIP_SMD||DATA|ONS_FDMF5085.pdf|EE_CHECK_LIST||FP_ECN||PSL||CREATOR||S~
TATUS||MSD|NA|ESD_CDM|NA|ESD_HBM|NA|ESD_MM|NA|PIN_LENGTH_SHORT_PIN|0 MILS|PIN_LE~
NGTH_LONG_PIN|0 MILS|CREATEDAY|20200423|VARIANT_DEVICE_TYPE|FDMF5085-FDMF5085,SM~
LF,IC,AL00',
 CDSVAR_REPCELL_ONSEMI='pure_quanta|fdmf5085';

PART_NAME
 PR1787 'Q_RES_0402LF-3.3,1%,1/16W,CHIPA':;

SECTION_NUMBER 1
 '@S9S_MB_2U_LIB.S9S_MB_2U(SCH_1):PAGE585_I154@PURE_QUANTA.Q_RES(CHIPS)':
 C_PATH='@s9s_mb_2u_lib.s9s_mb_2u(sch_1):page585_i154@pure_quanta.q_res(chips)',
 VAR_0_ONSEMI='VALUE|5.1|TOLERANCE|5%|WATTAGE|1/16W|PACK_TYPE|0402LF|MATERIAL|CH~
IP|PART_NUMBER|CS-5102JB03|STANDARD|End of Design|LIFECYCLE|Comp-Approve|PART_NU~
MBER|CS-5102JB03|JEDEC_TYPE|R0402|ALT_SYMBOLS|(R0402-0201)|VALUE|5.1|TOL|5%|WATT~
AGE|1/16W |CLASS|DISCRETE|DESCRIPTION|RES CHIP 5.1 1/16W +-5%(0402)|COMPONENT_TY~
PE|CHIP0402|LEAD_LENGTH||DFM_EXCLUSION||DAY|20100827|VARIANT_DEVICE_TYPE|Q_RES-5~
.1,5%,1/16W,0402LF,CHIP',
 CDSVAR_REPCELL_ONSEMI='pure_quanta|Q_res';

PART_NAME
 PR1786 'Q_RES_0402LF-3.3,1%,1/16W,CHIPA':;

SECTION_NUMBER 1
 '@S9S_MB_2U_LIB.S9S_MB_2U(SCH_1):PAGE585_I155@PURE_QUANTA.Q_RES(CHIPS)':
 C_PATH='@s9s_mb_2u_lib.s9s_mb_2u(sch_1):page585_i155@pure_quanta.q_res(chips)',
 VAR_0_ONSEMI='VALUE|5.1|TOLERANCE|5%|WATTAGE|1/16W|PACK_TYPE|0402LF|MATERIAL|CH~
IP|PART_NUMBER|CS-5102JB03|STANDARD|End of Design|LIFECYCLE|Comp-Approve|PART_NU~
MBER|CS-5102JB03|JEDEC_TYPE|R0402|ALT_SYMBOLS|(R0402-0201)|VALUE|5.1|TOL|5%|WATT~
AGE|1/16W |CLASS|DISCRETE|DESCRIPTION|RES CHIP 5.1 1/16W +-5%(0402)|COMPONENT_TY~
PE|CHIP0402|LEAD_LENGTH||DFM_EXCLUSION||DAY|20100827|VARIANT_DEVICE_TYPE|Q_RES-5~
.1,5%,1/16W,0402LF,CHIP',
 CDSVAR_REPCELL_ONSEMI='pure_quanta|Q_res';

PART_NAME
 PR155 'Q_RES_0402LF-0,5%,1/16W,CHIP,CA':;

SECTION_NUMBER 1
 '@S9S_MB_2U_LIB.S9S_MB_2U(SCH_1):PAGE585_I165@PURE_QUANTA.Q_RES(CHIPS)':
 C_PATH='@s9s_mb_2u_lib.s9s_mb_2u(sch_1):page585_i165@pure_quanta.q_res(chips)',
 CDSVAR_REPCELL_ONSEMI='pure_quanta|Q_res',
 VAR_0_ONSEMI='VALUE|0|TOLERANCE|5%|WATTAGE|1/16W|PACK_TYPE|0402LF|MATERIAL|EMPT~
Y|PART_NUMBER|CS00002JB38|STANDARD|End of Design|LIFECYCLE|Comp-Approve|PART_NUM~
BER|CS00002JB38|JEDEC_TYPE|R0402|ALT_SYMBOLS|(R0402-0201)|VALUE|0|TOL|5%|WATTAGE~
|1/16W|CLASS|IO|DESCRIPTION|RESISTOR CHIP 0 1/16W +-5%(0402)|COMPONENT_TYPE|CHIP~
0402|LEAD_LENGTH||DFM_EXCLUSION||DAY|20100618|VARIANT_DEVICE_TYPE|Q_RES-0,5%,1/1~
6W,0402LF,EMPTY,';

PART_NAME
 PR154 'Q_RES_0402LF-0,5%,1/16W,CHIP,CA':;

SECTION_NUMBER 1
 '@S9S_MB_2U_LIB.S9S_MB_2U(SCH_1):PAGE585_I164@PURE_QUANTA.Q_RES(CHIPS)':
 C_PATH='@s9s_mb_2u_lib.s9s_mb_2u(sch_1):page585_i164@pure_quanta.q_res(chips)',
 CDSVAR_REPCELL_ONSEMI='pure_quanta|Q_res',
 VAR_0_ONSEMI='VALUE|0|TOLERANCE|5%|WATTAGE|1/16W|PACK_TYPE|0402LF|MATERIAL|EMPT~
Y|PART_NUMBER|CS00002JB38|STANDARD|End of Design|LIFECYCLE|Comp-Approve|PART_NUM~
BER|CS00002JB38|JEDEC_TYPE|R0402|ALT_SYMBOLS|(R0402-0201)|VALUE|0|TOL|5%|WATTAGE~
|1/16W|CLASS|IO|DESCRIPTION|RESISTOR CHIP 0 1/16W +-5%(0402)|COMPONENT_TYPE|CHIP~
0402|LEAD_LENGTH||DFM_EXCLUSION||DAY|20100618|VARIANT_DEVICE_TYPE|Q_RES-0,5%,1/1~
6W,0402LF,EMPTY,';

PART_NAME
 PR153 'Q_RES_0402LF-2.2,1%,1/16W,CHIPA':;

SECTION_NUMBER 1
 '@S9S_MB_2U_LIB.S9S_MB_2U(SCH_1):PAGE585_I100@PURE_QUANTA.Q_RES(CHIPS)':
 C_PATH='@s9s_mb_2u_lib.s9s_mb_2u(sch_1):page585_i100@pure_quanta.q_res(chips)';

PART_NAME
 PR152 'Q_RES_0402LF-2.2,1%,1/16W,CHIPA':;

SECTION_NUMBER 1
 '@S9S_MB_2U_LIB.S9S_MB_2U(SCH_1):PAGE585_I107@PURE_QUANTA.Q_RES(CHIPS)':
 C_PATH='@s9s_mb_2u_lib.s9s_mb_2u(sch_1):page585_i107@pure_quanta.q_res(chips)';

PART_NAME
 PR151 'Q_RES_0402LF-8.87K,1%,1/16W,EMA':;

SECTION_NUMBER 1
 '@S9S_MB_2U_LIB.S9S_MB_2U(SCH_1):PAGE585_I166@PURE_QUANTA.Q_RES(CHIPS)':
 C_PATH='@s9s_mb_2u_lib.s9s_mb_2u(sch_1):page585_i166@pure_quanta.q_res(chips)';

PART_NAME
 PR150 'Q_RES_0402LF-8.87K,1%,1/16W,EMA':;

SECTION_NUMBER 1
 '@S9S_MB_2U_LIB.S9S_MB_2U(SCH_1):PAGE585_I167@PURE_QUANTA.Q_RES(CHIPS)':
 C_PATH='@s9s_mb_2u_lib.s9s_mb_2u(sch_1):page585_i167@pure_quanta.q_res(chips)';

PART_NAME
 PL114 'Q_INDUCTOR_SMLF-130NH/106A,INDA':;

SECTION_NUMBER 1
 '@S9S_MB_2U_LIB.S9S_MB_2U(SCH_1):PAGE585_I40@PURE_QUANTA.Q_INDUCTOR(CHIPS)':
 C_PATH='@s9s_mb_a_lib.s9s_mb_a(sch_1):page585_i40@pure_quanta.q_inductor(chips)~
';

PART_NAME
 PL15 'Q_INDUCTOR_SMLF-50NH/148A,IND,A':;

SECTION_NUMBER 1
 '@S9S_MB_2U_LIB.S9S_MB_2U(SCH_1):PAGE585_I72@PURE_QUANTA.Q_INDUCTOR(CHIPS)':
 C_PATH='@s9s_mb_a_lib.s9s_mb_a(sch_1):page585_i72@pure_quanta.q_inductor(chips)~
';

PART_NAME
 PL13 'Q_INDUCTOR_SMLF-130NH/106A,INDA':;

SECTION_NUMBER 1
 '@S9S_MB_2U_LIB.S9S_MB_2U(SCH_1):PAGE585_I128@PURE_QUANTA.Q_INDUCTOR(CHIPS)':
 C_PATH='@s9s_mb_2u_lib.s9s_mb_2u(sch_1):page585_i128@pure_quanta.q_inductor(chips~
)';

PART_NAME
 PC2336 'Q_CAPP_SMLF-470UF,2.5V,20%,POSA':;

SECTION_NUMBER 1
 '@S9S_MB_2U_LIB.S9S_MB_2U(SCH_1):PAGE585_I163@PURE_QUANTA.Q_CAPP(CHIPS)':
 C_PATH='@s9s_mb_2u_lib.s9s_mb_2u(sch_1):page585_i163@pure_quanta.q_capp(chips)';

PART_NAME
 PC1920 'Q_CAPP_SMLF-470UF,2.5V,20%,POSA':;

SECTION_NUMBER 1
 '@S9S_MB_2U_LIB.S9S_MB_2U(SCH_1):PAGE585_I153@PURE_QUANTA.Q_CAPP(CHIPS)':
 C_PATH='@s9s_mb_2u_lib.s9s_mb_2u(sch_1):page585_i153@pure_quanta.q_capp(chips)';

PART_NAME
 PC1356 'Q_CAP_0402-0.1UF,25V,10%,X7R,CA':;

SECTION_NUMBER 1
 '@S9S_MB_2U_LIB.S9S_MB_2U(SCH_1):PAGE585_I158@PURE_QUANTA.Q_CAP(CHIPS)':
 C_PATH='@s9s_mb_2u_lib.s9s_mb_2u(sch_1):page585_i158@pure_quanta.q_cap(chips)',
 VAR_0_ONSEMI='VALUE|0.1UF|VOLTAGE|25V|TOLERANCE|10%|PACK_TYPE|0402|MATERIAL|EMP~
TY|PART_NUMBER|CH4104K1B00|STANDARD||LIFECYCLE||ASS_PART||PART_NUMBER|CH4104K1B0~
0|JEDEC_TYPE|C0402|ALT_SYMBOLS|(C0402_OCTAGONXA,C0402-0201)|VALUE|NA|RATED_VOLTA~
GE|25V|TOL|10%|CLASS|IO|DESCRIPTION|CAP CHIP 0.1U 25V(+-10%,X7R,0402)|COMPONENT_~
TYPE|CHIP0402|LEAD_LENGTH||LPID||DATE|20160113|VARIANT_DEVICE_TYPE|Q_CAP-0.1UF,2~
5V,10%,0402,EMPTY',
 CDSVAR_REPCELL_ONSEMI='pure_quanta|Q_cap';

PART_NAME
 PC1355 'Q_CAP_0402-0.1UF,25V,10%,X7R,CA':;

SECTION_NUMBER 1
 '@S9S_MB_2U_LIB.S9S_MB_2U(SCH_1):PAGE585_I160@PURE_QUANTA.Q_CAP(CHIPS)':
 C_PATH='@s9s_mb_2u_lib.s9s_mb_2u(sch_1):page585_i160@pure_quanta.q_cap(chips)',
 VAR_0_ONSEMI='VALUE|0.1UF|VOLTAGE|25V|TOLERANCE|10%|PACK_TYPE|0402|MATERIAL|EMP~
TY|PART_NUMBER|CH4104K1B00|STANDARD||LIFECYCLE||ASS_PART||PART_NUMBER|CH4104K1B0~
0|JEDEC_TYPE|C0402|ALT_SYMBOLS|(C0402_OCTAGONXA,C0402-0201)|VALUE|NA|RATED_VOLTA~
GE|25V|TOL|10%|CLASS|IO|DESCRIPTION|CAP CHIP 0.1U 25V(+-10%,X7R,0402)|COMPONENT_~
TYPE|CHIP0402|LEAD_LENGTH||LPID||DATE|20160113|VARIANT_DEVICE_TYPE|Q_CAP-0.1UF,2~
5V,10%,0402,EMPTY',
 CDSVAR_REPCELL_ONSEMI='pure_quanta|Q_cap';

PART_NAME
 PC326 'Q_CAPP_SMLF-470UF,2.5V,20%,EMPA':;

SECTION_NUMBER 1
 '@S9S_MB_2U_LIB.S9S_MB_2U(SCH_1):PAGE585_I60@PURE_QUANTA.Q_CAPP(CHIPS)':
 C_PATH='@s9s_mb_2u_lib.s9s_mb_2u(sch_1):page585_i60@pure_quanta.q_capp(chips)';

PART_NAME
 PC325 'Q_CAPP_RDLF-560UF,2.5V,20%,ALUA':;

SECTION_NUMBER 1
 '@S9S_MB_2U_LIB.S9S_MB_2U(SCH_1):PAGE585_I66@PURE_QUANTA.Q_CAPP(CHIPS)':
 C_PATH='@s9s_mb_2u_lib.s9s_mb_2u(sch_1):page585_i66@pure_quanta.q_capp(chips)';

PART_NAME
 PC324 'Q_CAPP_THLF-270UF,16V,20%,OSCOA':;

SECTION_NUMBER 1
 '@S9S_MB_2U_LIB.S9S_MB_2U(SCH_1):PAGE585_I77@PURE_QUANTA.Q_CAPP(CHIPS)':
 C_PATH='@s9s_mb_2u_lib.s9s_mb_2u(sch_1):page585_i77@pure_quanta.q_capp(chips)';

PART_NAME
 PC323 'Q_CAPP_SMLF-470UF,2.5V,20%,POSA':;

SECTION_NUMBER 1
 '@S9S_MB_2U_LIB.S9S_MB_2U(SCH_1):PAGE585_I59@PURE_QUANTA.Q_CAPP(CHIPS)':
 C_PATH='@s9s_mb_2u_lib.s9s_mb_2u(sch_1):page585_i59@pure_quanta.q_capp(chips)';

PART_NAME
 PC322 'Q_CAPP_RDLF-560UF,2.5V,20%,ALUA':;

SECTION_NUMBER 1
 '@S9S_MB_2U_LIB.S9S_MB_2U(SCH_1):PAGE585_I65@PURE_QUANTA.Q_CAPP(CHIPS)':
 C_PATH='@s9s_mb_2u_lib.s9s_mb_2u(sch_1):page585_i65@pure_quanta.q_capp(chips)';

PART_NAME
 PC321 'Q_CAPP_THLF-270UF,16V,20%,OSCOA':;

SECTION_NUMBER 1
 '@S9S_MB_2U_LIB.S9S_MB_2U(SCH_1):PAGE585_I75@PURE_QUANTA.Q_CAPP(CHIPS)':
 C_PATH='@s9s_mb_2u_lib.s9s_mb_2u(sch_1):page585_i75@pure_quanta.q_capp(chips)';

PART_NAME
 PC319 'Q_CAPP_RDLF-560UF,2.5V,20%,ALUA':;

SECTION_NUMBER 1
 '@S9S_MB_2U_LIB.S9S_MB_2U(SCH_1):PAGE585_I63@PURE_QUANTA.Q_CAPP(CHIPS)':
 C_PATH='@s9s_mb_2u_lib.s9s_mb_2u(sch_1):page585_i63@pure_quanta.q_capp(chips)';

PART_NAME
 PC318 'Q_CAPP_THLF-270UF,16V,20%,OSCOA':;

SECTION_NUMBER 1
 '@S9S_MB_2U_LIB.S9S_MB_2U(SCH_1):PAGE585_I74@PURE_QUANTA.Q_CAPP(CHIPS)':
 C_PATH='@s9s_mb_2u_lib.s9s_mb_2u(sch_1):page585_i74@pure_quanta.q_capp(chips)';

PART_NAME
 PC316 'Q_CAPP_RDLF-560UF,2.5V,20%,ALUA':;

SECTION_NUMBER 1
 '@S9S_MB_2U_LIB.S9S_MB_2U(SCH_1):PAGE585_I56@PURE_QUANTA.Q_CAPP(CHIPS)':
 C_PATH='@s9s_mb_2u_lib.s9s_mb_2u(sch_1):page585_i56@pure_quanta.q_capp(chips)';

PART_NAME
 PC315 'Q_CAPP_THLF-270UF,16V,20%,OSCOA':;

SECTION_NUMBER 1
 '@S9S_MB_2U_LIB.S9S_MB_2U(SCH_1):PAGE585_I73@PURE_QUANTA.Q_CAPP(CHIPS)':
 C_PATH='@s9s_mb_2u_lib.s9s_mb_2u(sch_1):page585_i73@pure_quanta.q_capp(chips)';

PART_NAME
 PC314_P0_1 'Q_CAP_0805-22UF,4V,20%,X6S,TMPA':;

SECTION_NUMBER 1
 '@S9S_MB_2U_LIB.S9S_MB_2U(SCH_1):PAGE585_I54@PURE_QUANTA.Q_CAP(CHIPS)':
 C_PATH='@s9s_mb_2u_lib.s9s_mb_2u(sch_1):page585_i54@pure_quanta.q_cap(chips)';

PART_NAME
 PC313_P0_2 'Q_CAP_0805-22UF,4V,20%,X6S,TMPA':;

SECTION_NUMBER 1
 '@S9S_MB_2U_LIB.S9S_MB_2U(SCH_1):PAGE585_I131@PURE_QUANTA.Q_CAP(CHIPS)':
 C_PATH='@s9s_mb_2u_lib.s9s_mb_2u(sch_1):page585_i131@pure_quanta.q_cap(chips)';

PART_NAME
 PC312_P0_1 'Q_CAP_0805-22UF,4V,20%,X6S,TMPA':;

SECTION_NUMBER 1
 '@S9S_MB_2U_LIB.S9S_MB_2U(SCH_1):PAGE585_I53@PURE_QUANTA.Q_CAP(CHIPS)':
 C_PATH='@s9s_mb_2u_lib.s9s_mb_2u(sch_1):page585_i53@pure_quanta.q_cap(chips)';

PART_NAME
 PC311_P0_2 'Q_CAP_0805-22UF,4V,20%,X6S,TMPA':;

SECTION_NUMBER 1
 '@S9S_MB_2U_LIB.S9S_MB_2U(SCH_1):PAGE585_I119@PURE_QUANTA.Q_CAP(CHIPS)':
 C_PATH='@s9s_mb_2u_lib.s9s_mb_2u(sch_1):page585_i119@pure_quanta.q_cap(chips)';

PART_NAME
 PC310_P0_1 'Q_CAP_C0402-1UF,16V,10%,X6S,CHA':;

SECTION_NUMBER 1
 '@S9S_MB_2U_LIB.S9S_MB_2U(SCH_1):PAGE585_I52@PURE_QUANTA.Q_CAP(CHIPS)':
 C_PATH='@s9s_mb_2u_lib.s9s_mb_2u(sch_1):page585_i52@pure_quanta.q_cap(chips)';

PART_NAME
 PC308_P0_1 'Q_CAP_C0402-100NF,50V,10%,X7R,A':;

SECTION_NUMBER 1
 '@S9S_MB_2U_LIB.S9S_MB_2U(SCH_1):PAGE585_I32@PURE_QUANTA.Q_CAP(CHIPS)':
 C_PATH='@s9s_mb_2u_lib.s9s_mb_2u(sch_1):page585_i32@pure_quanta.q_cap(chips)';

PART_NAME
 PC307_P0_1 'Q_CAP_C0805-22UF,16V,20%,X6S,CA':;

SECTION_NUMBER 1
 '@S9S_MB_2U_LIB.S9S_MB_2U(SCH_1):PAGE585_I68@PURE_QUANTA.Q_CAP(CHIPS)':
 C_PATH='@s9s_mb_2u_lib.s9s_mb_2u(sch_1):page585_i68@pure_quanta.q_cap(chips)';

PART_NAME
 PC306_P0_2 'Q_CAP_C0805-22UF,16V,20%,X6S,CA':;

SECTION_NUMBER 1
 '@S9S_MB_2U_LIB.S9S_MB_2U(SCH_1):PAGE585_I122@PURE_QUANTA.Q_CAP(CHIPS)':
 C_PATH='@s9s_mb_2u_lib.s9s_mb_2u(sch_1):page585_i122@pure_quanta.q_cap(chips)';

PART_NAME
 PC305_P0_1 'Q_CAP_C0805-22UF,16V,20%,X6S,CA':;

SECTION_NUMBER 1
 '@S9S_MB_2U_LIB.S9S_MB_2U(SCH_1):PAGE585_I42@PURE_QUANTA.Q_CAP(CHIPS)':
 C_PATH='@s9s_mb_2u_lib.s9s_mb_2u(sch_1):page585_i42@pure_quanta.q_cap(chips)';

PART_NAME
 PC304_P0_2 'Q_CAP_C0805-22UF,16V,20%,X6S,CA':;

SECTION_NUMBER 1
 '@S9S_MB_2U_LIB.S9S_MB_2U(SCH_1):PAGE585_I123@PURE_QUANTA.Q_CAP(CHIPS)':
 C_PATH='@s9s_mb_2u_lib.s9s_mb_2u(sch_1):page585_i123@pure_quanta.q_cap(chips)';

PART_NAME
 PC303_P0_1 'Q_CAP_C0805-22UF,16V,20%,X6S,CA':;

SECTION_NUMBER 1
 '@S9S_MB_2U_LIB.S9S_MB_2U(SCH_1):PAGE585_I41@PURE_QUANTA.Q_CAP(CHIPS)':
 C_PATH='@s9s_mb_2u_lib.s9s_mb_2u(sch_1):page585_i41@pure_quanta.q_cap(chips)';

PART_NAME
 PC302_P0_2 'Q_CAP_C0805-22UF,16V,20%,X6S,CA':;

SECTION_NUMBER 1
 '@S9S_MB_2U_LIB.S9S_MB_2U(SCH_1):PAGE585_I125@PURE_QUANTA.Q_CAP(CHIPS)':
 C_PATH='@s9s_mb_2u_lib.s9s_mb_2u(sch_1):page585_i125@pure_quanta.q_cap(chips)';

PART_NAME
 PC301 'Q_CAP_C0402-100NF,50V,10%,X7R,A':;

SECTION_NUMBER 1
 '@S9S_MB_2U_LIB.S9S_MB_2U(SCH_1):PAGE585_I162@PURE_QUANTA.Q_CAP(CHIPS)':
 C_PATH='@s9s_mb_2u_lib.s9s_mb_2u(sch_1):page585_i162@pure_quanta.q_cap(chips)';

PART_NAME
 PC300 'Q_CAP_C0402-100NF,50V,10%,X7R,A':;

SECTION_NUMBER 1
 '@S9S_MB_2U_LIB.S9S_MB_2U(SCH_1):PAGE585_I161@PURE_QUANTA.Q_CAP(CHIPS)':
 C_PATH='@s9s_mb_2u_lib.s9s_mb_2u(sch_1):page585_i161@pure_quanta.q_cap(chips)';

PART_NAME
 PC299_P0_1 'Q_CAP_C0402-1UF,16V,10%,X6S,CHA':;

SECTION_NUMBER 1
 '@S9S_MB_2U_LIB.S9S_MB_2U(SCH_1):PAGE585_I39@PURE_QUANTA.Q_CAP(CHIPS)':
 C_PATH='@s9s_mb_2u_lib.s9s_mb_2u(sch_1):page585_i39@pure_quanta.q_cap(chips)';

PART_NAME
 PC298_P0_2 'Q_CAP_C0402-1UF,16V,10%,X6S,CHA':;

SECTION_NUMBER 1
 '@S9S_MB_2U_LIB.S9S_MB_2U(SCH_1):PAGE585_I126@PURE_QUANTA.Q_CAP(CHIPS)':
 C_PATH='@s9s_mb_2u_lib.s9s_mb_2u(sch_1):page585_i126@pure_quanta.q_cap(chips)';

PART_NAME
 PC297_P0_1 'Q_CAP_0402-3300PF,50V,10%,X7R,A':;

SECTION_NUMBER 1
 '@S9S_MB_2U_LIB.S9S_MB_2U(SCH_1):PAGE585_I38@PURE_QUANTA.Q_CAP(CHIPS)':
 C_PATH='@s9s_mb_2u_lib.s9s_mb_2u(sch_1):page585_i38@pure_quanta.q_cap(chips)';

PART_NAME
 PC296_P0_2 'Q_CAP_0402-3300PF,50V,10%,X7R,A':;

SECTION_NUMBER 1
 '@S9S_MB_2U_LIB.S9S_MB_2U(SCH_1):PAGE585_I127@PURE_QUANTA.Q_CAP(CHIPS)':
 C_PATH='@s9s_mb_2u_lib.s9s_mb_2u(sch_1):page585_i127@pure_quanta.q_cap(chips)';

PART_NAME
 PC295_P0_1 'Q_CAP_C0402-2.2UF,10V,10%,X6S,A':;

SECTION_NUMBER 1
 '@S9S_MB_2U_LIB.S9S_MB_2U(SCH_1):PAGE585_I103@PURE_QUANTA.Q_CAP(CHIPS)':
 C_PATH='@s9s_mb_2u_lib.s9s_mb_2u(sch_1):page585_i103@pure_quanta.q_cap(chips)';

PART_NAME
 PC294_P0_2 'Q_CAP_C0402-2.2UF,10V,10%,X6S,A':;

SECTION_NUMBER 1
 '@S9S_MB_2U_LIB.S9S_MB_2U(SCH_1):PAGE585_I110@PURE_QUANTA.Q_CAP(CHIPS)':
 C_PATH='@s9s_mb_2u_lib.s9s_mb_2u(sch_1):page585_i110@pure_quanta.q_cap(chips)';

PART_NAME
 PC293 'Q_CAP_C0402-2.2UF,10V,10%,X6S,A':;

SECTION_NUMBER 1
 '@S9S_MB_2U_LIB.S9S_MB_2U(SCH_1):PAGE585_I99@PURE_QUANTA.Q_CAP(CHIPS)':
 C_PATH='@s9s_mb_2u_lib.s9s_mb_2u(sch_1):page585_i99@pure_quanta.q_cap(chips)';

PART_NAME
 PC292 'Q_CAP_C0402-2.2UF,10V,10%,X6S,A':;

SECTION_NUMBER 1
 '@S9S_MB_2U_LIB.S9S_MB_2U(SCH_1):PAGE585_I106@PURE_QUANTA.Q_CAP(CHIPS)':
 C_PATH='@s9s_mb_2u_lib.s9s_mb_2u(sch_1):page585_i106@pure_quanta.q_cap(chips)';

PART_NAME
 PU11_P0_3 'ISL99390FRZTR5935-ISL99390FRZ-A':;

SECTION_NUMBER 1
 '@S9S_MB_2U_LIB.S9S_MB_2U(SCH_1):PAGE436_I25@PURE_QUANTA.ISL99390FRZTR5935(CHIPS)':
 C_PATH='@s9s_mb_2u_lib.s9s_mb_2u(sch_1):page436_i25@pure_quanta.isl99390frztr5935~
(chips)',
 VAR_0_ONSEMI='VAR_REPLACED|ISL99390FRZTR5935|VAR_PARTNAME|FDMF5085|VALUE|FDMF50~
85|PART_TYPE|SMLF|MATERIAL|IC|PART_NUMBER|AL005085000|STANDARD||LIFECYCLE||PART_~
NUMBER|AL005085000|JEDEC_TYPE|PQFN21_6X5XB|DESCRIPTION|IC OTHER(39P) FDMF5085(PQ~
FN)|MANUFTR|ONS|MANUF_PN|FDMF5085|RD_CMPLS_LVL|EP(V1)|CMPLS_LVL||FROM_PJ|S9S-KIM~
I|CLASS|IC|DIP_SMD||DATA|ONS_FDMF5085.pdf|EE_CHECK_LIST||FP_ECN||PSL||CREATOR||S~
TATUS||MSD|NA|ESD_CDM|NA|ESD_HBM|NA|ESD_MM|NA|PIN_LENGTH_SHORT_PIN|0 MILS|PIN_LE~
NGTH_LONG_PIN|0 MILS|CREATEDAY|20200423|VARIANT_DEVICE_TYPE|FDMF5085-FDMF5085,SM~
LF,IC,AL00',
 CDSVAR_REPCELL_ONSEMI='pure_quanta|fdmf5085';

PART_NAME
 PU10_P0_4 'ISL99390FRZTR5935-ISL99390FRZ-A':;

SECTION_NUMBER 1
 '@S9S_MB_2U_LIB.S9S_MB_2U(SCH_1):PAGE436_I21@PURE_QUANTA.ISL99390FRZTR5935(CHIPS)':
 C_PATH='@s9s_mb_2u_lib.s9s_mb_2u(sch_1):page436_i21@pure_quanta.isl99390frztr5935~
(chips)',
 VAR_0_ONSEMI='VAR_REPLACED|ISL99390FRZTR5935|VAR_PARTNAME|FDMF5085|VALUE|FDMF50~
85|PART_TYPE|SMLF|MATERIAL|IC|PART_NUMBER|AL005085000|STANDARD||LIFECYCLE||PART_~
NUMBER|AL005085000|JEDEC_TYPE|PQFN21_6X5XB|DESCRIPTION|IC OTHER(39P) FDMF5085(PQ~
FN)|MANUFTR|ONS|MANUF_PN|FDMF5085|RD_CMPLS_LVL|EP(V1)|CMPLS_LVL||FROM_PJ|S9S-KIM~
I|CLASS|IC|DIP_SMD||DATA|ONS_FDMF5085.pdf|EE_CHECK_LIST||FP_ECN||PSL||CREATOR||S~
TATUS||MSD|NA|ESD_CDM|NA|ESD_HBM|NA|ESD_MM|NA|PIN_LENGTH_SHORT_PIN|0 MILS|PIN_LE~
NGTH_LONG_PIN|0 MILS|CREATEDAY|20200423|VARIANT_DEVICE_TYPE|FDMF5085-FDMF5085,SM~
LF,IC,AL00',
 CDSVAR_REPCELL_ONSEMI='pure_quanta|fdmf5085';

PART_NAME
 PR1769 'Q_RES_0402LF-3.3,1%,1/16W,CHIPA':;

SECTION_NUMBER 1
 '@S9S_MB_2U_LIB.S9S_MB_2U(SCH_1):PAGE436_I84@PURE_QUANTA.Q_RES(CHIPS)':
 C_PATH='@s9s_mb_2u_lib.s9s_mb_2u(sch_1):page436_i84@pure_quanta.q_res(chips)',
 VAR_0_ONSEMI='VALUE|5.1|TOLERANCE|5%|WATTAGE|1/16W|PACK_TYPE|0402LF|MATERIAL|CH~
IP|PART_NUMBER|CS-5102JB03|STANDARD|End of Design|LIFECYCLE|Comp-Approve|PART_NU~
MBER|CS-5102JB03|JEDEC_TYPE|R0402|ALT_SYMBOLS|(R0402-0201)|VALUE|5.1|TOL|5%|WATT~
AGE|1/16W |CLASS|DISCRETE|DESCRIPTION|RES CHIP 5.1 1/16W +-5%(0402)|COMPONENT_TY~
PE|CHIP0402|LEAD_LENGTH||DFM_EXCLUSION||DAY|20100827|VARIANT_DEVICE_TYPE|Q_RES-5~
.1,5%,1/16W,0402LF,CHIP',
 CDSVAR_REPCELL_ONSEMI='pure_quanta|Q_res';

PART_NAME
 PR1768 'Q_RES_0402LF-3.3,1%,1/16W,CHIPA':;

SECTION_NUMBER 1
 '@S9S_MB_2U_LIB.S9S_MB_2U(SCH_1):PAGE436_I86@PURE_QUANTA.Q_RES(CHIPS)':
 C_PATH='@s9s_mb_2u_lib.s9s_mb_2u(sch_1):page436_i86@pure_quanta.q_res(chips)',
 VAR_0_ONSEMI='VALUE|5.1|TOLERANCE|5%|WATTAGE|1/16W|PACK_TYPE|0402LF|MATERIAL|CH~
IP|PART_NUMBER|CS-5102JB03|STANDARD|End of Design|LIFECYCLE|Comp-Approve|PART_NU~
MBER|CS-5102JB03|JEDEC_TYPE|R0402|ALT_SYMBOLS|(R0402-0201)|VALUE|5.1|TOL|5%|WATT~
AGE|1/16W |CLASS|DISCRETE|DESCRIPTION|RES CHIP 5.1 1/16W +-5%(0402)|COMPONENT_TY~
PE|CHIP0402|LEAD_LENGTH||DFM_EXCLUSION||DAY|20100827|VARIANT_DEVICE_TYPE|Q_RES-5~
.1,5%,1/16W,0402LF,CHIP',
 CDSVAR_REPCELL_ONSEMI='pure_quanta|Q_res';

PART_NAME
 PR149 'Q_RES_0402LF-0,5%,1/16W,CHIP,CA':;

SECTION_NUMBER 1
 '@S9S_MB_2U_LIB.S9S_MB_2U(SCH_1):PAGE436_I96@PURE_QUANTA.Q_RES(CHIPS)':
 C_PATH='@s9s_mb_2u_lib.s9s_mb_2u(sch_1):page436_i96@pure_quanta.q_res(chips)',
 VAR_0_ONSEMI='VALUE|0|TOLERANCE|5%|WATTAGE|1/16W|PACK_TYPE|0402LF|MATERIAL|EMPT~
Y|PART_NUMBER|CS00002JB38|STANDARD|End of Design|LIFECYCLE|Comp-Approve|PART_NUM~
BER|CS00002JB38|JEDEC_TYPE|R0402|ALT_SYMBOLS|(R0402-0201)|VALUE|0|TOL|5%|WATTAGE~
|1/16W|CLASS|IO|DESCRIPTION|RESISTOR CHIP 0 1/16W +-5%(0402)|COMPONENT_TYPE|CHIP~
0402|LEAD_LENGTH||DFM_EXCLUSION||DAY|20100618|VARIANT_DEVICE_TYPE|Q_RES-0,5%,1/1~
6W,0402LF,EMPTY,',
 CDSVAR_REPCELL_ONSEMI='pure_quanta|Q_res';

PART_NAME
 PR148 'Q_RES_0402LF-0,5%,1/16W,CHIP,CA':;

SECTION_NUMBER 1
 '@S9S_MB_2U_LIB.S9S_MB_2U(SCH_1):PAGE436_I94@PURE_QUANTA.Q_RES(CHIPS)':
 C_PATH='@s9s_mb_2u_lib.s9s_mb_2u(sch_1):page436_i94@pure_quanta.q_res(chips)',
 VAR_0_ONSEMI='VALUE|0|TOLERANCE|5%|WATTAGE|1/16W|PACK_TYPE|0402LF|MATERIAL|EMPT~
Y|PART_NUMBER|CS00002JB38|STANDARD|End of Design|LIFECYCLE|Comp-Approve|PART_NUM~
BER|CS00002JB38|JEDEC_TYPE|R0402|ALT_SYMBOLS|(R0402-0201)|VALUE|0|TOL|5%|WATTAGE~
|1/16W|CLASS|IO|DESCRIPTION|RESISTOR CHIP 0 1/16W +-5%(0402)|COMPONENT_TYPE|CHIP~
0402|LEAD_LENGTH||DFM_EXCLUSION||DAY|20100618|VARIANT_DEVICE_TYPE|Q_RES-0,5%,1/1~
6W,0402LF,EMPTY,',
 CDSVAR_REPCELL_ONSEMI='pure_quanta|Q_res';

PART_NAME
 PR147 'Q_RES_0402LF-2.2,1%,1/16W,CHIPA':;

SECTION_NUMBER 1
 '@S9S_MB_2U_LIB.S9S_MB_2U(SCH_1):PAGE436_I19@PURE_QUANTA.Q_RES(CHIPS)':
 C_PATH='@s9s_mb_2u_lib.s9s_mb_2u(sch_1):page436_i19@pure_quanta.q_res(chips)';

PART_NAME
 PR146 'Q_RES_0402LF-2.2,1%,1/16W,CHIPA':;

SECTION_NUMBER 1
 '@S9S_MB_2U_LIB.S9S_MB_2U(SCH_1):PAGE436_I99@PURE_QUANTA.Q_RES(CHIPS)':
 C_PATH='@s9s_mb_2u_lib.s9s_mb_2u(sch_1):page436_i99@pure_quanta.q_res(chips)';

PART_NAME
 PR145 'Q_RES_0402LF-8.87K,1%,1/16W,EMA':;

SECTION_NUMBER 1
 '@S9S_MB_2U_LIB.S9S_MB_2U(SCH_1):PAGE436_I97@PURE_QUANTA.Q_RES(CHIPS)':
 C_PATH='@s9s_mb_2u_lib.s9s_mb_2u(sch_1):page436_i97@pure_quanta.q_res(chips)';

PART_NAME
 PR144 'Q_RES_0402LF-8.87K,1%,1/16W,EMA':;

SECTION_NUMBER 1
 '@S9S_MB_2U_LIB.S9S_MB_2U(SCH_1):PAGE436_I98@PURE_QUANTA.Q_RES(CHIPS)':
 C_PATH='@s9s_mb_2u_lib.s9s_mb_2u(sch_1):page436_i98@pure_quanta.q_res(chips)';

PART_NAME
 PL112 'Q_INDUCTOR_SMLF-130NH/106A,INDA':;

SECTION_NUMBER 1
 '@S9S_MB_2U_LIB.S9S_MB_2U(SCH_1):PAGE436_I42@PURE_QUANTA.Q_INDUCTOR(CHIPS)':
 C_PATH='@s9s_mb_a_lib.s9s_mb_a(sch_1):page436_i42@pure_quanta.q_inductor(chips)~
';

PART_NAME
 PL11 'Q_INDUCTOR_SMLF-130NH/106A,INDA':;

SECTION_NUMBER 1
 '@S9S_MB_2U_LIB.S9S_MB_2U(SCH_1):PAGE436_I30@PURE_QUANTA.Q_INDUCTOR(CHIPS)':
 C_PATH='@s9s_mb_a_lib.s9s_mb_a(sch_1):page436_i30@pure_quanta.q_inductor(chips)~
';

PART_NAME
 PC1341 'Q_CAP_0402-0.1UF,25V,10%,X7R,CA':;

SECTION_NUMBER 1
 '@S9S_MB_2U_LIB.S9S_MB_2U(SCH_1):PAGE436_I89@PURE_QUANTA.Q_CAP(CHIPS)':
 C_PATH='@s9s_mb_2u_lib.s9s_mb_2u(sch_1):page436_i89@pure_quanta.q_cap(chips)',
 VAR_0_ONSEMI='VALUE|0.1UF|VOLTAGE|25V|TOLERANCE|10%|PACK_TYPE|0402|MATERIAL|EMP~
TY|PART_NUMBER|CH4104K1B00|STANDARD||LIFECYCLE||ASS_PART||PART_NUMBER|CH4104K1B0~
0|JEDEC_TYPE|C0402|ALT_SYMBOLS|(C0402_OCTAGONXA,C0402-0201)|VALUE|NA|RATED_VOLTA~
GE|25V|TOL|10%|CLASS|IO|DESCRIPTION|CAP CHIP 0.1U 25V(+-10%,X7R,0402)|COMPONENT_~
TYPE|CHIP0402|LEAD_LENGTH||LPID||DATE|20160113|VARIANT_DEVICE_TYPE|Q_CAP-0.1UF,2~
5V,10%,0402,EMPTY',
 CDSVAR_REPCELL_ONSEMI='pure_quanta|Q_cap';

PART_NAME
 PC1340 'Q_CAP_0402-0.1UF,25V,10%,X7R,CA':;

SECTION_NUMBER 1
 '@S9S_MB_2U_LIB.S9S_MB_2U(SCH_1):PAGE436_I91@PURE_QUANTA.Q_CAP(CHIPS)':
 C_PATH='@s9s_mb_2u_lib.s9s_mb_2u(sch_1):page436_i91@pure_quanta.q_cap(chips)',
 VAR_0_ONSEMI='VALUE|0.1UF|VOLTAGE|25V|TOLERANCE|10%|PACK_TYPE|0402|MATERIAL|EMP~
TY|PART_NUMBER|CH4104K1B00|STANDARD||LIFECYCLE||ASS_PART||PART_NUMBER|CH4104K1B0~
0|JEDEC_TYPE|C0402|ALT_SYMBOLS|(C0402_OCTAGONXA,C0402-0201)|VALUE|NA|RATED_VOLTA~
GE|25V|TOL|10%|CLASS|IO|DESCRIPTION|CAP CHIP 0.1U 25V(+-10%,X7R,0402)|COMPONENT_~
TYPE|CHIP0402|LEAD_LENGTH||LPID||DATE|20160113|VARIANT_DEVICE_TYPE|Q_CAP-0.1UF,2~
5V,10%,0402,EMPTY',
 CDSVAR_REPCELL_ONSEMI='pure_quanta|Q_cap';

PART_NAME
 PC291_P0_3 'Q_CAP_0805-22UF,4V,20%,X6S,TMPA':;

SECTION_NUMBER 1
 '@S9S_MB_2U_LIB.S9S_MB_2U(SCH_1):PAGE436_I58@PURE_QUANTA.Q_CAP(CHIPS)':
 C_PATH='@s9s_mb_2u_lib.s9s_mb_2u(sch_1):page436_i58@pure_quanta.q_cap(chips)';

PART_NAME
 PC290_P0_4 'Q_CAP_0805-22UF,4V,20%,X6S,TMPA':;

SECTION_NUMBER 1
 '@S9S_MB_2U_LIB.S9S_MB_2U(SCH_1):PAGE436_I52@PURE_QUANTA.Q_CAP(CHIPS)':
 C_PATH='@s9s_mb_2u_lib.s9s_mb_2u(sch_1):page436_i52@pure_quanta.q_cap(chips)';

PART_NAME
 PC289_P0_3 'Q_CAP_0805-22UF,4V,20%,X6S,TMPA':;

SECTION_NUMBER 1
 '@S9S_MB_2U_LIB.S9S_MB_2U(SCH_1):PAGE436_I57@PURE_QUANTA.Q_CAP(CHIPS)':
 C_PATH='@s9s_mb_2u_lib.s9s_mb_2u(sch_1):page436_i57@pure_quanta.q_cap(chips)';

PART_NAME
 PC288_P0_4 'Q_CAP_0805-22UF,4V,20%,X6S,TMPA':;

SECTION_NUMBER 1
 '@S9S_MB_2U_LIB.S9S_MB_2U(SCH_1):PAGE436_I51@PURE_QUANTA.Q_CAP(CHIPS)':
 C_PATH='@s9s_mb_2u_lib.s9s_mb_2u(sch_1):page436_i51@pure_quanta.q_cap(chips)';

PART_NAME
 PC285_P0_3 'Q_CAP_C0805-22UF,16V,20%,X6S,CA':;

SECTION_NUMBER 1
 '@S9S_MB_2U_LIB.S9S_MB_2U(SCH_1):PAGE436_I48@PURE_QUANTA.Q_CAP(CHIPS)':
 C_PATH='@s9s_mb_2u_lib.s9s_mb_2u(sch_1):page436_i48@pure_quanta.q_cap(chips)';

PART_NAME
 PC284_P0_4 'Q_CAP_C0805-22UF,16V,20%,X6S,CA':;

SECTION_NUMBER 1
 '@S9S_MB_2U_LIB.S9S_MB_2U(SCH_1):PAGE436_I35@PURE_QUANTA.Q_CAP(CHIPS)':
 C_PATH='@s9s_mb_2u_lib.s9s_mb_2u(sch_1):page436_i35@pure_quanta.q_cap(chips)';

PART_NAME
 PC283_P0_3 'Q_CAP_C0805-22UF,16V,20%,X6S,CA':;

SECTION_NUMBER 1
 '@S9S_MB_2U_LIB.S9S_MB_2U(SCH_1):PAGE436_I47@PURE_QUANTA.Q_CAP(CHIPS)':
 C_PATH='@s9s_mb_2u_lib.s9s_mb_2u(sch_1):page436_i47@pure_quanta.q_cap(chips)';

PART_NAME
 PC282_P0_4 'Q_CAP_C0805-22UF,16V,20%,X6S,CA':;

SECTION_NUMBER 1
 '@S9S_MB_2U_LIB.S9S_MB_2U(SCH_1):PAGE436_I34@PURE_QUANTA.Q_CAP(CHIPS)':
 C_PATH='@s9s_mb_2u_lib.s9s_mb_2u(sch_1):page436_i34@pure_quanta.q_cap(chips)';

PART_NAME
 PC281_P0_3 'Q_CAP_C0805-22UF,16V,20%,X6S,CA':;

SECTION_NUMBER 1
 '@S9S_MB_2U_LIB.S9S_MB_2U(SCH_1):PAGE436_I45@PURE_QUANTA.Q_CAP(CHIPS)':
 C_PATH='@s9s_mb_2u_lib.s9s_mb_2u(sch_1):page436_i45@pure_quanta.q_cap(chips)';

PART_NAME
 PC280_P0_4 'Q_CAP_C0805-22UF,16V,20%,X6S,CA':;

SECTION_NUMBER 1
 '@S9S_MB_2U_LIB.S9S_MB_2U(SCH_1):PAGE436_I33@PURE_QUANTA.Q_CAP(CHIPS)':
 C_PATH='@s9s_mb_2u_lib.s9s_mb_2u(sch_1):page436_i33@pure_quanta.q_cap(chips)';

PART_NAME
 PC279 'Q_CAP_C0402-100NF,50V,10%,X7R,A':;

SECTION_NUMBER 1
 '@S9S_MB_2U_LIB.S9S_MB_2U(SCH_1):PAGE436_I92@PURE_QUANTA.Q_CAP(CHIPS)':
 C_PATH='@s9s_mb_2u_lib.s9s_mb_2u(sch_1):page436_i92@pure_quanta.q_cap(chips)';

PART_NAME
 PC278 'Q_CAP_C0402-100NF,50V,10%,X7R,A':;

SECTION_NUMBER 1
 '@S9S_MB_2U_LIB.S9S_MB_2U(SCH_1):PAGE436_I93@PURE_QUANTA.Q_CAP(CHIPS)':
 C_PATH='@s9s_mb_2u_lib.s9s_mb_2u(sch_1):page436_i93@pure_quanta.q_cap(chips)';

PART_NAME
 PC277_P0_3 'Q_CAP_C0402-1UF,16V,10%,X6S,CHA':;

SECTION_NUMBER 1
 '@S9S_MB_2U_LIB.S9S_MB_2U(SCH_1):PAGE436_I44@PURE_QUANTA.Q_CAP(CHIPS)':
 C_PATH='@s9s_mb_2u_lib.s9s_mb_2u(sch_1):page436_i44@pure_quanta.q_cap(chips)';

PART_NAME
 PC276_P0_4 'Q_CAP_C0402-1UF,16V,10%,X6S,CHA':;

SECTION_NUMBER 1
 '@S9S_MB_2U_LIB.S9S_MB_2U(SCH_1):PAGE436_I32@PURE_QUANTA.Q_CAP(CHIPS)':
 C_PATH='@s9s_mb_2u_lib.s9s_mb_2u(sch_1):page436_i32@pure_quanta.q_cap(chips)';

PART_NAME
 PC275_P0_3 'Q_CAP_0402-3300PF,50V,10%,X7R,A':;

SECTION_NUMBER 1
 '@S9S_MB_2U_LIB.S9S_MB_2U(SCH_1):PAGE436_I43@PURE_QUANTA.Q_CAP(CHIPS)':
 C_PATH='@s9s_mb_2u_lib.s9s_mb_2u(sch_1):page436_i43@pure_quanta.q_cap(chips)';

PART_NAME
 PC274_P0_4 'Q_CAP_0402-3300PF,50V,10%,X7R,A':;

SECTION_NUMBER 1
 '@S9S_MB_2U_LIB.S9S_MB_2U(SCH_1):PAGE436_I27@PURE_QUANTA.Q_CAP(CHIPS)':
 C_PATH='@s9s_mb_2u_lib.s9s_mb_2u(sch_1):page436_i27@pure_quanta.q_cap(chips)';

PART_NAME
 PC273_P0_3 'Q_CAP_C0402-2.2UF,10V,10%,X6S,A':;

SECTION_NUMBER 1
 '@S9S_MB_2U_LIB.S9S_MB_2U(SCH_1):PAGE436_I40@PURE_QUANTA.Q_CAP(CHIPS)':
 C_PATH='@s9s_mb_2u_lib.s9s_mb_2u(sch_1):page436_i40@pure_quanta.q_cap(chips)';

PART_NAME
 PC272_P0_4 'Q_CAP_C0402-2.2UF,10V,10%,X6S,A':;

SECTION_NUMBER 1
 '@S9S_MB_2U_LIB.S9S_MB_2U(SCH_1):PAGE436_I24@PURE_QUANTA.Q_CAP(CHIPS)':
 C_PATH='@s9s_mb_2u_lib.s9s_mb_2u(sch_1):page436_i24@pure_quanta.q_cap(chips)';

PART_NAME
 PC271 'Q_CAP_C0402-2.2UF,10V,10%,X6S,A':;

SECTION_NUMBER 1
 '@S9S_MB_2U_LIB.S9S_MB_2U(SCH_1):PAGE436_I18@PURE_QUANTA.Q_CAP(CHIPS)':
 C_PATH='@s9s_mb_2u_lib.s9s_mb_2u(sch_1):page436_i18@pure_quanta.q_cap(chips)';

PART_NAME
 PC270 'Q_CAP_C0402-2.2UF,10V,10%,X6S,A':;

SECTION_NUMBER 1
 '@S9S_MB_2U_LIB.S9S_MB_2U(SCH_1):PAGE436_I8@PURE_QUANTA.Q_CAP(CHIPS)':
 C_PATH='@s9s_mb_2u_lib.s9s_mb_2u(sch_1):page436_i8@pure_quanta.q_cap(chips)';

PART_NAME
 PU9_P0_5 'ISL99390FRZTR5935-ISL99390FRZ-A':;

SECTION_NUMBER 1
 '@S9S_MB_2U_LIB.S9S_MB_2U(SCH_1):PAGE437_I27@PURE_QUANTA.ISL99390FRZTR5935(CHIPS)':
 C_PATH='@s9s_mb_2u_lib.s9s_mb_2u(sch_1):page437_i27@pure_quanta.isl99390frztr5935~
(chips)',
 VAR_0_ONSEMI='VAR_REPLACED|ISL99390FRZTR5935|VAR_PARTNAME|FDMF5085|VALUE|FDMF50~
85|PART_TYPE|SMLF|MATERIAL|IC|PART_NUMBER|AL005085000|STANDARD||LIFECYCLE||PART_~
NUMBER|AL005085000|JEDEC_TYPE|PQFN21_6X5XB|DESCRIPTION|IC OTHER(39P) FDMF5085(PQ~
FN)|MANUFTR|ONS|MANUF_PN|FDMF5085|RD_CMPLS_LVL|EP(V1)|CMPLS_LVL||FROM_PJ|S9S-KIM~
I|CLASS|IC|DIP_SMD||DATA|ONS_FDMF5085.pdf|EE_CHECK_LIST||FP_ECN||PSL||CREATOR||S~
TATUS||MSD|NA|ESD_CDM|NA|ESD_HBM|NA|ESD_MM|NA|PIN_LENGTH_SHORT_PIN|0 MILS|PIN_LE~
NGTH_LONG_PIN|0 MILS|CREATEDAY|20200423|VARIANT_DEVICE_TYPE|FDMF5085-FDMF5085,SM~
LF,IC,AL00',
 CDSVAR_REPCELL_ONSEMI='pure_quanta|fdmf5085';

PART_NAME
 PU8_P0_6 'ISL99390FRZTR5935-ISL99390FRZ-A':;

SECTION_NUMBER 1
 '@S9S_MB_2U_LIB.S9S_MB_2U(SCH_1):PAGE437_I8@PURE_QUANTA.ISL99390FRZTR5935(CHIPS)':
 C_PATH='@s9s_mb_2u_lib.s9s_mb_2u(sch_1):page437_i8@pure_quanta.isl99390frztr5935(~
chips)',
 VAR_0_ONSEMI='VAR_REPLACED|ISL99390FRZTR5935|VAR_PARTNAME|FDMF5085|VALUE|FDMF50~
85|PART_TYPE|SMLF|MATERIAL|IC|PART_NUMBER|AL005085000|STANDARD||LIFECYCLE||PART_~
NUMBER|AL005085000|JEDEC_TYPE|PQFN21_6X5XB|DESCRIPTION|IC OTHER(39P) FDMF5085(PQ~
FN)|MANUFTR|ONS|MANUF_PN|FDMF5085|RD_CMPLS_LVL|EP(V1)|CMPLS_LVL||FROM_PJ|S9S-KIM~
I|CLASS|IC|DIP_SMD||DATA|ONS_FDMF5085.pdf|EE_CHECK_LIST||FP_ECN||PSL||CREATOR||S~
TATUS||MSD|NA|ESD_CDM|NA|ESD_HBM|NA|ESD_MM|NA|PIN_LENGTH_SHORT_PIN|0 MILS|PIN_LE~
NGTH_LONG_PIN|0 MILS|CREATEDAY|20200423|VARIANT_DEVICE_TYPE|FDMF5085-FDMF5085,SM~
LF,IC,AL00',
 CDSVAR_REPCELL_ONSEMI='pure_quanta|fdmf5085';

PART_NAME
 PR1771 'Q_RES_0402LF-3.3,1%,1/16W,CHIPA':;

SECTION_NUMBER 1
 '@S9S_MB_2U_LIB.S9S_MB_2U(SCH_1):PAGE437_I71@PURE_QUANTA.Q_RES(CHIPS)':
 C_PATH='@s9s_mb_2u_lib.s9s_mb_2u(sch_1):page437_i71@pure_quanta.q_res(chips)',
 VAR_0_ONSEMI='VALUE|5.1|TOLERANCE|5%|WATTAGE|1/16W|PACK_TYPE|0402LF|MATERIAL|CH~
IP|PART_NUMBER|CS-5102JB03|STANDARD|End of Design|LIFECYCLE|Comp-Approve|PART_NU~
MBER|CS-5102JB03|JEDEC_TYPE|R0402|ALT_SYMBOLS|(R0402-0201)|VALUE|5.1|TOL|5%|WATT~
AGE|1/16W |CLASS|DISCRETE|DESCRIPTION|RES CHIP 5.1 1/16W +-5%(0402)|COMPONENT_TY~
PE|CHIP0402|LEAD_LENGTH||DFM_EXCLUSION||DAY|20100827|VARIANT_DEVICE_TYPE|Q_RES-5~
.1,5%,1/16W,0402LF,CHIP',
 CDSVAR_REPCELL_ONSEMI='pure_quanta|Q_res';

PART_NAME
 PR1770 'Q_RES_0402LF-3.3,1%,1/16W,CHIPA':;

SECTION_NUMBER 1
 '@S9S_MB_2U_LIB.S9S_MB_2U(SCH_1):PAGE437_I73@PURE_QUANTA.Q_RES(CHIPS)':
 C_PATH='@s9s_mb_2u_lib.s9s_mb_2u(sch_1):page437_i73@pure_quanta.q_res(chips)',
 VAR_0_ONSEMI='VALUE|5.1|TOLERANCE|5%|WATTAGE|1/16W|PACK_TYPE|0402LF|MATERIAL|CH~
IP|PART_NUMBER|CS-5102JB03|STANDARD|End of Design|LIFECYCLE|Comp-Approve|PART_NU~
MBER|CS-5102JB03|JEDEC_TYPE|R0402|ALT_SYMBOLS|(R0402-0201)|VALUE|5.1|TOL|5%|WATT~
AGE|1/16W |CLASS|DISCRETE|DESCRIPTION|RES CHIP 5.1 1/16W +-5%(0402)|COMPONENT_TY~
PE|CHIP0402|LEAD_LENGTH||DFM_EXCLUSION||DAY|20100827|VARIANT_DEVICE_TYPE|Q_RES-5~
.1,5%,1/16W,0402LF,CHIP';

PART_NAME
 PR143 'Q_RES_0402LF-0,5%,1/16W,CHIP,CA':;

SECTION_NUMBER 1
 '@S9S_MB_2U_LIB.S9S_MB_2U(SCH_1):PAGE437_I82@PURE_QUANTA.Q_RES(CHIPS)':
 C_PATH='@s9s_mb_2u_lib.s9s_mb_2u(sch_1):page437_i82@pure_quanta.q_res(chips)',
 VAR_0_ONSEMI='VALUE|0|TOLERANCE|5%|WATTAGE|1/16W|PACK_TYPE|0402LF|MATERIAL|EMPT~
Y|PART_NUMBER|CS00002JB38|STANDARD|End of Design|LIFECYCLE|Comp-Approve|PART_NUM~
BER|CS00002JB38|JEDEC_TYPE|R0402|ALT_SYMBOLS|(R0402-0201)|VALUE|0|TOL|5%|WATTAGE~
|1/16W|CLASS|IO|DESCRIPTION|RESISTOR CHIP 0 1/16W +-5%(0402)|COMPONENT_TYPE|CHIP~
0402|LEAD_LENGTH||DFM_EXCLUSION||DAY|20100618|VARIANT_DEVICE_TYPE|Q_RES-0,5%,1/1~
6W,0402LF,EMPTY,',
 CDSVAR_REPCELL_ONSEMI='pure_quanta|Q_res';

PART_NAME
 PR142 'Q_RES_0402LF-0,5%,1/16W,CHIP,CA':;

SECTION_NUMBER 1
 '@S9S_MB_2U_LIB.S9S_MB_2U(SCH_1):PAGE437_I81@PURE_QUANTA.Q_RES(CHIPS)':
 C_PATH='@s9s_mb_2u_lib.s9s_mb_2u(sch_1):page437_i81@pure_quanta.q_res(chips)',
 VAR_0_ONSEMI='VALUE|0|TOLERANCE|5%|WATTAGE|1/16W|PACK_TYPE|0402LF|MATERIAL|EMPT~
Y|PART_NUMBER|CS00002JB38|STANDARD|End of Design|LIFECYCLE|Comp-Approve|PART_NUM~
BER|CS00002JB38|JEDEC_TYPE|R0402|ALT_SYMBOLS|(R0402-0201)|VALUE|0|TOL|5%|WATTAGE~
|1/16W|CLASS|IO|DESCRIPTION|RESISTOR CHIP 0 1/16W +-5%(0402)|COMPONENT_TYPE|CHIP~
0402|LEAD_LENGTH||DFM_EXCLUSION||DAY|20100618|VARIANT_DEVICE_TYPE|Q_RES-0,5%,1/1~
6W,0402LF,EMPTY,',
 CDSVAR_REPCELL_ONSEMI='pure_quanta|Q_res';

PART_NAME
 PR141 'Q_RES_0402LF-2.2,1%,1/16W,CHIPA':;

SECTION_NUMBER 1
 '@S9S_MB_2U_LIB.S9S_MB_2U(SCH_1):PAGE437_I32@PURE_QUANTA.Q_RES(CHIPS)':
 C_PATH='@s9s_mb_2u_lib.s9s_mb_2u(sch_1):page437_i32@pure_quanta.q_res(chips)';

PART_NAME
 PR140 'Q_RES_0402LF-2.2,1%,1/16W,CHIPA':;

SECTION_NUMBER 1
 '@S9S_MB_2U_LIB.S9S_MB_2U(SCH_1):PAGE437_I19@PURE_QUANTA.Q_RES(CHIPS)':
 C_PATH='@s9s_mb_2u_lib.s9s_mb_2u(sch_1):page437_i19@pure_quanta.q_res(chips)';

PART_NAME
 PR139 'Q_RES_0402LF-8.87K,1%,1/16W,EMA':;

SECTION_NUMBER 1
 '@S9S_MB_2U_LIB.S9S_MB_2U(SCH_1):PAGE437_I84@PURE_QUANTA.Q_RES(CHIPS)':
 C_PATH='@s9s_mb_2u_lib.s9s_mb_2u(sch_1):page437_i84@pure_quanta.q_res(chips)';

PART_NAME
 PR138 'Q_RES_0402LF-8.87K,1%,1/16W,EMA':;

SECTION_NUMBER 1
 '@S9S_MB_2U_LIB.S9S_MB_2U(SCH_1):PAGE437_I83@PURE_QUANTA.Q_RES(CHIPS)':
 C_PATH='@s9s_mb_2u_lib.s9s_mb_2u(sch_1):page437_i83@pure_quanta.q_res(chips)';

PART_NAME
 PL10 'Q_INDUCTOR_SMLF-130NH/106A,INDA':;

SECTION_NUMBER 1
 '@S9S_MB_2U_LIB.S9S_MB_2U(SCH_1):PAGE437_I40@PURE_QUANTA.Q_INDUCTOR(CHIPS)':
 C_PATH='@s9s_mb_a_lib.s9s_mb_a(sch_1):page437_i40@pure_quanta.q_inductor(chips)~
';

PART_NAME
 PL9 'Q_INDUCTOR_SMLF-130NH/106A,INDA':;

SECTION_NUMBER 1
 '@S9S_MB_2U_LIB.S9S_MB_2U(SCH_1):PAGE437_I12@PURE_QUANTA.Q_INDUCTOR(CHIPS)':
 C_PATH='@s9s_mb_a_lib.s9s_mb_a(sch_1):page437_i12@pure_quanta.q_inductor(chips)~
';

PART_NAME
 PC1343 'Q_CAP_0402-0.1UF,25V,10%,X7R,CA':;

SECTION_NUMBER 1
 '@S9S_MB_2U_LIB.S9S_MB_2U(SCH_1):PAGE437_I76@PURE_QUANTA.Q_CAP(CHIPS)':
 C_PATH='@s9s_mb_2u_lib.s9s_mb_2u(sch_1):page437_i76@pure_quanta.q_cap(chips)',
 VAR_0_ONSEMI='VALUE|0.1UF|VOLTAGE|25V|TOLERANCE|10%|PACK_TYPE|0402|MATERIAL|EMP~
TY|PART_NUMBER|CH4104K1B00|STANDARD||LIFECYCLE||ASS_PART||PART_NUMBER|CH4104K1B0~
0|JEDEC_TYPE|C0402|ALT_SYMBOLS|(C0402_OCTAGONXA,C0402-0201)|VALUE|NA|RATED_VOLTA~
GE|25V|TOL|10%|CLASS|IO|DESCRIPTION|CAP CHIP 0.1U 25V(+-10%,X7R,0402)|COMPONENT_~
TYPE|CHIP0402|LEAD_LENGTH||LPID||DATE|20160113|VARIANT_DEVICE_TYPE|Q_CAP-0.1UF,2~
5V,10%,0402,EMPTY',
 CDSVAR_REPCELL_ONSEMI='pure_quanta|Q_cap';

PART_NAME
 PC1342 'Q_CAP_0402-0.1UF,25V,10%,X7R,CA':;

SECTION_NUMBER 1
 '@S9S_MB_2U_LIB.S9S_MB_2U(SCH_1):PAGE437_I78@PURE_QUANTA.Q_CAP(CHIPS)':
 C_PATH='@s9s_mb_2u_lib.s9s_mb_2u(sch_1):page437_i78@pure_quanta.q_cap(chips)',
 VAR_0_ONSEMI='VALUE|0.1UF|VOLTAGE|25V|TOLERANCE|10%|PACK_TYPE|0402|MATERIAL|EMP~
TY|PART_NUMBER|CH4104K1B00|STANDARD||LIFECYCLE||ASS_PART||PART_NUMBER|CH4104K1B0~
0|JEDEC_TYPE|C0402|ALT_SYMBOLS|(C0402_OCTAGONXA,C0402-0201)|VALUE|NA|RATED_VOLTA~
GE|25V|TOL|10%|CLASS|IO|DESCRIPTION|CAP CHIP 0.1U 25V(+-10%,X7R,0402)|COMPONENT_~
TYPE|CHIP0402|LEAD_LENGTH||LPID||DATE|20160113|VARIANT_DEVICE_TYPE|Q_CAP-0.1UF,2~
5V,10%,0402,EMPTY',
 CDSVAR_REPCELL_ONSEMI='pure_quanta|Q_cap';

PART_NAME
 PC269_P0_5 'Q_CAP_0805-22UF,4V,20%,X6S,TMPA':;

SECTION_NUMBER 1
 '@S9S_MB_2U_LIB.S9S_MB_2U(SCH_1):PAGE437_I56@PURE_QUANTA.Q_CAP(CHIPS)':
 C_PATH='@s9s_mb_2u_lib.s9s_mb_2u(sch_1):page437_i56@pure_quanta.q_cap(chips)';

PART_NAME
 PC268_P0_6 'Q_CAP_0805-22UF,4V,20%,X6S,TMPA':;

SECTION_NUMBER 1
 '@S9S_MB_2U_LIB.S9S_MB_2U(SCH_1):PAGE437_I15@PURE_QUANTA.Q_CAP(CHIPS)':
 C_PATH='@s9s_mb_2u_lib.s9s_mb_2u(sch_1):page437_i15@pure_quanta.q_cap(chips)';

PART_NAME
 PC267_P0_5 'Q_CAP_0805-22UF,4V,20%,X6S,TMPA':;

SECTION_NUMBER 1
 '@S9S_MB_2U_LIB.S9S_MB_2U(SCH_1):PAGE437_I55@PURE_QUANTA.Q_CAP(CHIPS)':
 C_PATH='@s9s_mb_2u_lib.s9s_mb_2u(sch_1):page437_i55@pure_quanta.q_cap(chips)';

PART_NAME
 PC266_P0_6 'Q_CAP_0805-22UF,4V,20%,X6S,TMPA':;

SECTION_NUMBER 1
 '@S9S_MB_2U_LIB.S9S_MB_2U(SCH_1):PAGE437_I14@PURE_QUANTA.Q_CAP(CHIPS)':
 C_PATH='@s9s_mb_2u_lib.s9s_mb_2u(sch_1):page437_i14@pure_quanta.q_cap(chips)';

PART_NAME
 PC263_P0_5 'Q_CAP_C0805-22UF,16V,20%,X6S,CA':;

SECTION_NUMBER 1
 '@S9S_MB_2U_LIB.S9S_MB_2U(SCH_1):PAGE437_I52@PURE_QUANTA.Q_CAP(CHIPS)':
 C_PATH='@s9s_mb_2u_lib.s9s_mb_2u(sch_1):page437_i52@pure_quanta.q_cap(chips)';

PART_NAME
 PC262_P0_6 'Q_CAP_C0805-22UF,16V,20%,X6S,CA':;

SECTION_NUMBER 1
 '@S9S_MB_2U_LIB.S9S_MB_2U(SCH_1):PAGE437_I47@PURE_QUANTA.Q_CAP(CHIPS)':
 C_PATH='@s9s_mb_2u_lib.s9s_mb_2u(sch_1):page437_i47@pure_quanta.q_cap(chips)';

PART_NAME
 PC261_P0_5 'Q_CAP_C0805-22UF,16V,20%,X6S,CA':;

SECTION_NUMBER 1
 '@S9S_MB_2U_LIB.S9S_MB_2U(SCH_1):PAGE437_I51@PURE_QUANTA.Q_CAP(CHIPS)':
 C_PATH='@s9s_mb_2u_lib.s9s_mb_2u(sch_1):page437_i51@pure_quanta.q_cap(chips)';

PART_NAME
 PC260_P0_6 'Q_CAP_C0805-22UF,16V,20%,X6S,CA':;

SECTION_NUMBER 1
 '@S9S_MB_2U_LIB.S9S_MB_2U(SCH_1):PAGE437_I46@PURE_QUANTA.Q_CAP(CHIPS)':
 C_PATH='@s9s_mb_2u_lib.s9s_mb_2u(sch_1):page437_i46@pure_quanta.q_cap(chips)';

PART_NAME
 PC259_P0_5 'Q_CAP_C0805-22UF,16V,20%,X6S,CA':;

SECTION_NUMBER 1
 '@S9S_MB_2U_LIB.S9S_MB_2U(SCH_1):PAGE437_I45@PURE_QUANTA.Q_CAP(CHIPS)':
 C_PATH='@s9s_mb_2u_lib.s9s_mb_2u(sch_1):page437_i45@pure_quanta.q_cap(chips)';

PART_NAME
 PC258_P0_6 'Q_CAP_C0805-22UF,16V,20%,X6S,CA':;

SECTION_NUMBER 1
 '@S9S_MB_2U_LIB.S9S_MB_2U(SCH_1):PAGE437_I39@PURE_QUANTA.Q_CAP(CHIPS)':
 C_PATH='@s9s_mb_2u_lib.s9s_mb_2u(sch_1):page437_i39@pure_quanta.q_cap(chips)';

PART_NAME
 PC257 'Q_CAP_C0402-100NF,50V,10%,X7R,A':;

SECTION_NUMBER 1
 '@S9S_MB_2U_LIB.S9S_MB_2U(SCH_1):PAGE437_I79@PURE_QUANTA.Q_CAP(CHIPS)':
 C_PATH='@s9s_mb_2u_lib.s9s_mb_2u(sch_1):page437_i79@pure_quanta.q_cap(chips)';

PART_NAME
 PC256 'Q_CAP_C0402-100NF,50V,10%,X7R,A':;

SECTION_NUMBER 1
 '@S9S_MB_2U_LIB.S9S_MB_2U(SCH_1):PAGE437_I80@PURE_QUANTA.Q_CAP(CHIPS)':
 C_PATH='@s9s_mb_2u_lib.s9s_mb_2u(sch_1):page437_i80@pure_quanta.q_cap(chips)';

PART_NAME
 PC255_P0_5 'Q_CAP_C0402-1UF,16V,10%,X6S,CHA':;

SECTION_NUMBER 1
 '@S9S_MB_2U_LIB.S9S_MB_2U(SCH_1):PAGE437_I44@PURE_QUANTA.Q_CAP(CHIPS)':
 C_PATH='@s9s_mb_2u_lib.s9s_mb_2u(sch_1):page437_i44@pure_quanta.q_cap(chips)';

PART_NAME
 PC254_P0_6 'Q_CAP_C0402-1UF,16V,10%,X6S,CHA':;

SECTION_NUMBER 1
 '@S9S_MB_2U_LIB.S9S_MB_2U(SCH_1):PAGE437_I38@PURE_QUANTA.Q_CAP(CHIPS)':
 C_PATH='@s9s_mb_2u_lib.s9s_mb_2u(sch_1):page437_i38@pure_quanta.q_cap(chips)';

PART_NAME
 PC253_P0_5 'Q_CAP_0402-3300PF,50V,10%,X7R,A':;

SECTION_NUMBER 1
 '@S9S_MB_2U_LIB.S9S_MB_2U(SCH_1):PAGE437_I43@PURE_QUANTA.Q_CAP(CHIPS)':
 C_PATH='@s9s_mb_2u_lib.s9s_mb_2u(sch_1):page437_i43@pure_quanta.q_cap(chips)';

PART_NAME
 PC252_P0_6 'Q_CAP_0402-3300PF,50V,10%,X7R,A':;

SECTION_NUMBER 1
 '@S9S_MB_2U_LIB.S9S_MB_2U(SCH_1):PAGE437_I37@PURE_QUANTA.Q_CAP(CHIPS)':
 C_PATH='@s9s_mb_2u_lib.s9s_mb_2u(sch_1):page437_i37@pure_quanta.q_cap(chips)';

PART_NAME
 PC251_P0_5 'Q_CAP_C0402-2.2UF,10V,10%,X6S,A':;

SECTION_NUMBER 1
 '@S9S_MB_2U_LIB.S9S_MB_2U(SCH_1):PAGE437_I35@PURE_QUANTA.Q_CAP(CHIPS)':
 C_PATH='@s9s_mb_2u_lib.s9s_mb_2u(sch_1):page437_i35@pure_quanta.q_cap(chips)';

PART_NAME
 PC250_P0_6 'Q_CAP_C0402-2.2UF,10V,10%,X6S,A':;

SECTION_NUMBER 1
 '@S9S_MB_2U_LIB.S9S_MB_2U(SCH_1):PAGE437_I26@PURE_QUANTA.Q_CAP(CHIPS)':
 C_PATH='@s9s_mb_2u_lib.s9s_mb_2u(sch_1):page437_i26@pure_quanta.q_cap(chips)';

PART_NAME
 PC249 'Q_CAP_C0402-2.2UF,10V,10%,X6S,A':;

SECTION_NUMBER 1
 '@S9S_MB_2U_LIB.S9S_MB_2U(SCH_1):PAGE437_I31@PURE_QUANTA.Q_CAP(CHIPS)':
 C_PATH='@s9s_mb_2u_lib.s9s_mb_2u(sch_1):page437_i31@pure_quanta.q_cap(chips)';

PART_NAME
 PC248 'Q_CAP_C0402-2.2UF,10V,10%,X6S,A':;

SECTION_NUMBER 1
 '@S9S_MB_2U_LIB.S9S_MB_2U(SCH_1):PAGE437_I18@PURE_QUANTA.Q_CAP(CHIPS)':
 C_PATH='@s9s_mb_2u_lib.s9s_mb_2u(sch_1):page437_i18@pure_quanta.q_cap(chips)';

PART_NAME
 PU7_P0_7 'ISL99390FRZTR5935-ISL99390FRZ-A':;

SECTION_NUMBER 1
 '@S9S_MB_2U_LIB.S9S_MB_2U(SCH_1):PAGE438_I25@PURE_QUANTA.ISL99390FRZTR5935(CHIPS)':
 C_PATH='@s9s_mb_2u_lib.s9s_mb_2u(sch_1):page438_i25@pure_quanta.isl99390frztr5935~
(chips)',
 VAR_0_ONSEMI='VAR_REPLACED|ISL99390FRZTR5935|VAR_PARTNAME|FDMF5085|VALUE|FDMF50~
85|PART_TYPE|SMLF|MATERIAL|IC|PART_NUMBER|AL005085000|STANDARD||LIFECYCLE||PART_~
NUMBER|AL005085000|JEDEC_TYPE|PQFN21_6X5XB|DESCRIPTION|IC OTHER(39P) FDMF5085(PQ~
FN)|MANUFTR|ONS|MANUF_PN|FDMF5085|RD_CMPLS_LVL|EP(V1)|CMPLS_LVL||FROM_PJ|S9S-KIM~
I|CLASS|IC|DIP_SMD||DATA|ONS_FDMF5085.pdf|EE_CHECK_LIST||FP_ECN||PSL||CREATOR||S~
TATUS||MSD|NA|ESD_CDM|NA|ESD_HBM|NA|ESD_MM|NA|PIN_LENGTH_SHORT_PIN|0 MILS|PIN_LE~
NGTH_LONG_PIN|0 MILS|CREATEDAY|20200423|VARIANT_DEVICE_TYPE|FDMF5085-FDMF5085,SM~
LF,IC,AL00',
 CDSVAR_REPCELL_ONSEMI='pure_quanta|fdmf5085';

PART_NAME
 PU6_P0_8 'ISL99390FRZTR5935-ISL99390FRZ-A':;

SECTION_NUMBER 1
 '@S9S_MB_2U_LIB.S9S_MB_2U(SCH_1):PAGE438_I7@PURE_QUANTA.ISL99390FRZTR5935(CHIPS)':
 C_PATH='@s9s_mb_2u_lib.s9s_mb_2u(sch_1):page438_i7@pure_quanta.isl99390frztr5935(~
chips)',
 VAR_0_ONSEMI='VAR_REPLACED|ISL99390FRZTR5935|VAR_PARTNAME|FDMF5085|VALUE|FDMF50~
85|PART_TYPE|SMLF|MATERIAL|IC|PART_NUMBER|AL005085000|STANDARD||LIFECYCLE||PART_~
NUMBER|AL005085000|JEDEC_TYPE|PQFN21_6X5XB|DESCRIPTION|IC OTHER(39P) FDMF5085(PQ~
FN)|MANUFTR|ONS|MANUF_PN|FDMF5085|RD_CMPLS_LVL|EP(V1)|CMPLS_LVL||FROM_PJ|S9S-KIM~
I|CLASS|IC|DIP_SMD||DATA|ONS_FDMF5085.pdf|EE_CHECK_LIST||FP_ECN||PSL||CREATOR||S~
TATUS||MSD|NA|ESD_CDM|NA|ESD_HBM|NA|ESD_MM|NA|PIN_LENGTH_SHORT_PIN|0 MILS|PIN_LE~
NGTH_LONG_PIN|0 MILS|CREATEDAY|20200423|VARIANT_DEVICE_TYPE|FDMF5085-FDMF5085,SM~
LF,IC,AL00',
 CDSVAR_REPCELL_ONSEMI='pure_quanta|fdmf5085';

PART_NAME
 PR1773 'Q_RES_0402LF-3.3,1%,1/16W,CHIPA':;

SECTION_NUMBER 1
 '@S9S_MB_2U_LIB.S9S_MB_2U(SCH_1):PAGE438_I71@PURE_QUANTA.Q_RES(CHIPS)':
 C_PATH='@s9s_mb_2u_lib.s9s_mb_2u(sch_1):page438_i71@pure_quanta.q_res(chips)',
 VAR_0_ONSEMI='VALUE|5.1|TOLERANCE|5%|WATTAGE|1/16W|PACK_TYPE|0402LF|MATERIAL|CH~
IP|PART_NUMBER|CS-5102JB03|STANDARD|End of Design|LIFECYCLE|Comp-Approve|PART_NU~
MBER|CS-5102JB03|JEDEC_TYPE|R0402|ALT_SYMBOLS|(R0402-0201)|VALUE|5.1|TOL|5%|WATT~
AGE|1/16W |CLASS|DISCRETE|DESCRIPTION|RES CHIP 5.1 1/16W +-5%(0402)|COMPONENT_TY~
PE|CHIP0402|LEAD_LENGTH||DFM_EXCLUSION||DAY|20100827|VARIANT_DEVICE_TYPE|Q_RES-5~
.1,5%,1/16W,0402LF,CHIP',
 CDSVAR_REPCELL_ONSEMI='pure_quanta|Q_res';

PART_NAME
 PR1772 'Q_RES_0402LF-3.3,1%,1/16W,CHIPA':;

SECTION_NUMBER 1
 '@S9S_MB_2U_LIB.S9S_MB_2U(SCH_1):PAGE438_I73@PURE_QUANTA.Q_RES(CHIPS)':
 C_PATH='@s9s_mb_2u_lib.s9s_mb_2u(sch_1):page438_i73@pure_quanta.q_res(chips)',
 VAR_0_ONSEMI='VALUE|5.1|TOLERANCE|5%|WATTAGE|1/16W|PACK_TYPE|0402LF|MATERIAL|CH~
IP|PART_NUMBER|CS-5102JB03|STANDARD|End of Design|LIFECYCLE|Comp-Approve|PART_NU~
MBER|CS-5102JB03|JEDEC_TYPE|R0402|ALT_SYMBOLS|(R0402-0201)|VALUE|5.1|TOL|5%|WATT~
AGE|1/16W |CLASS|DISCRETE|DESCRIPTION|RES CHIP 5.1 1/16W +-5%(0402)|COMPONENT_TY~
PE|CHIP0402|LEAD_LENGTH||DFM_EXCLUSION||DAY|20100827|VARIANT_DEVICE_TYPE|Q_RES-5~
.1,5%,1/16W,0402LF,CHIP',
 CDSVAR_REPCELL_ONSEMI='pure_quanta|Q_res';

PART_NAME
 PR137 'Q_RES_0402LF-0,5%,1/16W,CHIP,CA':;

SECTION_NUMBER 1
 '@S9S_MB_2U_LIB.S9S_MB_2U(SCH_1):PAGE438_I82@PURE_QUANTA.Q_RES(CHIPS)':
 C_PATH='@s9s_mb_2u_lib.s9s_mb_2u(sch_1):page438_i82@pure_quanta.q_res(chips)',
 VAR_0_ONSEMI='VALUE|0|TOLERANCE|5%|WATTAGE|1/16W|PACK_TYPE|0402LF|MATERIAL|EMPT~
Y|PART_NUMBER|CS00002JB38|STANDARD|End of Design|LIFECYCLE|Comp-Approve|PART_NUM~
BER|CS00002JB38|JEDEC_TYPE|R0402|ALT_SYMBOLS|(R0402-0201)|VALUE|0|TOL|5%|WATTAGE~
|1/16W|CLASS|IO|DESCRIPTION|RESISTOR CHIP 0 1/16W +-5%(0402)|COMPONENT_TYPE|CHIP~
0402|LEAD_LENGTH||DFM_EXCLUSION||DAY|20100618|VARIANT_DEVICE_TYPE|Q_RES-0,5%,1/1~
6W,0402LF,EMPTY,',
 CDSVAR_REPCELL_ONSEMI='pure_quanta|Q_res';

PART_NAME
 PR136 'Q_RES_0402LF-0,5%,1/16W,CHIP,CA':;

SECTION_NUMBER 1
 '@S9S_MB_2U_LIB.S9S_MB_2U(SCH_1):PAGE438_I83@PURE_QUANTA.Q_RES(CHIPS)':
 C_PATH='@s9s_mb_2u_lib.s9s_mb_2u(sch_1):page438_i83@pure_quanta.q_res(chips)',
 VAR_0_ONSEMI='VALUE|0|TOLERANCE|5%|WATTAGE|1/16W|PACK_TYPE|0402LF|MATERIAL|EMPT~
Y|PART_NUMBER|CS00002JB38|STANDARD|End of Design|LIFECYCLE|Comp-Approve|PART_NUM~
BER|CS00002JB38|JEDEC_TYPE|R0402|ALT_SYMBOLS|(R0402-0201)|VALUE|0|TOL|5%|WATTAGE~
|1/16W|CLASS|IO|DESCRIPTION|RESISTOR CHIP 0 1/16W +-5%(0402)|COMPONENT_TYPE|CHIP~
0402|LEAD_LENGTH||DFM_EXCLUSION||DAY|20100618|VARIANT_DEVICE_TYPE|Q_RES-0,5%,1/1~
6W,0402LF,EMPTY,',
 CDSVAR_REPCELL_ONSEMI='pure_quanta|Q_res';

PART_NAME
 PR135 'Q_RES_0402LF-2.2,1%,1/16W,CHIPA':;

SECTION_NUMBER 1
 '@S9S_MB_2U_LIB.S9S_MB_2U(SCH_1):PAGE438_I22@PURE_QUANTA.Q_RES(CHIPS)':
 C_PATH='@s9s_mb_2u_lib.s9s_mb_2u(sch_1):page438_i22@pure_quanta.q_res(chips)';

PART_NAME
 PR134 'Q_RES_0402LF-2.2,1%,1/16W,CHIPA':;

SECTION_NUMBER 1
 '@S9S_MB_2U_LIB.S9S_MB_2U(SCH_1):PAGE438_I10@PURE_QUANTA.Q_RES(CHIPS)':
 C_PATH='@s9s_mb_2u_lib.s9s_mb_2u(sch_1):page438_i10@pure_quanta.q_res(chips)';

PART_NAME
 PR133 'Q_RES_0402LF-8.87K,1%,1/16W,EMA':;

SECTION_NUMBER 1
 '@S9S_MB_2U_LIB.S9S_MB_2U(SCH_1):PAGE438_I84@PURE_QUANTA.Q_RES(CHIPS)':
 C_PATH='@s9s_mb_2u_lib.s9s_mb_2u(sch_1):page438_i84@pure_quanta.q_res(chips)';

PART_NAME
 PR132 'Q_RES_0402LF-8.87K,1%,1/16W,EMA':;

SECTION_NUMBER 1
 '@S9S_MB_2U_LIB.S9S_MB_2U(SCH_1):PAGE438_I85@PURE_QUANTA.Q_RES(CHIPS)':
 C_PATH='@s9s_mb_2u_lib.s9s_mb_2u(sch_1):page438_i85@pure_quanta.q_res(chips)';

PART_NAME
 PL8 'Q_INDUCTOR_SMLF-130NH/106A,INDA':;

SECTION_NUMBER 1
 '@S9S_MB_2U_LIB.S9S_MB_2U(SCH_1):PAGE438_I48@PURE_QUANTA.Q_INDUCTOR(CHIPS)':
 C_PATH='@s9s_mb_a_lib.s9s_mb_a(sch_1):page438_i48@pure_quanta.q_inductor(chips)~
';

PART_NAME
 PL7 'Q_INDUCTOR_SMLF-130NH/106A,INDA':;

SECTION_NUMBER 1
 '@S9S_MB_2U_LIB.S9S_MB_2U(SCH_1):PAGE438_I32@PURE_QUANTA.Q_INDUCTOR(CHIPS)':
 C_PATH='@s9s_mb_a_lib.s9s_mb_a(sch_1):page438_i32@pure_quanta.q_inductor(chips)~
';

PART_NAME
 PC1345 'Q_CAP_0402-0.1UF,25V,10%,X7R,CA':;

SECTION_NUMBER 1
 '@S9S_MB_2U_LIB.S9S_MB_2U(SCH_1):PAGE438_I78@PURE_QUANTA.Q_CAP(CHIPS)':
 C_PATH='@s9s_mb_2u_lib.s9s_mb_2u(sch_1):page438_i78@pure_quanta.q_cap(chips)',
 VAR_0_ONSEMI='VALUE|0.1UF|VOLTAGE|25V|TOLERANCE|10%|PACK_TYPE|0402|MATERIAL|EMP~
TY|PART_NUMBER|CH4104K1B00|STANDARD||LIFECYCLE||ASS_PART||PART_NUMBER|CH4104K1B0~
0|JEDEC_TYPE|C0402|ALT_SYMBOLS|(C0402_OCTAGONXA,C0402-0201)|VALUE|NA|RATED_VOLTA~
GE|25V|TOL|10%|CLASS|IO|DESCRIPTION|CAP CHIP 0.1U 25V(+-10%,X7R,0402)|COMPONENT_~
TYPE|CHIP0402|LEAD_LENGTH||LPID||DATE|20160113|VARIANT_DEVICE_TYPE|Q_CAP-0.1UF,2~
5V,10%,0402,EMPTY',
 CDSVAR_REPCELL_ONSEMI='pure_quanta|Q_cap';

PART_NAME
 PC1344 'Q_CAP_0402-0.1UF,25V,10%,X7R,CA':;

SECTION_NUMBER 1
 '@S9S_MB_2U_LIB.S9S_MB_2U(SCH_1):PAGE438_I76@PURE_QUANTA.Q_CAP(CHIPS)':
 C_PATH='@s9s_mb_2u_lib.s9s_mb_2u(sch_1):page438_i76@pure_quanta.q_cap(chips)',
 VAR_0_ONSEMI='VALUE|0.1UF|VOLTAGE|25V|TOLERANCE|10%|PACK_TYPE|0402|MATERIAL|EMP~
TY|PART_NUMBER|CH4104K1B00|STANDARD||LIFECYCLE||ASS_PART||PART_NUMBER|CH4104K1B0~
0|JEDEC_TYPE|C0402|ALT_SYMBOLS|(C0402_OCTAGONXA,C0402-0201)|VALUE|NA|RATED_VOLTA~
GE|25V|TOL|10%|CLASS|IO|DESCRIPTION|CAP CHIP 0.1U 25V(+-10%,X7R,0402)|COMPONENT_~
TYPE|CHIP0402|LEAD_LENGTH||LPID||DATE|20160113|VARIANT_DEVICE_TYPE|Q_CAP-0.1UF,2~
5V,10%,0402,EMPTY',
 CDSVAR_REPCELL_ONSEMI='pure_quanta|Q_cap';

PART_NAME
 PC247_P0_7 'Q_CAP_0805-22UF,4V,20%,X6S,TMPA':;

SECTION_NUMBER 1
 '@S9S_MB_2U_LIB.S9S_MB_2U(SCH_1):PAGE438_I55@PURE_QUANTA.Q_CAP(CHIPS)':
 C_PATH='@s9s_mb_2u_lib.s9s_mb_2u(sch_1):page438_i55@pure_quanta.q_cap(chips)';

PART_NAME
 PC246_P0_8 'Q_CAP_0805-22UF,4V,20%,X6S,TMPA':;

SECTION_NUMBER 1
 '@S9S_MB_2U_LIB.S9S_MB_2U(SCH_1):PAGE438_I41@PURE_QUANTA.Q_CAP(CHIPS)':
 C_PATH='@s9s_mb_2u_lib.s9s_mb_2u(sch_1):page438_i41@pure_quanta.q_cap(chips)';

PART_NAME
 PC245_P0_7 'Q_CAP_0805-22UF,4V,20%,X6S,TMPA':;

SECTION_NUMBER 1
 '@S9S_MB_2U_LIB.S9S_MB_2U(SCH_1):PAGE438_I53@PURE_QUANTA.Q_CAP(CHIPS)':
 C_PATH='@s9s_mb_2u_lib.s9s_mb_2u(sch_1):page438_i53@pure_quanta.q_cap(chips)';

PART_NAME
 PC244_P0_8 'Q_CAP_0805-22UF,4V,20%,X6S,TMPA':;

SECTION_NUMBER 1
 '@S9S_MB_2U_LIB.S9S_MB_2U(SCH_1):PAGE438_I39@PURE_QUANTA.Q_CAP(CHIPS)':
 C_PATH='@s9s_mb_2u_lib.s9s_mb_2u(sch_1):page438_i39@pure_quanta.q_cap(chips)';

PART_NAME
 PC243_P0_7 'Q_CAP_C0402-1UF,16V,10%,X6S,CHA':;

SECTION_NUMBER 1
 '@S9S_MB_2U_LIB.S9S_MB_2U(SCH_1):PAGE438_I52@PURE_QUANTA.Q_CAP(CHIPS)':
 C_PATH='@s9s_mb_2u_lib.s9s_mb_2u(sch_1):page438_i52@pure_quanta.q_cap(chips)';

PART_NAME
 PC242_P0_8 'Q_CAP_C0402-1UF,16V,10%,X6S,CHA':;

SECTION_NUMBER 1
 '@S9S_MB_2U_LIB.S9S_MB_2U(SCH_1):PAGE438_I37@PURE_QUANTA.Q_CAP(CHIPS)':
 C_PATH='@s9s_mb_2u_lib.s9s_mb_2u(sch_1):page438_i37@pure_quanta.q_cap(chips)';

PART_NAME
 PC241_P0_7 'Q_CAP_C0805-22UF,16V,20%,X6S,CA':;

SECTION_NUMBER 1
 '@S9S_MB_2U_LIB.S9S_MB_2U(SCH_1):PAGE438_I51@PURE_QUANTA.Q_CAP(CHIPS)':
 C_PATH='@s9s_mb_2u_lib.s9s_mb_2u(sch_1):page438_i51@pure_quanta.q_cap(chips)';

PART_NAME
 PC240_P0_8 'Q_CAP_C0805-22UF,16V,20%,X6S,CA':;

SECTION_NUMBER 1
 '@S9S_MB_2U_LIB.S9S_MB_2U(SCH_1):PAGE438_I35@PURE_QUANTA.Q_CAP(CHIPS)':
 C_PATH='@s9s_mb_2u_lib.s9s_mb_2u(sch_1):page438_i35@pure_quanta.q_cap(chips)';

PART_NAME
 PC239_P0_7 'Q_CAP_C0805-22UF,16V,20%,X6S,CA':;

SECTION_NUMBER 1
 '@S9S_MB_2U_LIB.S9S_MB_2U(SCH_1):PAGE438_I50@PURE_QUANTA.Q_CAP(CHIPS)':
 C_PATH='@s9s_mb_2u_lib.s9s_mb_2u(sch_1):page438_i50@pure_quanta.q_cap(chips)';

PART_NAME
 PC238_P0_8 'Q_CAP_C0805-22UF,16V,20%,X6S,CA':;

SECTION_NUMBER 1
 '@S9S_MB_2U_LIB.S9S_MB_2U(SCH_1):PAGE438_I34@PURE_QUANTA.Q_CAP(CHIPS)':
 C_PATH='@s9s_mb_2u_lib.s9s_mb_2u(sch_1):page438_i34@pure_quanta.q_cap(chips)';

PART_NAME
 PC237_P0_7 'Q_CAP_C0805-22UF,16V,20%,X6S,CA':;

SECTION_NUMBER 1
 '@S9S_MB_2U_LIB.S9S_MB_2U(SCH_1):PAGE438_I49@PURE_QUANTA.Q_CAP(CHIPS)':
 C_PATH='@s9s_mb_2u_lib.s9s_mb_2u(sch_1):page438_i49@pure_quanta.q_cap(chips)';

PART_NAME
 PC236_P0_8 'Q_CAP_C0805-22UF,16V,20%,X6S,CA':;

SECTION_NUMBER 1
 '@S9S_MB_2U_LIB.S9S_MB_2U(SCH_1):PAGE438_I33@PURE_QUANTA.Q_CAP(CHIPS)':
 C_PATH='@s9s_mb_2u_lib.s9s_mb_2u(sch_1):page438_i33@pure_quanta.q_cap(chips)';

PART_NAME
 PC235 'Q_CAP_C0402-100NF,50V,10%,X7R,A':;

SECTION_NUMBER 1
 '@S9S_MB_2U_LIB.S9S_MB_2U(SCH_1):PAGE438_I80@PURE_QUANTA.Q_CAP(CHIPS)':
 C_PATH='@s9s_mb_2u_lib.s9s_mb_2u(sch_1):page438_i80@pure_quanta.q_cap(chips)';

PART_NAME
 PC234 'Q_CAP_C0402-100NF,50V,10%,X7R,A':;

SECTION_NUMBER 1
 '@S9S_MB_2U_LIB.S9S_MB_2U(SCH_1):PAGE438_I81@PURE_QUANTA.Q_CAP(CHIPS)':
 C_PATH='@s9s_mb_2u_lib.s9s_mb_2u(sch_1):page438_i81@pure_quanta.q_cap(chips)';

PART_NAME
 PC233_P0_7 'Q_CAP_C0402-1UF,16V,10%,X6S,CHA':;

SECTION_NUMBER 1
 '@S9S_MB_2U_LIB.S9S_MB_2U(SCH_1):PAGE438_I46@PURE_QUANTA.Q_CAP(CHIPS)':
 C_PATH='@s9s_mb_2u_lib.s9s_mb_2u(sch_1):page438_i46@pure_quanta.q_cap(chips)';

PART_NAME
 PC232_P0_8 'Q_CAP_C0402-1UF,16V,10%,X6S,CHA':;

SECTION_NUMBER 1
 '@S9S_MB_2U_LIB.S9S_MB_2U(SCH_1):PAGE438_I30@PURE_QUANTA.Q_CAP(CHIPS)':
 C_PATH='@s9s_mb_2u_lib.s9s_mb_2u(sch_1):page438_i30@pure_quanta.q_cap(chips)';

PART_NAME
 PC231_P0_7 'Q_CAP_0402-3300PF,50V,10%,X7R,A':;

SECTION_NUMBER 1
 '@S9S_MB_2U_LIB.S9S_MB_2U(SCH_1):PAGE438_I44@PURE_QUANTA.Q_CAP(CHIPS)':
 C_PATH='@s9s_mb_2u_lib.s9s_mb_2u(sch_1):page438_i44@pure_quanta.q_cap(chips)';

PART_NAME
 PC230_P0_8 'Q_CAP_0402-3300PF,50V,10%,X7R,A':;

SECTION_NUMBER 1
 '@S9S_MB_2U_LIB.S9S_MB_2U(SCH_1):PAGE438_I29@PURE_QUANTA.Q_CAP(CHIPS)':
 C_PATH='@s9s_mb_2u_lib.s9s_mb_2u(sch_1):page438_i29@pure_quanta.q_cap(chips)';

PART_NAME
 PC229_P0_7 'Q_CAP_C0402-2.2UF,10V,10%,X6S,A':;

SECTION_NUMBER 1
 '@S9S_MB_2U_LIB.S9S_MB_2U(SCH_1):PAGE438_I23@PURE_QUANTA.Q_CAP(CHIPS)':
 C_PATH='@s9s_mb_2u_lib.s9s_mb_2u(sch_1):page438_i23@pure_quanta.q_cap(chips)';

PART_NAME
 PC228_P0_8 'Q_CAP_C0402-2.2UF,10V,10%,X6S,A':;

SECTION_NUMBER 1
 '@S9S_MB_2U_LIB.S9S_MB_2U(SCH_1):PAGE438_I11@PURE_QUANTA.Q_CAP(CHIPS)':
 C_PATH='@s9s_mb_2u_lib.s9s_mb_2u(sch_1):page438_i11@pure_quanta.q_cap(chips)';

PART_NAME
 PC227 'Q_CAP_C0402-2.2UF,10V,10%,X6S,A':;

SECTION_NUMBER 1
 '@S9S_MB_2U_LIB.S9S_MB_2U(SCH_1):PAGE438_I21@PURE_QUANTA.Q_CAP(CHIPS)':
 C_PATH='@s9s_mb_2u_lib.s9s_mb_2u(sch_1):page438_i21@pure_quanta.q_cap(chips)';

PART_NAME
 PC226 'Q_CAP_C0402-2.2UF,10V,10%,X6S,A':;

SECTION_NUMBER 1
 '@S9S_MB_2U_LIB.S9S_MB_2U(SCH_1):PAGE438_I9@PURE_QUANTA.Q_CAP(CHIPS)':
 C_PATH='@s9s_mb_2u_lib.s9s_mb_2u(sch_1):page438_i9@pure_quanta.q_cap(chips)';

PART_NAME
 R1766 'Q_RES_0402LF-49.9     ,1%  ,1/B':;

SECTION_NUMBER 1
 '@S9S_MB_2U_LIB.S9S_MB_2U(SCH_1):PAGE440_I409@PURE_QUANTA.Q_RES(CHIPS)':
 C_PATH='@s9s_mb_2u_lib.s9s_mb_2u(sch_1):page440_i409@pure_quanta.q_res(chips)';

PART_NAME
 R561 'Q_RES_0402LF-100,1%,1/16W,EMPTA':;

SECTION_NUMBER 1
 '@S9S_MB_2U_LIB.S9S_MB_2U(SCH_1):PAGE440_I411@PURE_QUANTA.Q_RES(CHIPS)':
 C_PATH='@s9s_mb_2u_lib.s9s_mb_2u(sch_1):page440_i411@pure_quanta.q_res(chips)';

PART_NAME
 PU5 'ISL69260IRAZT-ISL69260IRAZ-T,SA':;

SECTION_NUMBER 1
 '@S9S_MB_2U_LIB.S9S_MB_2U(SCH_1):PAGE440_I412@PURE_QUANTA.ISL69260IRAZT(CHIPS)':
 C_PATH='@s9s_mb_2u_lib.s9s_mb_2u(sch_1):page440_i412@pure_quanta.isl69260irazt(ch~
ips)',
 VAR_0_ONSEMI='VAR_REPLACED|ISL69260IRAZT|VAR_PARTNAME|FD5001|VALUE|FD5001|PART_~
TYPE|SMLF|MATERIAL|IC|PART_NUMBER|AL005001004|STANDARD||LIFECYCLE||PART_NUMBER|A~
L005001004|JEDEC_TYPE|VFQFPN40_TH_0-4_5X5XC|DESCRIPTION|IC OTHER(40P) FD5001(QFN~
)|MANUFTR|ONS|MANUF_PN|FD5001|RD_CMPLS_LVL|EP(V1)|CMPLS_LVL||FROM_PJ|S9S-KIMI|CL~
ASS|IC|DIP_SMD||DATA|ONS_FD5001.pdf|EE_CHECK_LIST||FP_ECN|FD5001.msg|PSL||CREATO~
R||STATUS||MSD|NA|ESD_CDM|NA|ESD_HBM|NA|ESD_MM|NA|PIN_LENGTH_SHORT_PIN|0 MILS|PI~
N_LENGTH_LONG_PIN|0 MILS|CREATEDAY|20200421|VARIANT_DEVICE_TYPE|FD5001-FD5001,SM~
LF,IC,AL005001',
 CDSVAR_REPCELL_ONSEMI='pure_quanta|fd5001';

PART_NAME
 PR524 'Q_RES_0402LF-1K,1%,1/16W,CHIP,A':;

SECTION_NUMBER 1
 '@S9S_MB_2U_LIB.S9S_MB_2U(SCH_1):PAGE440_I298@PURE_QUANTA.Q_RES(CHIPS)':
 C_PATH='@s9s_mb_2u_lib.s9s_mb_2u(sch_1):page440_i298@pure_quanta.q_res(chips)';

PART_NAME
 PR523 'Q_RES_0402LF-1K,1%,1/16W,CHIP,A':;

SECTION_NUMBER 1
 '@S9S_MB_2U_LIB.S9S_MB_2U(SCH_1):PAGE440_I297@PURE_QUANTA.Q_RES(CHIPS)':
 C_PATH='@s9s_mb_2u_lib.s9s_mb_2u(sch_1):page440_i297@pure_quanta.q_res(chips)';

PART_NAME
 PR522 'Q_RES_0402LF-100,1%,1/16W,CHIPA':;

SECTION_NUMBER 1
 '@S9S_MB_2U_LIB.S9S_MB_2U(SCH_1):PAGE440_I261@PURE_QUANTA.Q_RES(CHIPS)':
 C_PATH='@s9s_mb_2u_lib.s9s_mb_2u(sch_1):page440_i261@pure_quanta.q_res(chips)';

PART_NAME
 PR521 'Q_RES_0402LF-100,1%,1/16W,CHIPA':;

SECTION_NUMBER 1
 '@S9S_MB_2U_LIB.S9S_MB_2U(SCH_1):PAGE440_I252@PURE_QUANTA.Q_RES(CHIPS)':
 C_PATH='@s9s_mb_2u_lib.s9s_mb_2u(sch_1):page440_i252@pure_quanta.q_res(chips)';

PART_NAME
 PR520 'Q_RES_0402LF-100,1%,1/16W,CHIPA':;

SECTION_NUMBER 1
 '@S9S_MB_2U_LIB.S9S_MB_2U(SCH_1):PAGE440_I265@PURE_QUANTA.Q_RES(CHIPS)':
 C_PATH='@s9s_mb_2u_lib.s9s_mb_2u(sch_1):page440_i265@pure_quanta.q_res(chips)';

PART_NAME
 PR519 'Q_RES_0402LF-100,1%,1/16W,CHIPA':;

SECTION_NUMBER 1
 '@S9S_MB_2U_LIB.S9S_MB_2U(SCH_1):PAGE440_I256@PURE_QUANTA.Q_RES(CHIPS)':
 C_PATH='@s9s_mb_2u_lib.s9s_mb_2u(sch_1):page440_i256@pure_quanta.q_res(chips)';

PART_NAME
 PR131 'Q_RES_0402LF-1K,1%,1/16W,EMPTYA':;

SECTION_NUMBER 1
 '@S9S_MB_2U_LIB.S9S_MB_2U(SCH_1):PAGE440_I386@PURE_QUANTA.Q_RES(CHIPS)':
 C_PATH='@s9s_mb_2u_lib.s9s_mb_2u(sch_1):page440_i386@pure_quanta.q_res(chips)';

PART_NAME
 PR130 'Q_RES_0402LF-1,1%,1/16W,CHIP,CA':;

SECTION_NUMBER 1
 '@S9S_MB_2U_LIB.S9S_MB_2U(SCH_1):PAGE440_I335@PURE_QUANTA.Q_RES(CHIPS)':
 C_PATH='@s9s_mb_2u_lib.s9s_mb_2u(sch_1):page440_i335@pure_quanta.q_res(chips)';

PART_NAME
 PR123 'Q_RES_0402LF-1K,1%,1/16W,EMPTYA':;

SECTION_NUMBER 1
 '@S9S_MB_2U_LIB.S9S_MB_2U(SCH_1):PAGE440_I316@PURE_QUANTA.Q_RES(CHIPS)':
 C_PATH='@s9s_mb_2u_lib.s9s_mb_2u(sch_1):page440_i316@pure_quanta.q_res(chips)';

PART_NAME
 PR122 'Q_RES_0402LF-1K,1%,1/16W,EMPTYA':;

SECTION_NUMBER 1
 '@S9S_MB_2U_LIB.S9S_MB_2U(SCH_1):PAGE440_I317@PURE_QUANTA.Q_RES(CHIPS)':
 C_PATH='@s9s_mb_2u_lib.s9s_mb_2u(sch_1):page440_i317@pure_quanta.q_res(chips)';

PART_NAME
 PR121 'Q_RES_0402LF-0,5%,1/16W,CHIP,CA':;

SECTION_NUMBER 1
 '@S9S_MB_2U_LIB.S9S_MB_2U(SCH_1):PAGE440_I259@PURE_QUANTA.Q_RES(CHIPS)':
 C_PATH='@s9s_mb_2u_lib.s9s_mb_2u(sch_1):page440_i259@pure_quanta.q_res(chips)';

PART_NAME
 PR120 'Q_RES_0402LF-0,5%,1/16W,CHIP,CA':;

SECTION_NUMBER 1
 '@S9S_MB_2U_LIB.S9S_MB_2U(SCH_1):PAGE440_I250@PURE_QUANTA.Q_RES(CHIPS)':
 C_PATH='@s9s_mb_2u_lib.s9s_mb_2u(sch_1):page440_i250@pure_quanta.q_res(chips)';

PART_NAME
 PR119 'Q_RES_0402LF-0,5%,1/16W,CHIP,CA':;

SECTION_NUMBER 1
 '@S9S_MB_2U_LIB.S9S_MB_2U(SCH_1):PAGE440_I301@PURE_QUANTA.Q_RES(CHIPS)':
 C_PATH='@s9s_mb_2u_lib.s9s_mb_2u(sch_1):page440_i301@pure_quanta.q_res(chips)';

PART_NAME
 PR118 'Q_RES_0402LF-0,5%,1/16W,CHIP,CA':;

SECTION_NUMBER 1
 '@S9S_MB_2U_LIB.S9S_MB_2U(SCH_1):PAGE440_I304@PURE_QUANTA.Q_RES(CHIPS)':
 C_PATH='@s9s_mb_2u_lib.s9s_mb_2u(sch_1):page440_i304@pure_quanta.q_res(chips)';

PART_NAME
 PR117 'Q_RES_0402LF-1K,1%,1/16W,CHIP,A':;

SECTION_NUMBER 1
 '@S9S_MB_2U_LIB.S9S_MB_2U(SCH_1):PAGE440_I306@PURE_QUANTA.Q_RES(CHIPS)':
 C_PATH='@s9s_mb_2u_lib.s9s_mb_2u(sch_1):page440_i306@pure_quanta.q_res(chips)';

PART_NAME
 PR116 'Q_RES_0402LF-33.2,1%,1/16W,CHIA':;

SECTION_NUMBER 1
 '@S9S_MB_2U_LIB.S9S_MB_2U(SCH_1):PAGE440_I227@PURE_QUANTA.Q_RES(CHIPS)':
 C_PATH='@s9s_mb_2u_lib.s9s_mb_2u(sch_1):page440_i227@pure_quanta.q_res(chips)';

PART_NAME
 PR115 'Q_RES_0402LF-0,5%,1/16W,CHIP,CA':;

SECTION_NUMBER 1
 '@S9S_MB_2U_LIB.S9S_MB_2U(SCH_1):PAGE440_I226@PURE_QUANTA.Q_RES(CHIPS)':
 C_PATH='@s9s_mb_2u_lib.s9s_mb_2u(sch_1):page440_i226@pure_quanta.q_res(chips)';

PART_NAME
 PR114 'Q_RES_0402LF-0,5%,1/16W,CHIP,CA':;

SECTION_NUMBER 1
 '@S9S_MB_2U_LIB.S9S_MB_2U(SCH_1):PAGE440_I213@PURE_QUANTA.Q_RES(CHIPS)':
 C_PATH='@s9s_mb_2u_lib.s9s_mb_2u(sch_1):page440_i213@pure_quanta.q_res(chips)';

PART_NAME
 PR113 'Q_RES_0402LF-0,5%,1/16W,CHIP,CA':;

SECTION_NUMBER 1
 '@S9S_MB_2U_LIB.S9S_MB_2U(SCH_1):PAGE440_I223@PURE_QUANTA.Q_RES(CHIPS)':
 C_PATH='@s9s_mb_2u_lib.s9s_mb_2u(sch_1):page440_i223@pure_quanta.q_res(chips)';

PART_NAME
 PR112 'Q_RES_0402LF-150,1%,1/16W,CHIPA':;

SECTION_NUMBER 1
 '@S9S_MB_2U_LIB.S9S_MB_2U(SCH_1):PAGE440_I222@PURE_QUANTA.Q_RES(CHIPS)':
 C_PATH='@s9s_mb_2u_lib.s9s_mb_2u(sch_1):page440_i222@pure_quanta.q_res(chips)';

PART_NAME
 PR111 'Q_RES_0402LF-0,5%,1/16W,CHIP,CA':;

SECTION_NUMBER 1
 '@S9S_MB_2U_LIB.S9S_MB_2U(SCH_1):PAGE440_I214@PURE_QUANTA.Q_RES(CHIPS)':
 C_PATH='@s9s_mb_2u_lib.s9s_mb_2u(sch_1):page440_i214@pure_quanta.q_res(chips)';

PART_NAME
 PR110 'Q_RES_0402LF-0,5%,1/16W,CHIP,CA':;

SECTION_NUMBER 1
 '@S9S_MB_2U_LIB.S9S_MB_2U(SCH_1):PAGE440_I215@PURE_QUANTA.Q_RES(CHIPS)':
 C_PATH='@s9s_mb_2u_lib.s9s_mb_2u(sch_1):page440_i215@pure_quanta.q_res(chips)';

PART_NAME
 PR109 'Q_RES_0402LF-1K,1%,1/16W,CHIP,A':;

SECTION_NUMBER 1
 '@S9S_MB_2U_LIB.S9S_MB_2U(SCH_1):PAGE440_I216@PURE_QUANTA.Q_RES(CHIPS)':
 C_PATH='@s9s_mb_2u_lib.s9s_mb_2u(sch_1):page440_i216@pure_quanta.q_res(chips)';

PART_NAME
 PR108 'Q_RES_0402LF-0,5%,1/16W,CHIP,CA':;

SECTION_NUMBER 1
 '@S9S_MB_2U_LIB.S9S_MB_2U(SCH_1):PAGE440_I314@PURE_QUANTA.Q_RES(CHIPS)':
 C_PATH='@s9s_mb_2u_lib.s9s_mb_2u(sch_1):page440_i314@pure_quanta.q_res(chips)';

PART_NAME
 PR107 'Q_RES_0402LF-0,5%,1/16W,CHIP,CA':;

SECTION_NUMBER 1
 '@S9S_MB_2U_LIB.S9S_MB_2U(SCH_1):PAGE440_I320@PURE_QUANTA.Q_RES(CHIPS)':
 C_PATH='@s9s_mb_2u_lib.s9s_mb_2u(sch_1):page440_i320@pure_quanta.q_res(chips)';

PART_NAME
 PR106 'Q_RES_R0402LF-887,1%,1/16W,CHIA':;

SECTION_NUMBER 1
 '@S9S_MB_2U_LIB.S9S_MB_2U(SCH_1):PAGE440_I323@PURE_QUANTA.Q_RES(CHIPS)':
 C_PATH='@s9s_mb_2u_lib.s9s_mb_2u(sch_1):page440_i323@pure_quanta.q_res(chips)',
 VAR_0_ONSEMI='VALUE|4.12K|TOLERANCE|1%|WATTAGE|1/16W|PACK_TYPE|0402LF|MATERIAL|~
CHIP|PART_NUMBER|CS24122FB17|STANDARD|End of Design|LIFECYCLE|Comp-Approve|PART_~
NUMBER|CS24122FB17|JEDEC_TYPE|R0402|ALT_SYMBOLS|(R0402-0201)|VALUE|4.12K|TOL|1%|~
WATTAGE|1/16W|CLASS|DISCRETE|DESCRIPTION|RES CHIP 4.12K 1/16W +-1%(0402)|COMPONE~
NT_TYPE|CHIP0402|LEAD_LENGTH||DFM_EXCLUSION||DAY|20110805|VARIANT_DEVICE_TYPE|Q_~
RES-4.12K,1%,1/16W,0402LF,CH',
 CDSVAR_REPCELL_ONSEMI='pure_quanta|Q_res';

PART_NAME
 PR105 'Q_RES_0402LF-28K,1%,1/16W,EMPTA':;

SECTION_NUMBER 1
 '@S9S_MB_2U_LIB.S9S_MB_2U(SCH_1):PAGE440_I322@PURE_QUANTA.Q_RES(CHIPS)':
 C_PATH='@s9s_mb_2u_lib.s9s_mb_2u(sch_1):page440_i322@pure_quanta.q_res(chips)';

PART_NAME
 PJ46 'Q_SHORT_SM-EMPTY,SHORT6':;

SECTION_NUMBER 1
 '@S9S_MB_2U_LIB.S9S_MB_2U(SCH_1):PAGE440_I262@PURE_QUANTA.Q_SHORT(CHIPS)':
 C_PATH='@s9s_mb_2u_lib.s9s_mb_2u(sch_1):page440_i262@pure_quanta.q_short(chips)';

PART_NAME
 PJ45 'Q_SHORT_SM-EMPTY,SHORT6':;

SECTION_NUMBER 1
 '@S9S_MB_2U_LIB.S9S_MB_2U(SCH_1):PAGE440_I253@PURE_QUANTA.Q_SHORT(CHIPS)':
 C_PATH='@s9s_mb_2u_lib.s9s_mb_2u(sch_1):page440_i253@pure_quanta.q_short(chips)';

PART_NAME
 PC1372 'Q_CAP_C0402-1UF,16V,10%,X6S,CHA':;

SECTION_NUMBER 1
 '@S9S_MB_2U_LIB.S9S_MB_2U(SCH_1):PAGE440_I339@PURE_QUANTA.Q_CAP(CHIPS)':
 C_PATH='@s9s_mb_2u_lib.s9s_mb_2u(sch_1):page440_i339@pure_quanta.q_cap(chips)';

PART_NAME
 PC1271 'Q_CAP_0402-470PF,50V,10%,X7R,TA':;

SECTION_NUMBER 1
 '@S9S_MB_2U_LIB.S9S_MB_2U(SCH_1):PAGE440_I390@PURE_QUANTA.Q_CAP(CHIPS)':
 C_PATH='@s9s_mb_2u_lib.s9s_mb_2u(sch_1):page440_i390@pure_quanta.q_cap(chips)',
 VAR_0_ONSEMI='VALUE|2200PF|VOLTAGE|50V|TOLERANCE|10%|PACK_TYPE|C0402|MATERIAL|X~
7R|PART_NUMBER|CH2226K1B06|STANDARD||LIFECYCLE||ASS_PART||PART_NUMBER|CH2226K1B0~
6|JEDEC_TYPE|C0402|ALT_SYMBOLS|(C0402-0201)|VALUE|2200PF|RATED_VOLTAGE|50V|TOL|1~
0%|CLASS|DISCRETE|DESCRIPTION|CAP CHIP 2200P 50V(+-10%,X7R,0402)MUR|COMPONENT_TY~
PE|CHIP0402|LEAD_LENGTH||LPID||DATE|20150614|VARIANT_DEVICE_TYPE|Q_CAP-2200PF,50~
V,10%,C0402,X7R',
 CDSVAR_REPCELL_ONSEMI='pure_quanta|Q_cap';

PART_NAME
 PC225 'Q_CAP_C0402-1UF,16V,10%,X6S,CHA':;

SECTION_NUMBER 1
 '@S9S_MB_2U_LIB.S9S_MB_2U(SCH_1):PAGE440_I334@PURE_QUANTA.Q_CAP(CHIPS)':
 C_PATH='@s9s_mb_2u_lib.s9s_mb_2u(sch_1):page440_i334@pure_quanta.q_cap(chips)';

PART_NAME
 PC224 'Q_CAP_0402-4.7UF,6.3V,20%,X6S,A':;

SECTION_NUMBER 1
 '@S9S_MB_2U_LIB.S9S_MB_2U(SCH_1):PAGE440_I340@PURE_QUANTA.Q_CAP(CHIPS)':
 C_PATH='@s9s_mb_2u_lib.s9s_mb_2u(sch_1):page440_i340@pure_quanta.q_cap(chips)',
 VAR_0_ONSEMI='VALUE|4.7UF|VOLTAGE|6.3V|TOLERANCE|20%|PACK_TYPE|0402|MATERIAL|EM~
PTY|PART_NUMBER|CH5471MEB01|STANDARD||LIFECYCLE||ASS_PART||PART_NUMBER|CH5471MEB~
01|JEDEC_TYPE|C0402|ALT_SYMBOLS|(C0402_OCTAGON,C0402_OCTAGONXA,C0402-0201)|VALUE~
|NA|RATED_VOLTAGE|6.3V|TOL|20%|CLASS|IO|DESCRIPTION|CAP CHIP 4.7UF 6.3V(+-20%,X6~
S,0402)|COMPONENT_TYPE|CHIP0402|LEAD_LENGTH||LPID||DATE|20151211|VARIANT_DEVICE_~
TYPE|Q_CAP-4.7UF,6.3V,20%,0402,EMPT',
 CDSVAR_REPCELL_ONSEMI='pure_quanta|Q_cap';

PART_NAME
 PC223 'Q_CAP_C0402-100NF,50V,10%,EMPTA':;

SECTION_NUMBER 1
 '@S9S_MB_2U_LIB.S9S_MB_2U(SCH_1):PAGE440_I333@PURE_QUANTA.Q_CAP(CHIPS)':
 C_PATH='@s9s_mb_2u_lib.s9s_mb_2u(sch_1):page440_i333@pure_quanta.q_cap(chips)';

PART_NAME
 PC222 'Q_CAP_0402-470PF,50V,10%,X7R,TA':;

SECTION_NUMBER 1
 '@S9S_MB_2U_LIB.S9S_MB_2U(SCH_1):PAGE440_I368@PURE_QUANTA.Q_CAP(CHIPS)':
 C_PATH='@s9s_mb_2u_lib.s9s_mb_2u(sch_1):page440_i368@pure_quanta.q_cap(chips)',
 VAR_0_ONSEMI='VALUE|2200PF|VOLTAGE|50V|TOLERANCE|10%|PACK_TYPE|C0402|MATERIAL|X~
7R|PART_NUMBER|CH2226K1B06|STANDARD||LIFECYCLE||ASS_PART||PART_NUMBER|CH2226K1B0~
6|JEDEC_TYPE|C0402|ALT_SYMBOLS|(C0402-0201)|VALUE|2200PF|RATED_VOLTAGE|50V|TOL|1~
0%|CLASS|DISCRETE|DESCRIPTION|CAP CHIP 2200P 50V(+-10%,X7R,0402)MUR|COMPONENT_TY~
PE|CHIP0402|LEAD_LENGTH||LPID||DATE|20150614|VARIANT_DEVICE_TYPE|Q_CAP-2200PF,50~
V,10%,C0402,X7R',
 CDSVAR_REPCELL_ONSEMI='pure_quanta|Q_cap';

PART_NAME
 PC221 'Q_CAP_C0402-1UF,16V,10%,X6S,CHA':;

SECTION_NUMBER 1
 '@S9S_MB_2U_LIB.S9S_MB_2U(SCH_1):PAGE440_I313@PURE_QUANTA.Q_CAP(CHIPS)':
 C_PATH='@s9s_mb_2u_lib.s9s_mb_2u(sch_1):page440_i313@pure_quanta.q_cap(chips)';

PART_NAME
 PC220 'Q_CAP_0402-1000PF,50V,5%,EMPTYA':;

SECTION_NUMBER 1
 '@S9S_MB_2U_LIB.S9S_MB_2U(SCH_1):PAGE440_I307@PURE_QUANTA.Q_CAP(CHIPS)':
 C_PATH='@s9s_mb_2u_lib.s9s_mb_2u(sch_1):page440_i307@pure_quanta.q_cap(chips)';

PART_NAME
 PC219 'Q_CAP_0402-1000PF,50V,5%,X7R,TA':;

SECTION_NUMBER 1
 '@S9S_MB_2U_LIB.S9S_MB_2U(SCH_1):PAGE440_I302@PURE_QUANTA.Q_CAP(CHIPS)':
 C_PATH='@s9s_mb_2u_lib.s9s_mb_2u(sch_1):page440_i302@pure_quanta.q_cap(chips)';

PART_NAME
 PC218 'Q_CAP_0402-1000PF,50V,5%,EMPTYA':;

SECTION_NUMBER 1
 '@S9S_MB_2U_LIB.S9S_MB_2U(SCH_1):PAGE440_I219@PURE_QUANTA.Q_CAP(CHIPS)':
 C_PATH='@s9s_mb_2u_lib.s9s_mb_2u(sch_1):page440_i219@pure_quanta.q_cap(chips)';

PART_NAME
 PC217 'Q_CAP_0402-1000PF,50V,5%,X7R,TA':;

SECTION_NUMBER 1
 '@S9S_MB_2U_LIB.S9S_MB_2U(SCH_1):PAGE440_I218@PURE_QUANTA.Q_CAP(CHIPS)':
 C_PATH='@s9s_mb_2u_lib.s9s_mb_2u(sch_1):page440_i218@pure_quanta.q_cap(chips)';

PART_NAME
 PC216 'Q_CAP_0402-3300PF,50V,10%,X7R,A':;

SECTION_NUMBER 1
 '@S9S_MB_2U_LIB.S9S_MB_2U(SCH_1):PAGE440_I263@PURE_QUANTA.Q_CAP(CHIPS)':
 C_PATH='@s9s_mb_2u_lib.s9s_mb_2u(sch_1):page440_i263@pure_quanta.q_cap(chips)',
 VAR_0_ONSEMI='VALUE|1NF|VOLTAGE|50V|TOLERANCE|10%|PACK_TYPE|0402|MATERIAL|X7R|P~
ART_NUMBER|CH21006KB16|STANDARD||LIFECYCLE||ASS_PART||PART_NUMBER|CH21006KB16|JE~
DEC_TYPE|C0402|ALT_SYMBOLS|(C0402-0201)|VALUE|1NF|RATED_VOLTAGE|50V|TOL|10%|CLAS~
S|DISCRETE|DESCRIPTION|CAP CHIP 1N 50V(+-10%,X7R,0402)EP|COMPONENT_TYPE|CHIP0402~
|LEAD_LENGTH||LPID||DATE|20100811|VARIANT_DEVICE_TYPE|Q_CAP-1NF,50V,10%,0402,X7R~
,CH2',
 CDSVAR_REPCELL_ONSEMI='pure_quanta|Q_cap';

PART_NAME
 PC215 'Q_CAP_0402-3300PF,50V,10%,X7R,A':;

SECTION_NUMBER 1
 '@S9S_MB_2U_LIB.S9S_MB_2U(SCH_1):PAGE440_I254@PURE_QUANTA.Q_CAP(CHIPS)':
 C_PATH='@s9s_mb_2u_lib.s9s_mb_2u(sch_1):page440_i254@pure_quanta.q_cap(chips)',
 VAR_0_ONSEMI='VALUE|1NF|VOLTAGE|50V|TOLERANCE|10%|PACK_TYPE|0402|MATERIAL|X7R|P~
ART_NUMBER|CH21006KB16|STANDARD||LIFECYCLE||ASS_PART||PART_NUMBER|CH21006KB16|JE~
DEC_TYPE|C0402|ALT_SYMBOLS|(C0402-0201)|VALUE|1NF|RATED_VOLTAGE|50V|TOL|10%|CLAS~
S|DISCRETE|DESCRIPTION|CAP CHIP 1N 50V(+-10%,X7R,0402)EP|COMPONENT_TYPE|CHIP0402~
|LEAD_LENGTH||LPID||DATE|20100811|VARIANT_DEVICE_TYPE|Q_CAP-1NF,50V,10%,0402,X7R~
,CH2',
 CDSVAR_REPCELL_ONSEMI='pure_quanta|Q_cap';

PART_NAME
 PC214 'Q_CAP_C0402-1UF,16V,10%,X6S,CHA':;

SECTION_NUMBER 1
 '@S9S_MB_2U_LIB.S9S_MB_2U(SCH_1):PAGE440_I318@PURE_QUANTA.Q_CAP(CHIPS)':
 C_PATH='@s9s_mb_2u_lib.s9s_mb_2u(sch_1):page440_i318@pure_quanta.q_cap(chips)';

PART_NAME
 PU31_P1_1 'ISL99390FRZTR5935-ISL99390FRZ-A':;

SECTION_NUMBER 1
 '@S9S_MB_2U_LIB.S9S_MB_2U(SCH_1):PAGE435_I21@PURE_QUANTA.ISL99390FRZTR5935(CHIPS)':
 C_PATH='@s9s_mb_2u_lib.s9s_mb_2u(sch_1):page435_i21@pure_quanta.isl99390frztr5935~
(chips)',
 VAR_0_ONSEMI='VAR_REPLACED|ISL99390FRZTR5935|VAR_PARTNAME|FDMF5085|VALUE|FDMF50~
85|PART_TYPE|SMLF|MATERIAL|IC|PART_NUMBER|AL005085000|STANDARD||LIFECYCLE||PART_~
NUMBER|AL005085000|JEDEC_TYPE|PQFN21_6X5XB|DESCRIPTION|IC OTHER(39P) FDMF5085(PQ~
FN)|MANUFTR|ONS|MANUF_PN|FDMF5085|RD_CMPLS_LVL|EP(V1)|CMPLS_LVL||FROM_PJ|S9S-KIM~
I|CLASS|IC|DIP_SMD||DATA|ONS_FDMF5085.pdf|EE_CHECK_LIST||FP_ECN||PSL||CREATOR||S~
TATUS||MSD|NA|ESD_CDM|NA|ESD_HBM|NA|ESD_MM|NA|PIN_LENGTH_SHORT_PIN|0 MILS|PIN_LE~
NGTH_LONG_PIN|0 MILS|CREATEDAY|20200423|VARIANT_DEVICE_TYPE|FDMF5085-FDMF5085,SM~
LF,IC,AL00',
 CDSVAR_REPCELL_ONSEMI='pure_quanta|fdmf5085';

PART_NAME
 PU30_P1_2 'ISL99390FRZTR5935-ISL99390FRZ-A':;

SECTION_NUMBER 1
 '@S9S_MB_2U_LIB.S9S_MB_2U(SCH_1):PAGE435_I79@PURE_QUANTA.ISL99390FRZTR5935(CHIPS)':
 C_PATH='@s9s_mb_2u_lib.s9s_mb_2u(sch_1):page435_i79@pure_quanta.isl99390frztr5935~
(chips)',
 VAR_0_ONSEMI='VAR_REPLACED|ISL99390FRZTR5935|VAR_PARTNAME|FDMF5085|VALUE|FDMF50~
85|PART_TYPE|SMLF|MATERIAL|IC|PART_NUMBER|AL005085000|STANDARD||LIFECYCLE||PART_~
NUMBER|AL005085000|JEDEC_TYPE|PQFN21_6X5XB|DESCRIPTION|IC OTHER(39P) FDMF5085(PQ~
FN)|MANUFTR|ONS|MANUF_PN|FDMF5085|RD_CMPLS_LVL|EP(V1)|CMPLS_LVL||FROM_PJ|S9S-KIM~
I|CLASS|IC|DIP_SMD||DATA|ONS_FDMF5085.pdf|EE_CHECK_LIST||FP_ECN||PSL||CREATOR||S~
TATUS||MSD|NA|ESD_CDM|NA|ESD_HBM|NA|ESD_MM|NA|PIN_LENGTH_SHORT_PIN|0 MILS|PIN_LE~
NGTH_LONG_PIN|0 MILS|CREATEDAY|20200423|VARIANT_DEVICE_TYPE|FDMF5085-FDMF5085,SM~
LF,IC,AL00',
 CDSVAR_REPCELL_ONSEMI='pure_quanta|fdmf5085';

PART_NAME
 PR1767 'Q_RES_0402LF-3.3,1%,1/16W,CHIPA':;

SECTION_NUMBER 1
 '@S9S_MB_2U_LIB.S9S_MB_2U(SCH_1):PAGE435_I154@PURE_QUANTA.Q_RES(CHIPS)':
 C_PATH='@s9s_mb_2u_lib.s9s_mb_2u(sch_1):page435_i154@pure_quanta.q_res(chips)',
 CDSVAR_REPCELL_ONSEMI='pure_quanta|Q_res',
 VAR_0_ONSEMI='VALUE|5.1|TOLERANCE|5%|WATTAGE|1/16W|PACK_TYPE|0402LF|MATERIAL|CH~
IP|PART_NUMBER|CS-5102JB03|STANDARD|End of Design|LIFECYCLE|Comp-Approve|PART_NU~
MBER|CS-5102JB03|JEDEC_TYPE|R0402|ALT_SYMBOLS|(R0402-0201)|VALUE|5.1|TOL|5%|WATT~
AGE|1/16W |CLASS|DISCRETE|DESCRIPTION|RES CHIP 5.1 1/16W +-5%(0402)|COMPONENT_TY~
PE|CHIP0402|LEAD_LENGTH||DFM_EXCLUSION||DAY|20100827|VARIANT_DEVICE_TYPE|Q_RES-5~
.1,5%,1/16W,0402LF,CHIP';

PART_NAME
 PR1766 'Q_RES_0402LF-3.3,1%,1/16W,CHIPA':;

SECTION_NUMBER 1
 '@S9S_MB_2U_LIB.S9S_MB_2U(SCH_1):PAGE435_I156@PURE_QUANTA.Q_RES(CHIPS)':
 C_PATH='@s9s_mb_2u_lib.s9s_mb_2u(sch_1):page435_i156@pure_quanta.q_res(chips)',
 CDSVAR_REPCELL_ONSEMI='pure_quanta|Q_res',
 VAR_0_ONSEMI='VALUE|5.1|TOLERANCE|5%|WATTAGE|1/16W|PACK_TYPE|0402LF|MATERIAL|CH~
IP|PART_NUMBER|CS-5102JB03|STANDARD|End of Design|LIFECYCLE|Comp-Approve|PART_NU~
MBER|CS-5102JB03|JEDEC_TYPE|R0402|ALT_SYMBOLS|(R0402-0201)|VALUE|5.1|TOL|5%|WATT~
AGE|1/16W |CLASS|DISCRETE|DESCRIPTION|RES CHIP 5.1 1/16W +-5%(0402)|COMPONENT_TY~
PE|CHIP0402|LEAD_LENGTH||DFM_EXCLUSION||DAY|20100827|VARIANT_DEVICE_TYPE|Q_RES-5~
.1,5%,1/16W,0402LF,CHIP';

PART_NAME
 PR330 'Q_RES_0402LF-0,5%,1/16W,CHIP,CA':;

SECTION_NUMBER 1
 '@S9S_MB_2U_LIB.S9S_MB_2U(SCH_1):PAGE435_I165@PURE_QUANTA.Q_RES(CHIPS)':
 C_PATH='@s9s_mb_2u_lib.s9s_mb_2u(sch_1):page435_i165@pure_quanta.q_res(chips)',
 CDSVAR_REPCELL_ONSEMI='pure_quanta|Q_res',
 VAR_0_ONSEMI='VALUE|0|TOLERANCE|5%|WATTAGE|1/16W|PACK_TYPE|0402LF|MATERIAL|EMPT~
Y|PART_NUMBER|CS00002JB38|STANDARD|End of Design|LIFECYCLE|Comp-Approve|PART_NUM~
BER|CS00002JB38|JEDEC_TYPE|R0402|ALT_SYMBOLS|(R0402-0201)|VALUE|0|TOL|5%|WATTAGE~
|1/16W|CLASS|IO|DESCRIPTION|RESISTOR CHIP 0 1/16W +-5%(0402)|COMPONENT_TYPE|CHIP~
0402|LEAD_LENGTH||DFM_EXCLUSION||DAY|20100618|VARIANT_DEVICE_TYPE|Q_RES-0,5%,1/1~
6W,0402LF,EMPTY,';

PART_NAME
 PR329 'Q_RES_0402LF-0,5%,1/16W,CHIP,CA':;

SECTION_NUMBER 1
 '@S9S_MB_2U_LIB.S9S_MB_2U(SCH_1):PAGE435_I164@PURE_QUANTA.Q_RES(CHIPS)':
 C_PATH='@s9s_mb_2u_lib.s9s_mb_2u(sch_1):page435_i164@pure_quanta.q_res(chips)',
 CDSVAR_REPCELL_ONSEMI='pure_quanta|Q_res',
 VAR_0_ONSEMI='VALUE|0|TOLERANCE|5%|WATTAGE|1/16W|PACK_TYPE|0402LF|MATERIAL|EMPT~
Y|PART_NUMBER|CS00002JB38|STANDARD|End of Design|LIFECYCLE|Comp-Approve|PART_NUM~
BER|CS00002JB38|JEDEC_TYPE|R0402|ALT_SYMBOLS|(R0402-0201)|VALUE|0|TOL|5%|WATTAGE~
|1/16W|CLASS|IO|DESCRIPTION|RESISTOR CHIP 0 1/16W +-5%(0402)|COMPONENT_TYPE|CHIP~
0402|LEAD_LENGTH||DFM_EXCLUSION||DAY|20100618|VARIANT_DEVICE_TYPE|Q_RES-0,5%,1/1~
6W,0402LF,EMPTY,';

PART_NAME
 PR328 'Q_RES_0402LF-2.2,1%,1/16W,CHIPA':;

SECTION_NUMBER 1
 '@S9S_MB_2U_LIB.S9S_MB_2U(SCH_1):PAGE435_I100@PURE_QUANTA.Q_RES(CHIPS)':
 C_PATH='@s9s_mb_2u_lib.s9s_mb_2u(sch_1):page435_i100@pure_quanta.q_res(chips)';

PART_NAME
 PR327 'Q_RES_0402LF-2.2,1%,1/16W,CHIPA':;

SECTION_NUMBER 1
 '@S9S_MB_2U_LIB.S9S_MB_2U(SCH_1):PAGE435_I107@PURE_QUANTA.Q_RES(CHIPS)':
 C_PATH='@s9s_mb_2u_lib.s9s_mb_2u(sch_1):page435_i107@pure_quanta.q_res(chips)';

PART_NAME
 PR326 'Q_RES_0402LF-8.87K,1%,1/16W,EMA':;

SECTION_NUMBER 1
 '@S9S_MB_2U_LIB.S9S_MB_2U(SCH_1):PAGE435_I93@PURE_QUANTA.Q_RES(CHIPS)':
 C_PATH='@s9s_mb_2u_lib.s9s_mb_2u(sch_1):page435_i93@pure_quanta.q_res(chips)';

PART_NAME
 PR325 'Q_RES_0402LF-8.87K,1%,1/16W,EMA':;

SECTION_NUMBER 1
 '@S9S_MB_2U_LIB.S9S_MB_2U(SCH_1):PAGE435_I113@PURE_QUANTA.Q_RES(CHIPS)':
 C_PATH='@s9s_mb_2u_lib.s9s_mb_2u(sch_1):page435_i113@pure_quanta.q_res(chips)';

PART_NAME
 PL32 'Q_INDUCTOR_SMLF-50NH/148A,IND,A':;

SECTION_NUMBER 1
 '@S9S_MB_2U_LIB.S9S_MB_2U(SCH_1):PAGE435_I72@PURE_QUANTA.Q_INDUCTOR(CHIPS)':
 C_PATH='@s9s_mb_a_lib.s9s_mb_a(sch_1):page435_i72@pure_quanta.q_inductor(chips)~
';

PART_NAME
 PL31 'Q_INDUCTOR_SMLF-130NH/106A,INDA':;

SECTION_NUMBER 1
 '@S9S_MB_2U_LIB.S9S_MB_2U(SCH_1):PAGE435_I40@PURE_QUANTA.Q_INDUCTOR(CHIPS)':
 C_PATH='@s9s_mb_a_lib.s9s_mb_a(sch_1):page435_i40@pure_quanta.q_inductor(chips)~
';

PART_NAME
 PL30 'Q_INDUCTOR_SMLF-130NH/106A,INDA':;

SECTION_NUMBER 1
 '@S9S_MB_2U_LIB.S9S_MB_2U(SCH_1):PAGE435_I128@PURE_QUANTA.Q_INDUCTOR(CHIPS)':
 C_PATH='@s9s_mb_2u_lib.s9s_mb_2u(sch_1):page435_i128@pure_quanta.q_inductor(chips~
)';

PART_NAME
 PC1990 'Q_CAPP_SMLF-470UF,2.5V,20%,POSA':;

SECTION_NUMBER 1
 '@S9S_MB_2U_LIB.S9S_MB_2U(SCH_1):PAGE435_I163@PURE_QUANTA.Q_CAPP(CHIPS)':
 C_PATH='@s9s_mb_2u_lib.s9s_mb_2u(sch_1):page435_i163@pure_quanta.q_capp(chips)';

PART_NAME
 PC1339 'Q_CAP_0402-0.1UF,25V,10%,X7R,CA':;

SECTION_NUMBER 1
 '@S9S_MB_2U_LIB.S9S_MB_2U(SCH_1):PAGE435_I159@PURE_QUANTA.Q_CAP(CHIPS)':
 C_PATH='@s9s_mb_2u_lib.s9s_mb_2u(sch_1):page435_i159@pure_quanta.q_cap(chips)',
 CDSVAR_REPCELL_ONSEMI='pure_quanta|Q_cap',
 VAR_0_ONSEMI='VALUE|0.1UF|VOLTAGE|25V|TOLERANCE|10%|PACK_TYPE|0402|MATERIAL|EMP~
TY|PART_NUMBER|CH4104K1B00|STANDARD||LIFECYCLE||ASS_PART||PART_NUMBER|CH4104K1B0~
0|JEDEC_TYPE|C0402|ALT_SYMBOLS|(C0402_OCTAGONXA,C0402-0201)|VALUE|NA|RATED_VOLTA~
GE|25V|TOL|10%|CLASS|IO|DESCRIPTION|CAP CHIP 0.1U 25V(+-10%,X7R,0402)|COMPONENT_~
TYPE|CHIP0402|LEAD_LENGTH||LPID||DATE|20160113|VARIANT_DEVICE_TYPE|Q_CAP-0.1UF,2~
5V,10%,0402,EMPTY';

PART_NAME
 PC1338 'Q_CAP_0402-0.1UF,25V,10%,X7R,CA':;

SECTION_NUMBER 1
 '@S9S_MB_2U_LIB.S9S_MB_2U(SCH_1):PAGE435_I161@PURE_QUANTA.Q_CAP(CHIPS)':
 C_PATH='@s9s_mb_2u_lib.s9s_mb_2u(sch_1):page435_i161@pure_quanta.q_cap(chips)',
 CDSVAR_REPCELL_ONSEMI='pure_quanta|Q_cap',
 VAR_0_ONSEMI='VALUE|0.1UF|VOLTAGE|25V|TOLERANCE|10%|PACK_TYPE|0402|MATERIAL|EMP~
TY|PART_NUMBER|CH4104K1B00|STANDARD||LIFECYCLE||ASS_PART||PART_NUMBER|CH4104K1B0~
0|JEDEC_TYPE|C0402|ALT_SYMBOLS|(C0402_OCTAGONXA,C0402-0201)|VALUE|NA|RATED_VOLTA~
GE|25V|TOL|10%|CLASS|IO|DESCRIPTION|CAP CHIP 0.1U 25V(+-10%,X7R,0402)|COMPONENT_~
TYPE|CHIP0402|LEAD_LENGTH||LPID||DATE|20160113|VARIANT_DEVICE_TYPE|Q_CAP-0.1UF,2~
5V,10%,0402,EMPTY';

PART_NAME
 PC590 'Q_CAPP_SMLF-470UF,2.5V,20%,EMPA':;

SECTION_NUMBER 1
 '@S9S_MB_2U_LIB.S9S_MB_2U(SCH_1):PAGE435_I60@PURE_QUANTA.Q_CAPP(CHIPS)':
 C_PATH='@s9s_mb_2u_lib.s9s_mb_2u(sch_1):page435_i60@pure_quanta.q_capp(chips)';

PART_NAME
 PC589 'Q_CAPP_RDLF-560UF,2.5V,20%,ALUA':;

SECTION_NUMBER 1
 '@S9S_MB_2U_LIB.S9S_MB_2U(SCH_1):PAGE435_I66@PURE_QUANTA.Q_CAPP(CHIPS)':
 C_PATH='@s9s_mb_2u_lib.s9s_mb_2u(sch_1):page435_i66@pure_quanta.q_capp(chips)';

PART_NAME
 PC588 'Q_CAPP_THLF-270UF,16V,20%,OSCOA':;

SECTION_NUMBER 1
 '@S9S_MB_2U_LIB.S9S_MB_2U(SCH_1):PAGE435_I77@PURE_QUANTA.Q_CAPP(CHIPS)':
 C_PATH='@s9s_mb_2u_lib.s9s_mb_2u(sch_1):page435_i77@pure_quanta.q_capp(chips)';

PART_NAME
 PC587 'Q_CAPP_SMLF-470UF,2.5V,20%,POSA':;

SECTION_NUMBER 1
 '@S9S_MB_2U_LIB.S9S_MB_2U(SCH_1):PAGE435_I59@PURE_QUANTA.Q_CAPP(CHIPS)':
 C_PATH='@s9s_mb_2u_lib.s9s_mb_2u(sch_1):page435_i59@pure_quanta.q_capp(chips)';

PART_NAME
 PC586 'Q_CAPP_RDLF-560UF,2.5V,20%,ALUA':;

SECTION_NUMBER 1
 '@S9S_MB_2U_LIB.S9S_MB_2U(SCH_1):PAGE435_I65@PURE_QUANTA.Q_CAPP(CHIPS)':
 C_PATH='@s9s_mb_2u_lib.s9s_mb_2u(sch_1):page435_i65@pure_quanta.q_capp(chips)';

PART_NAME
 PC585 'Q_CAPP_THLF-270UF,16V,20%,OSCOA':;

SECTION_NUMBER 1
 '@S9S_MB_2U_LIB.S9S_MB_2U(SCH_1):PAGE435_I75@PURE_QUANTA.Q_CAPP(CHIPS)':
 C_PATH='@s9s_mb_2u_lib.s9s_mb_2u(sch_1):page435_i75@pure_quanta.q_capp(chips)';

PART_NAME
 PC583 'Q_CAPP_RDLF-560UF,2.5V,20%,ALUA':;

SECTION_NUMBER 1
 '@S9S_MB_2U_LIB.S9S_MB_2U(SCH_1):PAGE435_I63@PURE_QUANTA.Q_CAPP(CHIPS)':
 C_PATH='@s9s_mb_2u_lib.s9s_mb_2u(sch_1):page435_i63@pure_quanta.q_capp(chips)';

PART_NAME
 PC582 'Q_CAPP_THLF-270UF,16V,20%,OSCOA':;

SECTION_NUMBER 1
 '@S9S_MB_2U_LIB.S9S_MB_2U(SCH_1):PAGE435_I74@PURE_QUANTA.Q_CAPP(CHIPS)':
 C_PATH='@s9s_mb_2u_lib.s9s_mb_2u(sch_1):page435_i74@pure_quanta.q_capp(chips)';

PART_NAME
 PC580 'Q_CAPP_RDLF-560UF,2.5V,20%,ALUA':;

SECTION_NUMBER 1
 '@S9S_MB_2U_LIB.S9S_MB_2U(SCH_1):PAGE435_I56@PURE_QUANTA.Q_CAPP(CHIPS)':
 C_PATH='@s9s_mb_2u_lib.s9s_mb_2u(sch_1):page435_i56@pure_quanta.q_capp(chips)';

PART_NAME
 PC579 'Q_CAPP_THLF-270UF,16V,20%,OSCOA':;

SECTION_NUMBER 1
 '@S9S_MB_2U_LIB.S9S_MB_2U(SCH_1):PAGE435_I73@PURE_QUANTA.Q_CAPP(CHIPS)':
 C_PATH='@s9s_mb_2u_lib.s9s_mb_2u(sch_1):page435_i73@pure_quanta.q_capp(chips)';

PART_NAME
 PC578_P1_1 'Q_CAP_0805-22UF,4V,20%,X6S,TMPA':;

SECTION_NUMBER 1
 '@S9S_MB_2U_LIB.S9S_MB_2U(SCH_1):PAGE435_I54@PURE_QUANTA.Q_CAP(CHIPS)':
 C_PATH='@s9s_mb_2u_lib.s9s_mb_2u(sch_1):page435_i54@pure_quanta.q_cap(chips)';

PART_NAME
 PC577_P1_2 'Q_CAP_0805-22UF,4V,20%,X6S,TMPA':;

SECTION_NUMBER 1
 '@S9S_MB_2U_LIB.S9S_MB_2U(SCH_1):PAGE435_I131@PURE_QUANTA.Q_CAP(CHIPS)':
 C_PATH='@s9s_mb_2u_lib.s9s_mb_2u(sch_1):page435_i131@pure_quanta.q_cap(chips)';

PART_NAME
 PC576_P1_1 'Q_CAP_0805-22UF,4V,20%,X6S,TMPA':;

SECTION_NUMBER 1
 '@S9S_MB_2U_LIB.S9S_MB_2U(SCH_1):PAGE435_I53@PURE_QUANTA.Q_CAP(CHIPS)':
 C_PATH='@s9s_mb_2u_lib.s9s_mb_2u(sch_1):page435_i53@pure_quanta.q_cap(chips)';

PART_NAME
 PC575_P1_2 'Q_CAP_0805-22UF,4V,20%,X6S,TMPA':;

SECTION_NUMBER 1
 '@S9S_MB_2U_LIB.S9S_MB_2U(SCH_1):PAGE435_I119@PURE_QUANTA.Q_CAP(CHIPS)':
 C_PATH='@s9s_mb_2u_lib.s9s_mb_2u(sch_1):page435_i119@pure_quanta.q_cap(chips)';

PART_NAME
 PC574_P1_1 'Q_CAP_C0402-1UF,16V,10%,X6S,CHA':;

SECTION_NUMBER 1
 '@S9S_MB_2U_LIB.S9S_MB_2U(SCH_1):PAGE435_I52@PURE_QUANTA.Q_CAP(CHIPS)':
 C_PATH='@s9s_mb_2u_lib.s9s_mb_2u(sch_1):page435_i52@pure_quanta.q_cap(chips)';

PART_NAME
 PC572_P1_1 'Q_CAP_C0402-100NF,50V,10%,X7R,A':;

SECTION_NUMBER 1
 '@S9S_MB_2U_LIB.S9S_MB_2U(SCH_1):PAGE435_I32@PURE_QUANTA.Q_CAP(CHIPS)':
 C_PATH='@s9s_mb_2u_lib.s9s_mb_2u(sch_1):page435_i32@pure_quanta.q_cap(chips)';

PART_NAME
 PC571_P1_1 'Q_CAP_C0805-22UF,16V,20%,X6S,CA':;

SECTION_NUMBER 1
 '@S9S_MB_2U_LIB.S9S_MB_2U(SCH_1):PAGE435_I68@PURE_QUANTA.Q_CAP(CHIPS)':
 C_PATH='@s9s_mb_2u_lib.s9s_mb_2u(sch_1):page435_i68@pure_quanta.q_cap(chips)';

PART_NAME
 PC570_P1_2 'Q_CAP_C0805-22UF,16V,20%,X6S,CA':;

SECTION_NUMBER 1
 '@S9S_MB_2U_LIB.S9S_MB_2U(SCH_1):PAGE435_I122@PURE_QUANTA.Q_CAP(CHIPS)':
 C_PATH='@s9s_mb_2u_lib.s9s_mb_2u(sch_1):page435_i122@pure_quanta.q_cap(chips)';

PART_NAME
 PC569_P1_1 'Q_CAP_C0805-22UF,16V,20%,X6S,CA':;

SECTION_NUMBER 1
 '@S9S_MB_2U_LIB.S9S_MB_2U(SCH_1):PAGE435_I42@PURE_QUANTA.Q_CAP(CHIPS)':
 C_PATH='@s9s_mb_2u_lib.s9s_mb_2u(sch_1):page435_i42@pure_quanta.q_cap(chips)';

PART_NAME
 PC568_P1_2 'Q_CAP_C0805-22UF,16V,20%,X6S,CA':;

SECTION_NUMBER 1
 '@S9S_MB_2U_LIB.S9S_MB_2U(SCH_1):PAGE435_I123@PURE_QUANTA.Q_CAP(CHIPS)':
 C_PATH='@s9s_mb_2u_lib.s9s_mb_2u(sch_1):page435_i123@pure_quanta.q_cap(chips)';

PART_NAME
 PC567_P1_1 'Q_CAP_C0805-22UF,16V,20%,X6S,CA':;

SECTION_NUMBER 1
 '@S9S_MB_2U_LIB.S9S_MB_2U(SCH_1):PAGE435_I41@PURE_QUANTA.Q_CAP(CHIPS)':
 C_PATH='@s9s_mb_2u_lib.s9s_mb_2u(sch_1):page435_i41@pure_quanta.q_cap(chips)';

PART_NAME
 PC566_P1_2 'Q_CAP_C0805-22UF,16V,20%,X6S,CA':;

SECTION_NUMBER 1
 '@S9S_MB_2U_LIB.S9S_MB_2U(SCH_1):PAGE435_I125@PURE_QUANTA.Q_CAP(CHIPS)':
 C_PATH='@s9s_mb_2u_lib.s9s_mb_2u(sch_1):page435_i125@pure_quanta.q_cap(chips)';

PART_NAME
 PC565 'Q_CAP_C0402-100NF,50V,10%,X7R,A':;

SECTION_NUMBER 1
 '@S9S_MB_2U_LIB.S9S_MB_2U(SCH_1):PAGE435_I162@PURE_QUANTA.Q_CAP(CHIPS)':
 C_PATH='@s9s_mb_2u_lib.s9s_mb_2u(sch_1):page435_i162@pure_quanta.q_cap(chips)';

PART_NAME
 PC564 'Q_CAP_C0402-100NF,50V,10%,X7R,A':;

SECTION_NUMBER 1
 '@S9S_MB_2U_LIB.S9S_MB_2U(SCH_1):PAGE435_I157@PURE_QUANTA.Q_CAP(CHIPS)':
 C_PATH='@s9s_mb_2u_lib.s9s_mb_2u(sch_1):page435_i157@pure_quanta.q_cap(chips)';

PART_NAME
 PC563_P1_1 'Q_CAP_C0402-1UF,16V,10%,X6S,CHA':;

SECTION_NUMBER 1
 '@S9S_MB_2U_LIB.S9S_MB_2U(SCH_1):PAGE435_I39@PURE_QUANTA.Q_CAP(CHIPS)':
 C_PATH='@s9s_mb_2u_lib.s9s_mb_2u(sch_1):page435_i39@pure_quanta.q_cap(chips)';

PART_NAME
 PC562_P1_2 'Q_CAP_C0402-1UF,16V,10%,X6S,CHA':;

SECTION_NUMBER 1
 '@S9S_MB_2U_LIB.S9S_MB_2U(SCH_1):PAGE435_I126@PURE_QUANTA.Q_CAP(CHIPS)':
 C_PATH='@s9s_mb_2u_lib.s9s_mb_2u(sch_1):page435_i126@pure_quanta.q_cap(chips)';

PART_NAME
 PC561_P1_1 'Q_CAP_0402-3300PF,50V,10%,X7R,A':;

SECTION_NUMBER 1
 '@S9S_MB_2U_LIB.S9S_MB_2U(SCH_1):PAGE435_I38@PURE_QUANTA.Q_CAP(CHIPS)':
 C_PATH='@s9s_mb_2u_lib.s9s_mb_2u(sch_1):page435_i38@pure_quanta.q_cap(chips)';

PART_NAME
 PC560_P1_2 'Q_CAP_0402-3300PF,50V,10%,X7R,A':;

SECTION_NUMBER 1
 '@S9S_MB_2U_LIB.S9S_MB_2U(SCH_1):PAGE435_I127@PURE_QUANTA.Q_CAP(CHIPS)':
 C_PATH='@s9s_mb_2u_lib.s9s_mb_2u(sch_1):page435_i127@pure_quanta.q_cap(chips)';

PART_NAME
 PC559_P1_1 'Q_CAP_C0402-2.2UF,10V,10%,X6S,A':;

SECTION_NUMBER 1
 '@S9S_MB_2U_LIB.S9S_MB_2U(SCH_1):PAGE435_I103@PURE_QUANTA.Q_CAP(CHIPS)':
 C_PATH='@s9s_mb_2u_lib.s9s_mb_2u(sch_1):page435_i103@pure_quanta.q_cap(chips)';

PART_NAME
 PC558_P1_2 'Q_CAP_C0402-2.2UF,10V,10%,X6S,A':;

SECTION_NUMBER 1
 '@S9S_MB_2U_LIB.S9S_MB_2U(SCH_1):PAGE435_I110@PURE_QUANTA.Q_CAP(CHIPS)':
 C_PATH='@s9s_mb_2u_lib.s9s_mb_2u(sch_1):page435_i110@pure_quanta.q_cap(chips)';

PART_NAME
 PC557 'Q_CAP_C0402-2.2UF,10V,10%,X6S,A':;

SECTION_NUMBER 1
 '@S9S_MB_2U_LIB.S9S_MB_2U(SCH_1):PAGE435_I99@PURE_QUANTA.Q_CAP(CHIPS)':
 C_PATH='@s9s_mb_2u_lib.s9s_mb_2u(sch_1):page435_i99@pure_quanta.q_cap(chips)';

PART_NAME
 PC556 'Q_CAP_C0402-2.2UF,10V,10%,X6S,A':;

SECTION_NUMBER 1
 '@S9S_MB_2U_LIB.S9S_MB_2U(SCH_1):PAGE435_I106@PURE_QUANTA.Q_CAP(CHIPS)':
 C_PATH='@s9s_mb_2u_lib.s9s_mb_2u(sch_1):page435_i106@pure_quanta.q_cap(chips)';

PART_NAME
 PC189 'Q_CAPP_SMLF-470UF,2.5V,20%,POSA':;

SECTION_NUMBER 1
 '@S9S_MB_2U_LIB.S9S_MB_2U(SCH_1):PAGE435_I153@PURE_QUANTA.Q_CAPP(CHIPS)':
 C_PATH='@s9s_mb_2u_lib.s9s_mb_2u(sch_1):page435_i153@pure_quanta.q_capp(chips)';

PART_NAME
 PU44_P0_2 'RAA2213404GNPHB0-RAA2213404GNPA':;

SECTION_NUMBER 1
 '@S9S_MB_2U_LIB.S9S_MB_2U(SCH_1):PAGE442_I183@PURE_QUANTA.RAA2213404GNPHB0(CHIPS)':
 C_PATH='@s9s_mb_2u_lib.s9s_mb_2u(sch_1):page442_i183@pure_quanta.raa2213404gnphb0~
(chips)',
 VAR_0_ONSEMI='VAR_REPLACED|RAA2213404GNPHB0|VAR_PARTNAME|FDMF5076|VALUE|FDMF507~
6|PART_TYPE|SMLF|MATERIAL|IC|PART_NUMBER|AL005076000|STANDARD||LIFECYCLE||PART_N~
UMBER|AL005076000|JEDEC_TYPE|PQFN17_TH_5X4XA|DESCRIPTION|IC OTHER(27P)FDMF5076(P~
QFN)|MANUFTR|ONS|MANUF_PN|FDMF5076|RD_CMPLS_LVL|EP(V1)|CMPLS_LVL|EP(V1)|FROM_PJ|~
S9S-KIMI|CLASS|IC|DIP_SMD||DATA|ONS_FDMF5076.pdf|EE_CHECK_LIST||FP_ECN|FDMF5076.~
msg|PSL||CREATOR||STATUS||MSD|NA|ESD_CDM|NA|ESD_HBM|NA|ESD_MM|NA|PIN_LENGTH_SHOR~
T_PIN|0 MILS|PIN_LENGTH_LONG_PIN|0 MILS|CREATEDAY|20200416|VARIANT_DEVICE_TYPE|F~
DMF5076-FDMF5076,SMLF,IC,AL00',
 CDSVAR_REPCELL_ONSEMI='pure_quanta|fdmf5076';

PART_NAME
 PU43_P0_1 'RAA2213404GNPHB0-RAA2213404GNPA':;

SECTION_NUMBER 1
 '@S9S_MB_2U_LIB.S9S_MB_2U(SCH_1):PAGE442_I241@PURE_QUANTA.RAA2213404GNPHB0(CHIPS)':
 C_PATH='@s9s_mb_2u_lib.s9s_mb_2u(sch_1):page442_i241@pure_quanta.raa2213404gnphb0~
(chips)',
 VAR_0_ONSEMI='VAR_REPLACED|RAA2213404GNPHB0|VAR_PARTNAME|FDMF5076|PART_TYPE|SML~
F|MATERIAL|IC|VALUE|FDMF5076|PART_NUMBER|AL005076000|PIN_LENGTH_LONG_PIN|0 MILS|~
MSD|NA|DESCRIPTION|IC OTHER(27P)FDMF5076(PQFN)|EE_CHECK_LIST||CLASS|IC|MANUFTR|O~
NS|ESD_MM|NA|ESD_CDM|NA|FROM_PJ|S9S-KIMI|DIP_SMD||CREATEDAY|20200416|STANDARD||P~
IN_LENGTH_SHORT_PIN|0 MILS|ESD_HBM|NA|LIFECYCLE||STATUS||PSL||RD_CMPLS_LVL|EP(V1~
)|FP_ECN|FDMF5076.msg|MANUF_PN|FDMF5076|CMPLS_LVL|EP(V1)|JEDEC_TYPE|PQFN17_TH_5X~
4XA|DATA|ONS_FDMF5076.pdf|PART_NUMBER|AL005076000|CREATOR||VARIANT_DEVICE_TYPE|F~
DMF5076',
 CDSVAR_REPCELL_ONSEMI='pure_quanta|fdmf5076';

PART_NAME
 PR1777 'Q_RES_0402LF-0,5%,1/16W,CHIP,CA':;

SECTION_NUMBER 1
 '@S9S_MB_2U_LIB.S9S_MB_2U(SCH_1):PAGE442_I228@PURE_QUANTA.Q_RES(CHIPS)':
 C_PATH='@s9s_mb_2u_lib.s9s_mb_2u(sch_1):page442_i228@pure_quanta.q_res(chips)',
 VAR_0_ONSEMI='VALUE|0|TOLERANCE|5%|WATTAGE|1/16W|PACK_TYPE|0402LF|MATERIAL|EMPT~
Y|PART_NUMBER|CS00002JB38|STANDARD|End of Design|LIFECYCLE|Comp-Approve|PART_NUM~
BER|CS00002JB38|JEDEC_TYPE|R0402|ALT_SYMBOLS|(R0402-0201)|VALUE|0|TOL|5%|WATTAGE~
|1/16W|CLASS|IO|DESCRIPTION|RESISTOR CHIP 0 1/16W +-5%(0402)|COMPONENT_TYPE|CHIP~
0402|LEAD_LENGTH||DFM_EXCLUSION||DAY|20100618|VARIANT_DEVICE_TYPE|Q_RES-0,5%,1/1~
6W,0402LF,EMPTY,',
 CDSVAR_REPCELL_ONSEMI='pure_quanta|Q_res';

PART_NAME
 PR1776 'Q_RES_0402LF-0,5%,1/16W,CHIP,CA':;

SECTION_NUMBER 1
 '@S9S_MB_2U_LIB.S9S_MB_2U(SCH_1):PAGE442_I225@PURE_QUANTA.Q_RES(CHIPS)':
 C_PATH='@s9s_mb_2u_lib.s9s_mb_2u(sch_1):page442_i225@pure_quanta.q_res(chips)',
 VAR_0_ONSEMI='VALUE|0|TOLERANCE|5%|WATTAGE|1/16W|PACK_TYPE|0402LF|MATERIAL|EMPT~
Y|PART_NUMBER|CS00002JB38|STANDARD|End of Design|LIFECYCLE|Comp-Approve|PART_NUM~
BER|CS00002JB38|JEDEC_TYPE|R0402|ALT_SYMBOLS|(R0402-0201)|VALUE|0|TOL|5%|WATTAGE~
|1/16W|CLASS|IO|DESCRIPTION|RESISTOR CHIP 0 1/16W +-5%(0402)|COMPONENT_TYPE|CHIP~
0402|LEAD_LENGTH||DFM_EXCLUSION||DAY|20100618|VARIANT_DEVICE_TYPE|Q_RES-0,5%,1/1~
6W,0402LF,EMPTY,',
 CDSVAR_REPCELL_ONSEMI='pure_quanta|Q_res';

PART_NAME
 PR1775 'Q_RES_0402LF-4.7,1%,1/16W,CHIPA':;

SECTION_NUMBER 1
 '@S9S_MB_2U_LIB.S9S_MB_2U(SCH_1):PAGE442_I223@PURE_QUANTA.Q_RES(CHIPS)':
 C_PATH='@s9s_mb_2u_lib.s9s_mb_2u(sch_1):page442_i223@pure_quanta.q_res(chips)',
 VAR_0_ONSEMI='VALUE|0|TOLERANCE|5%|WATTAGE|1/16W|PACK_TYPE|0402LF|MATERIAL|CHIP~
|PART_NUMBER|CS00002JB38|STANDARD|End of Design|LIFECYCLE|Comp-Approve|PART_NUMB~
ER|CS00002JB38|JEDEC_TYPE|R0402|ALT_SYMBOLS|(R0402-0201)|VALUE|0|TOL|5%|WATTAGE|~
1/16W|CLASS|DISCRETE|DESCRIPTION|RESISTOR CHIP 0 1/16W +-5%(0402)|COMPONENT_TYPE~
|CHIP0402|LEAD_LENGTH||DFM_EXCLUSION||DAY|20100618|VARIANT_DEVICE_TYPE|Q_RES-0,5~
%,1/16W,0402LF,CHIP,C',
 CDSVAR_REPCELL_ONSEMI='pure_quanta|Q_res';

PART_NAME
 PR1774 'Q_RES_0402LF-4.7,1%,1/16W,CHIPA':;

SECTION_NUMBER 1
 '@S9S_MB_2U_LIB.S9S_MB_2U(SCH_1):PAGE442_I221@PURE_QUANTA.Q_RES(CHIPS)':
 C_PATH='@s9s_mb_2u_lib.s9s_mb_2u(sch_1):page442_i221@pure_quanta.q_res(chips)',
 VAR_0_ONSEMI='VALUE|0|TOLERANCE|5%|WATTAGE|1/16W|PACK_TYPE|0402LF|MATERIAL|CHIP~
|PART_NUMBER|CS00002JB38|STANDARD|End of Design|LIFECYCLE|Comp-Approve|PART_NUMB~
ER|CS00002JB38|JEDEC_TYPE|R0402|ALT_SYMBOLS|(R0402-0201)|VALUE|0|TOL|5%|WATTAGE|~
1/16W|CLASS|DISCRETE|DESCRIPTION|RESISTOR CHIP 0 1/16W +-5%(0402)|COMPONENT_TYPE~
|CHIP0402|LEAD_LENGTH||DFM_EXCLUSION||DAY|20100618|VARIANT_DEVICE_TYPE|Q_RES-0,5~
%,1/16W,0402LF,CHIP,C',
 CDSVAR_REPCELL_ONSEMI='pure_quanta|Q_res';

PART_NAME
 PR1708 'Q_RES_0402LF-8.87K,1%,1/16W,EMA':;

SECTION_NUMBER 1
 '@S9S_MB_2U_LIB.S9S_MB_2U(SCH_1):PAGE442_I238@PURE_QUANTA.Q_RES(CHIPS)':
 C_PATH='@s9s_mb_2u_lib.s9s_mb_2u(sch_1):page442_i238@pure_quanta.q_res(chips)';

PART_NAME
 PR1707 'Q_RES_0402LF-8.87K,1%,1/16W,EMA':;

SECTION_NUMBER 1
 '@S9S_MB_2U_LIB.S9S_MB_2U(SCH_1):PAGE442_I239@PURE_QUANTA.Q_RES(CHIPS)':
 C_PATH='@s9s_mb_2u_lib.s9s_mb_2u(sch_1):page442_i239@pure_quanta.q_res(chips)';

PART_NAME
 PR102 'Q_RES_0402LF-2.2,1%,1/16W,CHIPA':;

SECTION_NUMBER 1
 '@S9S_MB_2U_LIB.S9S_MB_2U(SCH_1):PAGE442_I165@PURE_QUANTA.Q_RES(CHIPS)':
 C_PATH='@s9s_mb_2u_lib.s9s_mb_2u(sch_1):page442_i165@pure_quanta.q_res(chips)';

PART_NAME
 PR101 'Q_RES_0402LF-2.2,1%,1/16W,CHIPA':;

SECTION_NUMBER 1
 '@S9S_MB_2U_LIB.S9S_MB_2U(SCH_1):PAGE442_I154@PURE_QUANTA.Q_RES(CHIPS)':
 C_PATH='@s9s_mb_2u_lib.s9s_mb_2u(sch_1):page442_i154@pure_quanta.q_res(chips)';

PART_NAME
 PL6 'Q_INDUCTOR_SMLF-100NH/16A,IND,A':;

SECTION_NUMBER 1
 '@S9S_MB_2U_LIB.S9S_MB_2U(SCH_1):PAGE442_I141@PURE_QUANTA.Q_INDUCTOR(CHIPS)':
 C_PATH='@s9s_mb_2u_lib.s9s_mb_2u(sch_1):page442_i141@pure_quanta.q_inductor(chips~
)';

PART_NAME
 PL5 'Q_INDUCTOR_SMLF-130NH/95A,IND,A':;

SECTION_NUMBER 1
 '@S9S_MB_2U_LIB.S9S_MB_2U(SCH_1):PAGE442_I182@PURE_QUANTA.Q_INDUCTOR(CHIPS)':
 C_PATH='@s9s_mb_2u_lib.s9s_mb_2u(sch_1):page442_i182@pure_quanta.q_inductor(chips~
)';

PART_NAME
 PL4 'Q_INDUCTOR_SMLF-130NH/95A,IND,A':;

SECTION_NUMBER 1
 '@S9S_MB_2U_LIB.S9S_MB_2U(SCH_1):PAGE442_I150@PURE_QUANTA.Q_INDUCTOR(CHIPS)':
 C_PATH='@s9s_mb_2u_lib.s9s_mb_2u(sch_1):page442_i150@pure_quanta.q_inductor(chips~
)';

PART_NAME
 PC1579 'Q_CAPP_RDLF-560UF,2.5V,20%,ALUA':;

SECTION_NUMBER 1
 '@S9S_MB_2U_LIB.S9S_MB_2U(SCH_1):PAGE442_I213@PURE_QUANTA.Q_CAPP(CHIPS)':
 C_PATH='@s9s_mb_2u_lib.s9s_mb_2u(sch_1):page442_i213@pure_quanta.q_capp(chips)';

PART_NAME
 PC1576 'Q_CAPP_RDLF-560UF,2.5V,20%,ALUA':;

SECTION_NUMBER 1
 '@S9S_MB_2U_LIB.S9S_MB_2U(SCH_1):PAGE442_I212@PURE_QUANTA.Q_CAPP(CHIPS)':
 C_PATH='@s9s_mb_2u_lib.s9s_mb_2u(sch_1):page442_i212@pure_quanta.q_capp(chips)';

PART_NAME
 PC1575 'Q_CAPP_RDLLF-330UF,2V,35%,C_POA':;

SECTION_NUMBER 1
 '@S9S_MB_2U_LIB.S9S_MB_2U(SCH_1):PAGE442_I219@PURE_QUANTA.Q_CAPP(CHIPS)':
 C_PATH='@s9s_mb_2u_lib.s9s_mb_2u(sch_1):page442_i219@pure_quanta.q_capp(chips)';

PART_NAME
 PC1574 'Q_CAPP_RDLF-560UF,2.5V,20%,ALUA':;

SECTION_NUMBER 1
 '@S9S_MB_2U_LIB.S9S_MB_2U(SCH_1):PAGE442_I211@PURE_QUANTA.Q_CAPP(CHIPS)':
 C_PATH='@s9s_mb_2u_lib.s9s_mb_2u(sch_1):page442_i211@pure_quanta.q_capp(chips)';

PART_NAME
 PC1573 'Q_CAPP_RDLLF-330UF,2V,35%,C_POA':;

SECTION_NUMBER 1
 '@S9S_MB_2U_LIB.S9S_MB_2U(SCH_1):PAGE442_I214@PURE_QUANTA.Q_CAPP(CHIPS)':
 C_PATH='@s9s_mb_2u_lib.s9s_mb_2u(sch_1):page442_i214@pure_quanta.q_capp(chips)';

PART_NAME
 PC1347 'Q_CAP_0402-0.1UF,25V,10%,X7R,CA':;

SECTION_NUMBER 1
 '@S9S_MB_2U_LIB.S9S_MB_2U(SCH_1):PAGE442_I231@PURE_QUANTA.Q_CAP(CHIPS)':
 C_PATH='@s9s_mb_2u_lib.s9s_mb_2u(sch_1):page442_i231@pure_quanta.q_cap(chips)',
 VAR_0_ONSEMI='VALUE|0.1UF|VOLTAGE|25V|TOLERANCE|10%|PACK_TYPE|0402|MATERIAL|EMP~
TY|PART_NUMBER|CH4104K1B00|STANDARD||LIFECYCLE||ASS_PART||PART_NUMBER|CH4104K1B0~
0|JEDEC_TYPE|C0402|ALT_SYMBOLS|(C0402_OCTAGONXA,C0402-0201)|VALUE|NA|RATED_VOLTA~
GE|25V|TOL|10%|CLASS|IO|DESCRIPTION|CAP CHIP 0.1U 25V(+-10%,X7R,0402)|COMPONENT_~
TYPE|CHIP0402|LEAD_LENGTH||LPID||DATE|20160113|VARIANT_DEVICE_TYPE|Q_CAP-0.1UF,2~
5V,10%,0402,EMPTY',
 CDSVAR_REPCELL_ONSEMI='pure_quanta|Q_cap';

PART_NAME
 PC1346 'Q_CAP_0402-0.1UF,25V,10%,X7R,CA':;

SECTION_NUMBER 1
 '@S9S_MB_2U_LIB.S9S_MB_2U(SCH_1):PAGE442_I233@PURE_QUANTA.Q_CAP(CHIPS)':
 C_PATH='@s9s_mb_2u_lib.s9s_mb_2u(sch_1):page442_i233@pure_quanta.q_cap(chips)',
 VAR_0_ONSEMI='VALUE|0.1UF|VOLTAGE|25V|TOLERANCE|10%|PACK_TYPE|0402|MATERIAL|EMP~
TY|PART_NUMBER|CH4104K1B00|STANDARD||LIFECYCLE||ASS_PART||PART_NUMBER|CH4104K1B0~
0|JEDEC_TYPE|C0402|ALT_SYMBOLS|(C0402_OCTAGONXA,C0402-0201)|VALUE|NA|RATED_VOLTA~
GE|25V|TOL|10%|CLASS|IO|DESCRIPTION|CAP CHIP 0.1U 25V(+-10%,X7R,0402)|COMPONENT_~
TYPE|CHIP0402|LEAD_LENGTH||LPID||DATE|20160113|VARIANT_DEVICE_TYPE|Q_CAP-0.1UF,2~
5V,10%,0402,EMPTY',
 CDSVAR_REPCELL_ONSEMI='pure_quanta|Q_cap';

PART_NAME
 PC208 'Q_CAPP_THLF-270UF,16V,20%,OSCOA':;

SECTION_NUMBER 1
 '@S9S_MB_2U_LIB.S9S_MB_2U(SCH_1):PAGE442_I143@PURE_QUANTA.Q_CAPP(CHIPS)':
 C_PATH='@s9s_mb_2u_lib.s9s_mb_2u(sch_1):page442_i143@pure_quanta.q_capp(chips)';

PART_NAME
 PC207 'Q_CAPP_THLF-270UF,16V,20%,OSCOA':;

SECTION_NUMBER 1
 '@S9S_MB_2U_LIB.S9S_MB_2U(SCH_1):PAGE442_I142@PURE_QUANTA.Q_CAPP(CHIPS)':
 C_PATH='@s9s_mb_2u_lib.s9s_mb_2u(sch_1):page442_i142@pure_quanta.q_capp(chips)';

PART_NAME
 PC205_P0_2 'Q_CAP_0805-22UF,4V,20%,X6S,TMPA':;

SECTION_NUMBER 1
 '@S9S_MB_2U_LIB.S9S_MB_2U(SCH_1):PAGE442_I178@PURE_QUANTA.Q_CAP(CHIPS)':
 C_PATH='@s9s_mb_2u_lib.s9s_mb_2u(sch_1):page442_i178@pure_quanta.q_cap(chips)';

PART_NAME
 PC204_P0_1 'Q_CAP_0805-22UF,4V,20%,X6S,TMPA':;

SECTION_NUMBER 1
 '@S9S_MB_2U_LIB.S9S_MB_2U(SCH_1):PAGE442_I126@PURE_QUANTA.Q_CAP(CHIPS)':
 C_PATH='@s9s_mb_2u_lib.s9s_mb_2u(sch_1):page442_i126@pure_quanta.q_cap(chips)';

PART_NAME
 PC203_P0_2 'Q_CAP_0805-22UF,4V,20%,X6S,TMPA':;

SECTION_NUMBER 1
 '@S9S_MB_2U_LIB.S9S_MB_2U(SCH_1):PAGE442_I177@PURE_QUANTA.Q_CAP(CHIPS)':
 C_PATH='@s9s_mb_2u_lib.s9s_mb_2u(sch_1):page442_i177@pure_quanta.q_cap(chips)';

PART_NAME
 PC202_P0_1 'Q_CAP_0805-22UF,4V,20%,X6S,TMPA':;

SECTION_NUMBER 1
 '@S9S_MB_2U_LIB.S9S_MB_2U(SCH_1):PAGE442_I125@PURE_QUANTA.Q_CAP(CHIPS)':
 C_PATH='@s9s_mb_2u_lib.s9s_mb_2u(sch_1):page442_i125@pure_quanta.q_cap(chips)';

PART_NAME
 PC199_P0_1 'Q_CAP_C0402-100NF,50V,10%,X7R,A':;

SECTION_NUMBER 1
 '@S9S_MB_2U_LIB.S9S_MB_2U(SCH_1):PAGE442_I105@PURE_QUANTA.Q_CAP(CHIPS)':
 C_PATH='@s9s_mb_2u_lib.s9s_mb_2u(sch_1):page442_i105@pure_quanta.q_cap(chips)';

PART_NAME
 PC198_P0_2 'Q_CAP_C0805-22UF,16V,20%,X6S,CA':;

SECTION_NUMBER 1
 '@S9S_MB_2U_LIB.S9S_MB_2U(SCH_1):PAGE442_I173@PURE_QUANTA.Q_CAP(CHIPS)':
 C_PATH='@s9s_mb_2u_lib.s9s_mb_2u(sch_1):page442_i173@pure_quanta.q_cap(chips)';

PART_NAME
 PC197_P0_1 'Q_CAP_C0805-22UF,16V,20%,X6S,CA':;

SECTION_NUMBER 1
 '@S9S_MB_2U_LIB.S9S_MB_2U(SCH_1):PAGE442_I115@PURE_QUANTA.Q_CAP(CHIPS)':
 C_PATH='@s9s_mb_2u_lib.s9s_mb_2u(sch_1):page442_i115@pure_quanta.q_cap(chips)';

PART_NAME
 PC196_P0_2 'Q_CAP_C0805-22UF,16V,20%,X6S,CA':;

SECTION_NUMBER 1
 '@S9S_MB_2U_LIB.S9S_MB_2U(SCH_1):PAGE442_I172@PURE_QUANTA.Q_CAP(CHIPS)':
 C_PATH='@s9s_mb_2u_lib.s9s_mb_2u(sch_1):page442_i172@pure_quanta.q_cap(chips)';

PART_NAME
 PC195_P0_1 'Q_CAP_C0805-22UF,16V,20%,X6S,CA':;

SECTION_NUMBER 1
 '@S9S_MB_2U_LIB.S9S_MB_2U(SCH_1):PAGE442_I113@PURE_QUANTA.Q_CAP(CHIPS)':
 C_PATH='@s9s_mb_2u_lib.s9s_mb_2u(sch_1):page442_i113@pure_quanta.q_cap(chips)';

PART_NAME
 PC194 'Q_CAP_C0402-100NF,50V,10%,X7R,A':;

SECTION_NUMBER 1
 '@S9S_MB_2U_LIB.S9S_MB_2U(SCH_1):PAGE442_I235@PURE_QUANTA.Q_CAP(CHIPS)':
 C_PATH='@s9s_mb_2u_lib.s9s_mb_2u(sch_1):page442_i235@pure_quanta.q_cap(chips)';

PART_NAME
 PC193 'Q_CAP_C0402-100NF,50V,10%,X7R,A':;

SECTION_NUMBER 1
 '@S9S_MB_2U_LIB.S9S_MB_2U(SCH_1):PAGE442_I234@PURE_QUANTA.Q_CAP(CHIPS)':
 C_PATH='@s9s_mb_2u_lib.s9s_mb_2u(sch_1):page442_i234@pure_quanta.q_cap(chips)';

PART_NAME
 PC192_P0_2 'Q_CAP_C0402-1UF,16V,10%,X6S,CHA':;

SECTION_NUMBER 1
 '@S9S_MB_2U_LIB.S9S_MB_2U(SCH_1):PAGE442_I170@PURE_QUANTA.Q_CAP(CHIPS)':
 C_PATH='@s9s_mb_2u_lib.s9s_mb_2u(sch_1):page442_i170@pure_quanta.q_cap(chips)';

PART_NAME
 PC191_P0_1 'Q_CAP_C0402-1UF,16V,10%,X6S,CHA':;

SECTION_NUMBER 1
 '@S9S_MB_2U_LIB.S9S_MB_2U(SCH_1):PAGE442_I112@PURE_QUANTA.Q_CAP(CHIPS)':
 C_PATH='@s9s_mb_2u_lib.s9s_mb_2u(sch_1):page442_i112@pure_quanta.q_cap(chips)';

PART_NAME
 PC190_P0_2 'Q_CAP_0402-3300PF,50V,10%,X7R,A':;

SECTION_NUMBER 1
 '@S9S_MB_2U_LIB.S9S_MB_2U(SCH_1):PAGE442_I171@PURE_QUANTA.Q_CAP(CHIPS)':
 C_PATH='@s9s_mb_2u_lib.s9s_mb_2u(sch_1):page442_i171@pure_quanta.q_cap(chips)';

PART_NAME
 PC189_P0_1 'Q_CAP_0402-3300PF,50V,10%,X7R,A':;

SECTION_NUMBER 1
 '@S9S_MB_2U_LIB.S9S_MB_2U(SCH_1):PAGE442_I111@PURE_QUANTA.Q_CAP(CHIPS)':
 C_PATH='@s9s_mb_2u_lib.s9s_mb_2u(sch_1):page442_i111@pure_quanta.q_cap(chips)';

PART_NAME
 PC188 'Q_CAP_C0402-2.2UF,10V,10%,X6S,A':;

SECTION_NUMBER 1
 '@S9S_MB_2U_LIB.S9S_MB_2U(SCH_1):PAGE442_I164@PURE_QUANTA.Q_CAP(CHIPS)':
 C_PATH='@s9s_mb_2u_lib.s9s_mb_2u(sch_1):page442_i164@pure_quanta.q_cap(chips)';

PART_NAME
 PC187 'Q_CAP_C0402-2.2UF,10V,10%,X6S,A':;

SECTION_NUMBER 1
 '@S9S_MB_2U_LIB.S9S_MB_2U(SCH_1):PAGE442_I151@PURE_QUANTA.Q_CAP(CHIPS)':
 C_PATH='@s9s_mb_2u_lib.s9s_mb_2u(sch_1):page442_i151@pure_quanta.q_cap(chips)';

PART_NAME
 PU42 'RAA2213404GNPHB0-RAA2213404GNPA':;

SECTION_NUMBER 1
 '@S9S_MB_2U_LIB.S9S_MB_2U(SCH_1):PAGE444_I53@PURE_QUANTA.RAA2213404GNPHB0(CHIPS)':
 C_PATH='@s9s_mb_2u_lib.s9s_mb_2u(sch_1):page444_i53@pure_quanta.raa2213404gnphb0(~
chips)',
 VAR_0_ONSEMI='VAR_REPLACED|RAA2213404GNPHB0|VAR_PARTNAME|FDMF5076|VALUE|FDMF507~
6|PART_TYPE|SMLF|MATERIAL|IC|PART_NUMBER|AL005076000|STANDARD||LIFECYCLE||PART_N~
UMBER|AL005076000|JEDEC_TYPE|PQFN17_TH_5X4XA|DESCRIPTION|IC OTHER(27P)FDMF5076(P~
QFN)|MANUFTR|ONS|MANUF_PN|FDMF5076|RD_CMPLS_LVL|EP(V1)|CMPLS_LVL|EP(V1)|FROM_PJ|~
S9S-KIMI|CLASS|IC|DIP_SMD||DATA|ONS_FDMF5076.pdf|EE_CHECK_LIST||FP_ECN|FDMF5076.~
msg|PSL||CREATOR||STATUS||MSD|NA|ESD_CDM|NA|ESD_HBM|NA|ESD_MM|NA|PIN_LENGTH_SHOR~
T_PIN|0 MILS|PIN_LENGTH_LONG_PIN|0 MILS|CREATEDAY|20200416|VARIANT_DEVICE_TYPE|F~
DMF5076-FDMF5076,SMLF,IC,AL00',
 CDSVAR_REPCELL_ONSEMI='pure_quanta|fdmf5076';

PART_NAME
 PR1779 'Q_RES_0402LF-0,5%,1/16W,CHIP,CA':;

SECTION_NUMBER 1
 '@S9S_MB_2U_LIB.S9S_MB_2U(SCH_1):PAGE444_I46@PURE_QUANTA.Q_RES(CHIPS)':
 C_PATH='@s9s_mb_2u_lib.s9s_mb_2u(sch_1):page444_i46@pure_quanta.q_res(chips)',
 VAR_0_ONSEMI='VALUE|0|TOLERANCE|5%|WATTAGE|1/16W|PACK_TYPE|0402LF|MATERIAL|EMPT~
Y|PART_NUMBER|CS00002JB38|STANDARD|End of Design|LIFECYCLE|Comp-Approve|PART_NUM~
BER|CS00002JB38|JEDEC_TYPE|R0402|ALT_SYMBOLS|(R0402-0201)|VALUE|0|TOL|5%|WATTAGE~
|1/16W|CLASS|IO|DESCRIPTION|RESISTOR CHIP 0 1/16W +-5%(0402)|COMPONENT_TYPE|CHIP~
0402|LEAD_LENGTH||DFM_EXCLUSION||DAY|20100618|VARIANT_DEVICE_TYPE|Q_RES-0,5%,1/1~
6W,0402LF,EMPTY,',
 CDSVAR_REPCELL_ONSEMI='pure_quanta|Q_res';

PART_NAME
 PR1778 'Q_RES_0402LF-4.7,1%,1/16W,CHIPA':;

SECTION_NUMBER 1
 '@S9S_MB_2U_LIB.S9S_MB_2U(SCH_1):PAGE444_I44@PURE_QUANTA.Q_RES(CHIPS)':
 C_PATH='@s9s_mb_2u_lib.s9s_mb_2u(sch_1):page444_i44@pure_quanta.q_res(chips)',
 VAR_0_ONSEMI='VALUE|0|TOLERANCE|5%|WATTAGE|1/16W|PACK_TYPE|0402LF|MATERIAL|CHIP~
|PART_NUMBER|CS00002JB38|STANDARD|End of Design|LIFECYCLE|Comp-Approve|PART_NUMB~
ER|CS00002JB38|JEDEC_TYPE|R0402|ALT_SYMBOLS|(R0402-0201)|VALUE|0|TOL|5%|WATTAGE|~
1/16W|CLASS|DISCRETE|DESCRIPTION|RESISTOR CHIP 0 1/16W +-5%(0402)|COMPONENT_TYPE~
|CHIP0402|LEAD_LENGTH||DFM_EXCLUSION||DAY|20100618|VARIANT_DEVICE_TYPE|Q_RES-0,5~
%,1/16W,0402LF,CHIP,C',
 CDSVAR_REPCELL_ONSEMI='pure_quanta|Q_res';

PART_NAME
 PR1709 'Q_RES_0402LF-8.87K,1%,1/16W,EMA':;

SECTION_NUMBER 1
 '@S9S_MB_2U_LIB.S9S_MB_2U(SCH_1):PAGE444_I52@PURE_QUANTA.Q_RES(CHIPS)':
 C_PATH='@s9s_mb_2u_lib.s9s_mb_2u(sch_1):page444_i52@pure_quanta.q_res(chips)';

PART_NAME
 PR97 'Q_RES_0402LF-2.2,1%,1/16W,CHIPA':;

SECTION_NUMBER 1
 '@S9S_MB_2U_LIB.S9S_MB_2U(SCH_1):PAGE444_I19@PURE_QUANTA.Q_RES(CHIPS)':
 C_PATH='@s9s_mb_2u_lib.s9s_mb_2u(sch_1):page444_i19@pure_quanta.q_res(chips)';

PART_NAME
 PL3 'Q_INDUCTOR_SMLF-320NH/38A,IND,A':;

SECTION_NUMBER 1
 '@S9S_MB_2U_LIB.S9S_MB_2U(SCH_1):PAGE444_I21@PURE_QUANTA.Q_INDUCTOR(CHIPS)':
 C_PATH='@s9s_mb_a_lib.s9s_mb_a(sch_1):page444_i21@pure_quanta.q_inductor(chips)~
';

PART_NAME
 PC2180 'Q_CAPP_RDLF-560UF,2.5V,20%,ALUA':;

SECTION_NUMBER 1
 '@S9S_MB_2U_LIB.S9S_MB_2U(SCH_1):PAGE444_I41@PURE_QUANTA.Q_CAPP(CHIPS)':
 C_PATH='@s9s_mb_2u_lib.s9s_mb_2u(sch_1):page444_i41@pure_quanta.q_capp(chips)';

PART_NAME
 PC1900 'Q_CAPP_SMLF-470UF,2.5V,20%,POSA':;

SECTION_NUMBER 1
 '@S9S_MB_2U_LIB.S9S_MB_2U(SCH_1):PAGE444_I42@PURE_QUANTA.Q_CAPP(CHIPS)':
 C_PATH='@s9s_mb_2u_lib.s9s_mb_2u(sch_1):page444_i42@pure_quanta.q_capp(chips)';

PART_NAME
 PC1348 'Q_CAP_0402-0.1UF,25V,10%,X7R,CA':;

SECTION_NUMBER 1
 '@S9S_MB_2U_LIB.S9S_MB_2U(SCH_1):PAGE444_I49@PURE_QUANTA.Q_CAP(CHIPS)':
 C_PATH='@s9s_mb_2u_lib.s9s_mb_2u(sch_1):page444_i49@pure_quanta.q_cap(chips)',
 VAR_0_ONSEMI='VALUE|0.1UF|VOLTAGE|25V|TOLERANCE|10%|PACK_TYPE|0402|MATERIAL|EMP~
TY|PART_NUMBER|CH4104K1B00|STANDARD||LIFECYCLE||ASS_PART||PART_NUMBER|CH4104K1B0~
0|JEDEC_TYPE|C0402|ALT_SYMBOLS|(C0402_OCTAGONXA,C0402-0201)|VALUE|NA|RATED_VOLTA~
GE|25V|TOL|10%|CLASS|IO|DESCRIPTION|CAP CHIP 0.1U 25V(+-10%,X7R,0402)|COMPONENT_~
TYPE|CHIP0402|LEAD_LENGTH||LPID||DATE|20160113|VARIANT_DEVICE_TYPE|Q_CAP-0.1UF,2~
5V,10%,0402,EMPTY',
 CDSVAR_REPCELL_ONSEMI='pure_quanta|Q_cap';

PART_NAME
 PC186 'Q_CAP_0805-22UF,4V,20%,X6S,TMPA':;

SECTION_NUMBER 1
 '@S9S_MB_2U_LIB.S9S_MB_2U(SCH_1):PAGE444_I5@PURE_QUANTA.Q_CAP(CHIPS)':
 C_PATH='@s9s_mb_2u_lib.s9s_mb_2u(sch_1):page444_i5@pure_quanta.q_cap(chips)';

PART_NAME
 PC184 'Q_CAP_0805-22UF,4V,20%,X6S,TMPA':;

SECTION_NUMBER 1
 '@S9S_MB_2U_LIB.S9S_MB_2U(SCH_1):PAGE444_I6@PURE_QUANTA.Q_CAP(CHIPS)':
 C_PATH='@s9s_mb_2u_lib.s9s_mb_2u(sch_1):page444_i6@pure_quanta.q_cap(chips)';

PART_NAME
 PC181 'Q_CAP_C0402-100NF,50V,10%,X7R,A':;

SECTION_NUMBER 1
 '@S9S_MB_2U_LIB.S9S_MB_2U(SCH_1):PAGE444_I8@PURE_QUANTA.Q_CAP(CHIPS)':
 C_PATH='@s9s_mb_2u_lib.s9s_mb_2u(sch_1):page444_i8@pure_quanta.q_cap(chips)';

PART_NAME
 PC180 'Q_CAP_C0805-22UF,16V,20%,X6S,CA':;

SECTION_NUMBER 1
 '@S9S_MB_2U_LIB.S9S_MB_2U(SCH_1):PAGE444_I14@PURE_QUANTA.Q_CAP(CHIPS)':
 C_PATH='@s9s_mb_2u_lib.s9s_mb_2u(sch_1):page444_i14@pure_quanta.q_cap(chips)';

PART_NAME
 PC179 'Q_CAP_C0805-22UF,16V,20%,X6S,CA':;

SECTION_NUMBER 1
 '@S9S_MB_2U_LIB.S9S_MB_2U(SCH_1):PAGE444_I15@PURE_QUANTA.Q_CAP(CHIPS)':
 C_PATH='@s9s_mb_2u_lib.s9s_mb_2u(sch_1):page444_i15@pure_quanta.q_cap(chips)';

PART_NAME
 PC178 'Q_CAP_C0402-100NF,50V,10%,X7R,A':;

SECTION_NUMBER 1
 '@S9S_MB_2U_LIB.S9S_MB_2U(SCH_1):PAGE444_I50@PURE_QUANTA.Q_CAP(CHIPS)':
 C_PATH='@s9s_mb_2u_lib.s9s_mb_2u(sch_1):page444_i50@pure_quanta.q_cap(chips)';

PART_NAME
 PC177 'Q_CAP_C0402-1UF,16V,10%,X6S,CHA':;

SECTION_NUMBER 1
 '@S9S_MB_2U_LIB.S9S_MB_2U(SCH_1):PAGE444_I16@PURE_QUANTA.Q_CAP(CHIPS)':
 C_PATH='@s9s_mb_2u_lib.s9s_mb_2u(sch_1):page444_i16@pure_quanta.q_cap(chips)';

PART_NAME
 PC176 'Q_CAP_0402-3300PF,50V,10%,X7R,A':;

SECTION_NUMBER 1
 '@S9S_MB_2U_LIB.S9S_MB_2U(SCH_1):PAGE444_I17@PURE_QUANTA.Q_CAP(CHIPS)':
 C_PATH='@s9s_mb_2u_lib.s9s_mb_2u(sch_1):page444_i17@pure_quanta.q_cap(chips)';

PART_NAME
 PC175 'Q_CAP_C0402-2.2UF,10V,10%,X6S,A':;

SECTION_NUMBER 1
 '@S9S_MB_2U_LIB.S9S_MB_2U(SCH_1):PAGE444_I20@PURE_QUANTA.Q_CAP(CHIPS)':
 C_PATH='@s9s_mb_2u_lib.s9s_mb_2u(sch_1):page444_i20@pure_quanta.q_cap(chips)';

PART_NAME
 R1736 'Q_RES_0402LF-0,5%,1/16W,CHIP,CA':;

SECTION_NUMBER 1
 '@S9S_MB_2U_LIB.S9S_MB_2U(SCH_1):PAGE518_I89@PURE_QUANTA.Q_RES(CHIPS)':
 C_PATH='@s9s_mb_2u_lib.s9s_mb_2u(sch_1):page518_i89@pure_quanta.q_res(chips)';

PART_NAME
 R1676 'Q_RES_0402LF-1K,1%,1/16W,EMPTYA':;

SECTION_NUMBER 1
 '@S9S_MB_2U_LIB.S9S_MB_2U(SCH_1):PAGE518_I94@PURE_QUANTA.Q_RES(CHIPS)':
 C_PATH='@s9s_mb_2u_lib.s9s_mb_2u(sch_1):page518_i94@pure_quanta.q_res(chips)';

PART_NAME
 R1675 'Q_RES_0402LF-2.49K,1%,1/16W,EMA':;

SECTION_NUMBER 1
 '@S9S_MB_2U_LIB.S9S_MB_2U(SCH_1):PAGE518_I82@PURE_QUANTA.Q_RES(CHIPS)':
 C_PATH='@s9s_mb_2u_lib.s9s_mb_2u(sch_1):page518_i82@pure_quanta.q_res(chips)';

PART_NAME
 R1486 'Q_RES_0402LF-200,1%,1/16W,EMPTA':;

SECTION_NUMBER 1
 '@S9S_MB_2U_LIB.S9S_MB_2U(SCH_1):PAGE518_I74@PURE_QUANTA.Q_RES(CHIPS)':
 C_PATH='@s9s_mb_2u_lib.s9s_mb_2u(sch_1):page518_i74@pure_quanta.q_res(chips)';

PART_NAME
 R1485 'Q_RES_0402LF-200,1%,1/16W,EMPTA':;

SECTION_NUMBER 1
 '@S9S_MB_2U_LIB.S9S_MB_2U(SCH_1):PAGE518_I75@PURE_QUANTA.Q_RES(CHIPS)':
 C_PATH='@s9s_mb_2u_lib.s9s_mb_2u(sch_1):page518_i75@pure_quanta.q_res(chips)';

PART_NAME
 R1201 'Q_RES_0402LF-49.9     ,1%  ,1/A':;

SECTION_NUMBER 1
 '@S9S_MB_2U_LIB.S9S_MB_2U(SCH_1):PAGE518_I58@PURE_QUANTA.Q_RES(CHIPS)':
 C_PATH='@s9s_mb_2u_lib.s9s_mb_2u(sch_1):page518_i58@pure_quanta.q_res(chips)';

PART_NAME
 R1200 'Q_RES_0402LF-100,1%,1/16W,CHIPA':;

SECTION_NUMBER 1
 '@S9S_MB_2U_LIB.S9S_MB_2U(SCH_1):PAGE518_I60@PURE_QUANTA.Q_RES(CHIPS)':
 C_PATH='@s9s_mb_2u_lib.s9s_mb_2u(sch_1):page518_i60@pure_quanta.q_res(chips)';

PART_NAME
 R1198 'Q_RES_0402LF-10K,1%,1/16W,CHIPA':;

SECTION_NUMBER 1
 '@S9S_MB_2U_LIB.S9S_MB_2U(SCH_1):PAGE518_I48@PURE_QUANTA.Q_RES(CHIPS)':
 C_PATH='@s9s_mb_2u_lib.s9s_mb_2u(sch_1):page518_i48@pure_quanta.q_res(chips)';

PART_NAME
 R1197 'Q_RES_0402LF-1K,5%,1/16W,EMPTYA':;

SECTION_NUMBER 1
 '@S9S_MB_2U_LIB.S9S_MB_2U(SCH_1):PAGE518_I50@PURE_QUANTA.Q_RES(CHIPS)':
 C_PATH='@s9s_mb_2u_lib.s9s_mb_2u(sch_1):page518_i50@pure_quanta.q_res(chips)';

PART_NAME
 R1026 'Q_RES_0402LF-1K,1%,1/16W,CHIP,A':;

SECTION_NUMBER 1
 '@S9S_MB_2U_LIB.S9S_MB_2U(SCH_1):PAGE518_I37@PURE_QUANTA.Q_RES(CHIPS)':
 C_PATH='@s9s_mb_2u_lib.s9s_mb_2u(sch_1):page518_i37@pure_quanta.q_res(chips)';

PART_NAME
 R1025 'Q_RES_0402LF-75,1%,1/16W,EMPTYA':;

SECTION_NUMBER 1
 '@S9S_MB_2U_LIB.S9S_MB_2U(SCH_1):PAGE518_I38@PURE_QUANTA.Q_RES(CHIPS)':
 C_PATH='@s9s_mb_2u_lib.s9s_mb_2u(sch_1):page518_i38@pure_quanta.q_res(chips)';

PART_NAME
 R1024 'Q_RES_0402LF-100,1%,1/16W,CHIPA':;

SECTION_NUMBER 1
 '@S9S_MB_2U_LIB.S9S_MB_2U(SCH_1):PAGE518_I41@PURE_QUANTA.Q_RES(CHIPS)':
 C_PATH='@s9s_mb_2u_lib.s9s_mb_2u(sch_1):page518_i41@pure_quanta.q_res(chips)';

PART_NAME
 R989 'Q_RES_0402LF-10K,1%,1/16W,CHIPA':;

SECTION_NUMBER 1
 '@S9S_MB_2U_LIB.S9S_MB_2U(SCH_1):PAGE518_I68@PURE_QUANTA.Q_RES(CHIPS)':
 C_PATH='@s9s_mb_2u_lib.s9s_mb_2u(sch_1):page518_i68@pure_quanta.q_res(chips)';

PART_NAME
 R697 'Q_RES_0402LF-33,5%,1/16W,CHIP,A':;

SECTION_NUMBER 1
 '@S9S_MB_2U_LIB.S9S_MB_2U(SCH_1):PAGE518_I66@PURE_QUANTA.Q_RES(CHIPS)':
 C_PATH='@s9s_mb_2u_lib.s9s_mb_2u(sch_1):page518_i66@pure_quanta.q_res(chips)';

PART_NAME
 R696 'Q_RES_0402LF-4.75K,1%,1/16W,CHA':;

SECTION_NUMBER 1
 '@S9S_MB_2U_LIB.S9S_MB_2U(SCH_1):PAGE518_I63@PURE_QUANTA.Q_RES(CHIPS)':
 C_PATH='@s9s_mb_2u_lib.s9s_mb_2u(sch_1):page518_i63@pure_quanta.q_res(chips)';

PART_NAME
 R494 'Q_RES_0402LF-4.75K,1%,1/16W,CHA':;

SECTION_NUMBER 1
 '@S9S_MB_2U_LIB.S9S_MB_2U(SCH_1):PAGE518_I4@PURE_QUANTA.Q_RES(CHIPS)':
 C_PATH='@s9s_mb_2u_lib.s9s_mb_2u(sch_1):page518_i4@pure_quanta.q_res(chips)';

PART_NAME
 R453 'Q_RES_0402LF-10K,1%,1/16W,CHIPA':;

SECTION_NUMBER 1
 '@S9S_MB_2U_LIB.S9S_MB_2U(SCH_1):PAGE518_I77@PURE_QUANTA.Q_RES(CHIPS)':
 C_PATH='@s9s_mb_2u_lib.s9s_mb_2u(sch_1):page518_i77@pure_quanta.q_res(chips)';

PART_NAME
 JP8 'CONN3_HFK1030G000LAF-CONN3_HFKA':;

SECTION_NUMBER 1
 '@S9S_MB_2U_LIB.S9S_MB_2U(SCH_1):PAGE518_I86@PURE_QUANTA.CONN3_HFK1030G000LAF(CHIPS)':
 C_PATH='@s9s_mb_2u_lib.s9s_mb_2u(sch_1):page518_i86@pure_quanta.conn3_hfk1030g000~
laf(chips)';

PART_NAME
 R1007 'Q_RES_0402LF-4.7K,5%,1/16W,CHIA':;

SECTION_NUMBER 1
 '@S9S_MB_2U_LIB.S9S_MB_2U(SCH_1):PAGE489_I65@PURE_QUANTA.Q_RES(CHIPS)':
 C_PATH='@s9s_mb_2u_lib.s9s_mb_2u(sch_1):page489_i65@pure_quanta.q_res(chips)';

PART_NAME
 R1006 'Q_RES_0402LF-4.7K,5%,1/16W,CHIA':;

SECTION_NUMBER 1
 '@S9S_MB_2U_LIB.S9S_MB_2U(SCH_1):PAGE489_I52@PURE_QUANTA.Q_RES(CHIPS)':
 C_PATH='@s9s_mb_2u_lib.s9s_mb_2u(sch_1):page489_i52@pure_quanta.q_res(chips)';

PART_NAME
 R1005 'Q_RES_0402LF-10K,1%,1/16W,EMPTA':;

SECTION_NUMBER 1
 '@S9S_MB_2U_LIB.S9S_MB_2U(SCH_1):PAGE489_I36@PURE_QUANTA.Q_RES(CHIPS)':
 C_PATH='@s9s_mb_2u_lib.s9s_mb_2u(sch_1):page489_i36@pure_quanta.q_res(chips)';

PART_NAME
 R1004 'Q_RES_0402LF-1K,1%,1/16W,CHIP,A':;

SECTION_NUMBER 1
 '@S9S_MB_2U_LIB.S9S_MB_2U(SCH_1):PAGE489_I35@PURE_QUANTA.Q_RES(CHIPS)':
 C_PATH='@s9s_mb_2u_lib.s9s_mb_2u(sch_1):page489_i35@pure_quanta.q_res(chips)';

PART_NAME
 R1003 'Q_RES_0402LF-4.7K,5%,1/16W,CHIA':;

SECTION_NUMBER 1
 '@S9S_MB_2U_LIB.S9S_MB_2U(SCH_1):PAGE489_I68@PURE_QUANTA.Q_RES(CHIPS)':
 C_PATH='@s9s_mb_2u_lib.s9s_mb_2u(sch_1):page489_i68@pure_quanta.q_res(chips)';

PART_NAME
 R1002 'Q_RES_0402LF-4.7K,5%,1/16W,CHIA':;

SECTION_NUMBER 1
 '@S9S_MB_2U_LIB.S9S_MB_2U(SCH_1):PAGE489_I51@PURE_QUANTA.Q_RES(CHIPS)':
 C_PATH='@s9s_mb_2u_lib.s9s_mb_2u(sch_1):page489_i51@pure_quanta.q_res(chips)';

PART_NAME
 R1001 'Q_RES_0402LF-4.7K,5%,1/16W,CHIA':;

SECTION_NUMBER 1
 '@S9S_MB_2U_LIB.S9S_MB_2U(SCH_1):PAGE489_I69@PURE_QUANTA.Q_RES(CHIPS)':
 C_PATH='@s9s_mb_2u_lib.s9s_mb_2u(sch_1):page489_i69@pure_quanta.q_res(chips)';

PART_NAME
 R1000 'Q_RES_0402LF-4.7K,5%,1/16W,CHIA':;

SECTION_NUMBER 1
 '@S9S_MB_2U_LIB.S9S_MB_2U(SCH_1):PAGE489_I57@PURE_QUANTA.Q_RES(CHIPS)':
 C_PATH='@s9s_mb_2u_lib.s9s_mb_2u(sch_1):page489_i57@pure_quanta.q_res(chips)';

PART_NAME
 R999 'Q_RES_0402LF-0,5%,1/16W,CHIP,CA':;

SECTION_NUMBER 1
 '@S9S_MB_2U_LIB.S9S_MB_2U(SCH_1):PAGE489_I70@PURE_QUANTA.Q_RES(CHIPS)':
 C_PATH='@s9s_mb_2u_lib.s9s_mb_2u(sch_1):page489_i70@pure_quanta.q_res(chips)';

PART_NAME
 R998 'Q_RES_0402LF-0,5%,1/16W,CHIP,CA':;

SECTION_NUMBER 1
 '@S9S_MB_2U_LIB.S9S_MB_2U(SCH_1):PAGE489_I59@PURE_QUANTA.Q_RES(CHIPS)':
 C_PATH='@s9s_mb_2u_lib.s9s_mb_2u(sch_1):page489_i59@pure_quanta.q_res(chips)';

PART_NAME
 R997 'Q_RES_0402LF-10K,1%,1/16W,EMPTA':;

SECTION_NUMBER 1
 '@S9S_MB_2U_LIB.S9S_MB_2U(SCH_1):PAGE489_I31@PURE_QUANTA.Q_RES(CHIPS)':
 C_PATH='@s9s_mb_2u_lib.s9s_mb_2u(sch_1):page489_i31@pure_quanta.q_res(chips)';

PART_NAME
 R650 'Q_RES_0402LF-1K,1%,1/16W,CHIP,A':;

SECTION_NUMBER 1
 '@S9S_MB_2U_LIB.S9S_MB_2U(SCH_1):PAGE489_I32@PURE_QUANTA.Q_RES(CHIPS)':
 C_PATH='@s9s_mb_2u_lib.s9s_mb_2u(sch_1):page489_i32@pure_quanta.q_res(chips)';

PART_NAME
 R630 'Q_RES_0402LF-10K,1%,1/16W,EMPTA':;

SECTION_NUMBER 1
 '@S9S_MB_2U_LIB.S9S_MB_2U(SCH_1):PAGE489_I15@PURE_QUANTA.Q_RES(CHIPS)':
 C_PATH='@s9s_mb_2u_lib.s9s_mb_2u(sch_1):page489_i15@pure_quanta.q_res(chips)';

PART_NAME
 R629 'Q_RES_0402LF-1K,1%,1/16W,CHIP,A':;

SECTION_NUMBER 1
 '@S9S_MB_2U_LIB.S9S_MB_2U(SCH_1):PAGE489_I13@PURE_QUANTA.Q_RES(CHIPS)':
 C_PATH='@s9s_mb_2u_lib.s9s_mb_2u(sch_1):page489_i13@pure_quanta.q_res(chips)';

PART_NAME
 R628 'Q_RES_0402LF-10K,1%,1/16W,CHIPA':;

SECTION_NUMBER 1
 '@S9S_MB_2U_LIB.S9S_MB_2U(SCH_1):PAGE489_I17@PURE_QUANTA.Q_RES(CHIPS)':
 C_PATH='@s9s_mb_2u_lib.s9s_mb_2u(sch_1):page489_i17@pure_quanta.q_res(chips)';

PART_NAME
 R627 'Q_RES_0402LF-1K,1%,1/16W,EMPTYA':;

SECTION_NUMBER 1
 '@S9S_MB_2U_LIB.S9S_MB_2U(SCH_1):PAGE489_I14@PURE_QUANTA.Q_RES(CHIPS)':
 C_PATH='@s9s_mb_2u_lib.s9s_mb_2u(sch_1):page489_i14@pure_quanta.q_res(chips)';

PART_NAME
 R626 'Q_RES_0402LF-10K,1%,1/16W,CHIPA':;

SECTION_NUMBER 1
 '@S9S_MB_2U_LIB.S9S_MB_2U(SCH_1):PAGE489_I26@PURE_QUANTA.Q_RES(CHIPS)':
 C_PATH='@s9s_mb_2u_lib.s9s_mb_2u(sch_1):page489_i26@pure_quanta.q_res(chips)';

PART_NAME
 R625 'Q_RES_0402LF-1K,1%,1/16W,EMPTYA':;

SECTION_NUMBER 1
 '@S9S_MB_2U_LIB.S9S_MB_2U(SCH_1):PAGE489_I24@PURE_QUANTA.Q_RES(CHIPS)':
 C_PATH='@s9s_mb_2u_lib.s9s_mb_2u(sch_1):page489_i24@pure_quanta.q_res(chips)';

PART_NAME
 R515 'Q_RES_0402LF-10K,1%,1/16W,CHIPA':;

SECTION_NUMBER 1
 '@S9S_MB_2U_LIB.S9S_MB_2U(SCH_1):PAGE489_I7@PURE_QUANTA.Q_RES(CHIPS)':
 C_PATH='@s9s_mb_2u_lib.s9s_mb_2u(sch_1):page489_i7@pure_quanta.q_res(chips)';

PART_NAME
 R335 'Q_RES_0402LF-1K,1%,1/16W,EMPTYA':;

SECTION_NUMBER 1
 '@S9S_MB_2U_LIB.S9S_MB_2U(SCH_1):PAGE489_I5@PURE_QUANTA.Q_RES(CHIPS)':
 C_PATH='@s9s_mb_2u_lib.s9s_mb_2u(sch_1):page489_i5@pure_quanta.q_res(chips)';

PART_NAME
 R334 'Q_RES_0402LF-10K,1%,1/16W,CHIPA':;

SECTION_NUMBER 1
 '@S9S_MB_2U_LIB.S9S_MB_2U(SCH_1):PAGE489_I1@PURE_QUANTA.Q_RES(CHIPS)':
 C_PATH='@s9s_mb_2u_lib.s9s_mb_2u(sch_1):page489_i1@pure_quanta.q_res(chips)';

PART_NAME
 R333 'Q_RES_0402LF-1K,1%,1/16W,EMPTYA':;

SECTION_NUMBER 1
 '@S9S_MB_2U_LIB.S9S_MB_2U(SCH_1):PAGE489_I6@PURE_QUANTA.Q_RES(CHIPS)':
 C_PATH='@s9s_mb_2u_lib.s9s_mb_2u(sch_1):page489_i6@pure_quanta.q_res(chips)';

PART_NAME
 R332 'Q_RES_0402LF-10K,1%,1/16W,CHIPA':;

SECTION_NUMBER 1
 '@S9S_MB_2U_LIB.S9S_MB_2U(SCH_1):PAGE489_I21@PURE_QUANTA.Q_RES(CHIPS)':
 C_PATH='@s9s_mb_2u_lib.s9s_mb_2u(sch_1):page489_i21@pure_quanta.q_res(chips)';

PART_NAME
 R331 'Q_RES_0402LF-1K,1%,1/16W,EMPTYA':;

SECTION_NUMBER 1
 '@S9S_MB_2U_LIB.S9S_MB_2U(SCH_1):PAGE489_I20@PURE_QUANTA.Q_RES(CHIPS)':
 C_PATH='@s9s_mb_2u_lib.s9s_mb_2u(sch_1):page489_i20@pure_quanta.q_res(chips)';

PART_NAME
 Q16 'MOSFET_NCH_DUAL-2N7002KDW,SMLFA':;

SECTION_NUMBER 1
 '@S9S_MB_2U_LIB.S9S_MB_2U(SCH_1):PAGE489_I73@PURE_QUANTA.MOSFET_NCH_DUAL(CHIPS)':
 C_PATH='@s9s_mb_2u_lib.s9s_mb_2u(sch_1):page489_i73@pure_quanta.mosfet_nch_dual(c~
hips)';

SECTION_NUMBER 2
 '@S9S_MB_2U_LIB.S9S_MB_2U(SCH_1):PAGE489_I75@PURE_QUANTA.MOSFET_NCH_DUAL(CHIPS)':
 C_PATH='@s9s_mb_2u_lib.s9s_mb_2u(sch_1):page489_i75@pure_quanta.mosfet_nch_dual(c~
hips)';

PART_NAME
 Q15 'MOSFET_NCH_DUAL-2N7002KDW,SMLFA':;

SECTION_NUMBER 1
 '@S9S_MB_2U_LIB.S9S_MB_2U(SCH_1):PAGE489_I53@PURE_QUANTA.MOSFET_NCH_DUAL(CHIPS)':
 C_PATH='@s9s_mb_2u_lib.s9s_mb_2u(sch_1):page489_i53@pure_quanta.mosfet_nch_dual(c~
hips)';

SECTION_NUMBER 2
 '@S9S_MB_2U_LIB.S9S_MB_2U(SCH_1):PAGE489_I76@PURE_QUANTA.MOSFET_NCH_DUAL(CHIPS)':
 C_PATH='@s9s_mb_2u_lib.s9s_mb_2u(sch_1):page489_i76@pure_quanta.mosfet_nch_dual(c~
hips)';

PART_NAME
 JP7 'CONN3_210HP1030BR1-CONN3_210-HA':;

SECTION_NUMBER 1
 '@S9S_MB_2U_LIB.S9S_MB_2U(SCH_1):PAGE489_I85@PURE_QUANTA.CONN3_210HP1030BR1(CHIPS)':
 C_PATH='@s9s_mb_2u_lib.s9s_mb_2u(sch_1):page489_i85@pure_quanta.conn3_210hp1030br~
1(chips)';

PART_NAME
 R1715 'Q_RES_0402LF-33,5%,1/16W,CHIP,A':;

SECTION_NUMBER 1
 '@S9S_MB_2U_LIB.S9S_MB_2U(SCH_1):PAGE583_I182@PURE_QUANTA.Q_RES(CHIPS)':
 C_PATH='@s9s_mb_2u_lib.s9s_mb_2u(sch_1):page583_i182@pure_quanta.q_res(chips)';

PART_NAME
 R1714 'Q_RES_0402LF-33,5%,1/16W,CHIP,A':;

SECTION_NUMBER 1
 '@S9S_MB_2U_LIB.S9S_MB_2U(SCH_1):PAGE583_I183@PURE_QUANTA.Q_RES(CHIPS)':
 C_PATH='@s9s_mb_2u_lib.s9s_mb_2u(sch_1):page583_i183@pure_quanta.q_res(chips)';

PART_NAME
 R1713 'Q_RES_0402LF-2.2K ,5%,1/16W,EMA':;

SECTION_NUMBER 1
 '@S9S_MB_2U_LIB.S9S_MB_2U(SCH_1):PAGE583_I177@PURE_QUANTA.Q_RES(CHIPS)':
 C_PATH='@s9s_mb_2u_lib.s9s_mb_2u(sch_1):page583_i177@pure_quanta.q_res(chips)';

PART_NAME
 R1712 'Q_RES_0402LF-2.2K ,5%,1/16W,EMA':;

SECTION_NUMBER 1
 '@S9S_MB_2U_LIB.S9S_MB_2U(SCH_1):PAGE583_I176@PURE_QUANTA.Q_RES(CHIPS)':
 C_PATH='@s9s_mb_2u_lib.s9s_mb_2u(sch_1):page583_i176@pure_quanta.q_res(chips)';

PART_NAME
 R541 'Q_RES_0402LF-0,5%,1/16W,CHIP,CA':;

SECTION_NUMBER 1
 '@S9S_MB_2U_LIB.S9S_MB_2U(SCH_1):PAGE583_I171@PURE_QUANTA.Q_RES(CHIPS)':
 C_PATH='@s9s_mb_2u_lib.s9s_mb_2u(sch_1):page583_i171@pure_quanta.q_res(chips)';

PART_NAME
 PU14 'ISL69260IRAZT-ISL69260IRAZ-T,SA':;

SECTION_NUMBER 1
 '@S9S_MB_2U_LIB.S9S_MB_2U(SCH_1):PAGE583_I188@PURE_QUANTA.ISL69260IRAZT(CHIPS)':
 C_PATH='@s9s_mb_2u_lib.s9s_mb_2u(sch_1):page583_i188@pure_quanta.isl69260irazt(ch~
ips)',
 CDSVAR_REPCELL_ONSEMI='pure_quanta|fd5001',
 VAR_0_ONSEMI='VAR_REPLACED|ISL69260IRAZT|VAR_PARTNAME|FD5001|PART_TYPE|SMLF|MAT~
ERIAL|IC|VALUE|FD5001|PART_NUMBER|AL005001004|PIN_LENGTH_LONG_PIN|0 MILS|MSD|NA|~
DESCRIPTION|IC OTHER(40P) FD5001(QFN)|EE_CHECK_LIST||CLASS|IC|MANUFTR|ONS|ESD_MM~
|NA|ESD_CDM|NA|FROM_PJ|S9S-KIMI|DIP_SMD||CREATEDAY|20200421|STANDARD||PIN_LENGTH~
_SHORT_PIN|0 MILS|ESD_HBM|NA|LIFECYCLE||STATUS||PSL||RD_CMPLS_LVL|EP(V1)|FP_ECN|~
FD5001.msg|MANUF_PN|FD5001|CMPLS_LVL||JEDEC_TYPE|VFQFPN40_TH_0-4_5X5XC|DATA|ONS_~
FD5001.pdf|PART_NUMBER|AL005001004|CREATOR||VARIANT_DEVICE_TYPE|FD5001';

PART_NAME
 PR531 'Q_RES_0402LF-100,1%,1/16W,CHIPA':;

SECTION_NUMBER 1
 '@S9S_MB_2U_LIB.S9S_MB_2U(SCH_1):PAGE583_I138@PURE_QUANTA.Q_RES(CHIPS)':
 C_PATH='@s9s_mb_2u_lib.s9s_mb_2u(sch_1):page583_i138@pure_quanta.q_res(chips)';

PART_NAME
 PR530 'Q_RES_0402LF-49.9     ,1%  ,1/B':;

SECTION_NUMBER 1
 '@S9S_MB_2U_LIB.S9S_MB_2U(SCH_1):PAGE583_I147@PURE_QUANTA.Q_RES(CHIPS)':
 C_PATH='@s9s_mb_2u_lib.s9s_mb_2u(sch_1):page583_i147@pure_quanta.q_res(chips)';

PART_NAME
 PR529 'Q_RES_0402LF-49.9     ,1%  ,1/A':;

SECTION_NUMBER 1
 '@S9S_MB_2U_LIB.S9S_MB_2U(SCH_1):PAGE583_I141@PURE_QUANTA.Q_RES(CHIPS)':
 C_PATH='@s9s_mb_2u_lib.s9s_mb_2u(sch_1):page583_i141@pure_quanta.q_res(chips)';

PART_NAME
 PR528 'Q_RES_0402LF-100,1%,1/16W,CHIPA':;

SECTION_NUMBER 1
 '@S9S_MB_2U_LIB.S9S_MB_2U(SCH_1):PAGE583_I143@PURE_QUANTA.Q_RES(CHIPS)':
 C_PATH='@s9s_mb_2u_lib.s9s_mb_2u(sch_1):page583_i143@pure_quanta.q_res(chips)';

PART_NAME
 PR527 'Q_RES_0402LF-100,1%,1/16W,CHIPA':;

SECTION_NUMBER 1
 '@S9S_MB_2U_LIB.S9S_MB_2U(SCH_1):PAGE583_I136@PURE_QUANTA.Q_RES(CHIPS)':
 C_PATH='@s9s_mb_2u_lib.s9s_mb_2u(sch_1):page583_i136@pure_quanta.q_res(chips)';

PART_NAME
 PR177 'Q_RES_0402LF-1K,1%,1/16W,CHIP,A':;

SECTION_NUMBER 1
 '@S9S_MB_2U_LIB.S9S_MB_2U(SCH_1):PAGE583_I82@PURE_QUANTA.Q_RES(CHIPS)':
 C_PATH='@s9s_mb_2u_lib.s9s_mb_2u(sch_1):page583_i82@pure_quanta.q_res(chips)';

PART_NAME
 PR176 'Q_RES_0402LF-1,1%,1/16W,CHIP,CA':;

SECTION_NUMBER 1
 '@S9S_MB_2U_LIB.S9S_MB_2U(SCH_1):PAGE583_I100@PURE_QUANTA.Q_RES(CHIPS)':
 C_PATH='@s9s_mb_2u_lib.s9s_mb_2u(sch_1):page583_i100@pure_quanta.q_res(chips)';

PART_NAME
 PR174 'Q_RES_0402LF-0,5%,1/16W,CHIP,CA':;

SECTION_NUMBER 1
 '@S9S_MB_2U_LIB.S9S_MB_2U(SCH_1):PAGE583_I187@PURE_QUANTA.Q_RES(CHIPS)':
 C_PATH='@s9s_mb_2u_lib.s9s_mb_2u(sch_1):page583_i187@pure_quanta.q_res(chips)';

PART_NAME
 PR172 'Q_RES_0402LF-1K,1%,1/16W,CHIP,A':;

SECTION_NUMBER 1
 '@S9S_MB_2U_LIB.S9S_MB_2U(SCH_1):PAGE583_I35@PURE_QUANTA.Q_RES(CHIPS)':
 C_PATH='@s9s_mb_2u_lib.s9s_mb_2u(sch_1):page583_i35@pure_quanta.q_res(chips)';

PART_NAME
 PR171 'Q_RES_0402LF-0,5%,1/16W,CHIP,CA':;

SECTION_NUMBER 1
 '@S9S_MB_2U_LIB.S9S_MB_2U(SCH_1):PAGE583_I26@PURE_QUANTA.Q_RES(CHIPS)':
 C_PATH='@s9s_mb_2u_lib.s9s_mb_2u(sch_1):page583_i26@pure_quanta.q_res(chips)',
 CDSVAR_REPCELL_ONSEMI='pure_quanta|Q_res',
 VAR_0_ONSEMI='VALUE|1.3K|TOLERANCE|1%|WATTAGE|1/16W|PACK_TYPE|0402LF|MATERIAL|C~
HIP|PART_NUMBER|CS21302FB17|STANDARD|End of Design|LIFECYCLE|Comp-Approve|PART_N~
UMBER|CS21302FB17|JEDEC_TYPE|R0402|ALT_SYMBOLS|(R0402-0201)|VALUE|1.3K|TOL|1%|WA~
TTAGE|1/16W|CLASS|DISCRETE|DESCRIPTION|RES CHIP 1.3K 1/16W +-1%(0402) L-F|COMPON~
ENT_TYPE|CHIP0402|LEAD_LENGTH||DFM_EXCLUSION||DAY|20131122|VARIANT_DEVICE_TYPE|Q~
_RES-1.3K,1%,1/16W,0402LF,CHI';

PART_NAME
 PR170 'Q_RES_0402LF-0,5%,1/16W,CHIP,CA':;

SECTION_NUMBER 1
 '@S9S_MB_2U_LIB.S9S_MB_2U(SCH_1):PAGE583_I134@PURE_QUANTA.Q_RES(CHIPS)':
 C_PATH='@s9s_mb_2u_lib.s9s_mb_2u(sch_1):page583_i134@pure_quanta.q_res(chips)';

PART_NAME
 PR169 'Q_RES_0402LF-1K,1%,1/16W,CHIP,A':;

SECTION_NUMBER 1
 '@S9S_MB_2U_LIB.S9S_MB_2U(SCH_1):PAGE583_I34@PURE_QUANTA.Q_RES(CHIPS)':
 C_PATH='@s9s_mb_2u_lib.s9s_mb_2u(sch_1):page583_i34@pure_quanta.q_res(chips)';

PART_NAME
 PR168 'Q_RES_0402LF-33.2,1%,1/16W,CHIA':;

SECTION_NUMBER 1
 '@S9S_MB_2U_LIB.S9S_MB_2U(SCH_1):PAGE583_I133@PURE_QUANTA.Q_RES(CHIPS)':
 C_PATH='@s9s_mb_2u_lib.s9s_mb_2u(sch_1):page583_i133@pure_quanta.q_res(chips)';

PART_NAME
 PR167 'Q_RES_0402LF-0,5%,1/16W,CHIP,CA':;

SECTION_NUMBER 1
 '@S9S_MB_2U_LIB.S9S_MB_2U(SCH_1):PAGE583_I132@PURE_QUANTA.Q_RES(CHIPS)':
 C_PATH='@s9s_mb_2u_lib.s9s_mb_2u(sch_1):page583_i132@pure_quanta.q_res(chips)';

PART_NAME
 PR166 'Q_RES_0402LF-1K,1%,1/16W,EMPTYA':;

SECTION_NUMBER 1
 '@S9S_MB_2U_LIB.S9S_MB_2U(SCH_1):PAGE583_I37@PURE_QUANTA.Q_RES(CHIPS)':
 C_PATH='@s9s_mb_2u_lib.s9s_mb_2u(sch_1):page583_i37@pure_quanta.q_res(chips)';

PART_NAME
 PR165 'Q_RES_0402LF-0,5%,1/16W,CHIP,CA':;

SECTION_NUMBER 1
 '@S9S_MB_2U_LIB.S9S_MB_2U(SCH_1):PAGE583_I121@PURE_QUANTA.Q_RES(CHIPS)':
 C_PATH='@s9s_mb_2u_lib.s9s_mb_2u(sch_1):page583_i121@pure_quanta.q_res(chips)';

PART_NAME
 PR164 'Q_RES_0402LF-0,5%,1/16W,CHIP,CA':;

SECTION_NUMBER 1
 '@S9S_MB_2U_LIB.S9S_MB_2U(SCH_1):PAGE583_I120@PURE_QUANTA.Q_RES(CHIPS)':
 C_PATH='@s9s_mb_2u_lib.s9s_mb_2u(sch_1):page583_i120@pure_quanta.q_res(chips)';

PART_NAME
 PR163 'Q_RES_0402LF-150,1%,1/16W,CHIPA':;

SECTION_NUMBER 1
 '@S9S_MB_2U_LIB.S9S_MB_2U(SCH_1):PAGE583_I52@PURE_QUANTA.Q_RES(CHIPS)':
 C_PATH='@s9s_mb_2u_lib.s9s_mb_2u(sch_1):page583_i52@pure_quanta.q_res(chips)';

PART_NAME
 PR162 'Q_RES_0402LF-0,5%,1/16W,CHIP,CA':;

SECTION_NUMBER 1
 '@S9S_MB_2U_LIB.S9S_MB_2U(SCH_1):PAGE583_I122@PURE_QUANTA.Q_RES(CHIPS)':
 C_PATH='@s9s_mb_2u_lib.s9s_mb_2u(sch_1):page583_i122@pure_quanta.q_res(chips)';

PART_NAME
 PR161 'Q_RES_0402LF-0,5%,1/16W,CHIP,CA':;

SECTION_NUMBER 1
 '@S9S_MB_2U_LIB.S9S_MB_2U(SCH_1):PAGE583_I123@PURE_QUANTA.Q_RES(CHIPS)':
 C_PATH='@s9s_mb_2u_lib.s9s_mb_2u(sch_1):page583_i123@pure_quanta.q_res(chips)';

PART_NAME
 PR160 'Q_RES_0402LF-1K,1%,1/16W,CHIP,A':;

SECTION_NUMBER 1
 '@S9S_MB_2U_LIB.S9S_MB_2U(SCH_1):PAGE583_I126@PURE_QUANTA.Q_RES(CHIPS)':
 C_PATH='@s9s_mb_2u_lib.s9s_mb_2u(sch_1):page583_i126@pure_quanta.q_res(chips)';

PART_NAME
 PR159 'Q_RES_0402LF-28K,1%,1/16W,EMPTA':;

SECTION_NUMBER 1
 '@S9S_MB_2U_LIB.S9S_MB_2U(SCH_1):PAGE583_I25@PURE_QUANTA.Q_RES(CHIPS)':
 C_PATH='@s9s_mb_2u_lib.s9s_mb_2u(sch_1):page583_i25@pure_quanta.q_res(chips)';

PART_NAME
 PR158 'Q_RES_0402LF-1K,1%,1/16W,EMPTYA':;

SECTION_NUMBER 1
 '@S9S_MB_2U_LIB.S9S_MB_2U(SCH_1):PAGE583_I1@PURE_QUANTA.Q_RES(CHIPS)':
 C_PATH='@s9s_mb_2u_lib.s9s_mb_2u(sch_1):page583_i1@pure_quanta.q_res(chips)';

PART_NAME
 PR157 'Q_RES_0402LF-0,5%,1/16W,CHIP,CA':;

SECTION_NUMBER 1
 '@S9S_MB_2U_LIB.S9S_MB_2U(SCH_1):PAGE583_I153@PURE_QUANTA.Q_RES(CHIPS)':
 C_PATH='@s9s_mb_2u_lib.s9s_mb_2u(sch_1):page583_i153@pure_quanta.q_res(chips)';

PART_NAME
 PR156 'Q_RES_0402LF-0,5%,1/16W,CHIP,CA':;

SECTION_NUMBER 1
 '@S9S_MB_2U_LIB.S9S_MB_2U(SCH_1):PAGE583_I154@PURE_QUANTA.Q_RES(CHIPS)':
 C_PATH='@s9s_mb_2u_lib.s9s_mb_2u(sch_1):page583_i154@pure_quanta.q_res(chips)';

PART_NAME
 PJ47 'Q_SHORT_SM-EMPTY,SHORT6':;

SECTION_NUMBER 1
 '@S9S_MB_2U_LIB.S9S_MB_2U(SCH_1):PAGE583_I33@PURE_QUANTA.Q_SHORT(CHIPS)':
 C_PATH='@s9s_mb_2u_lib.s9s_mb_2u(sch_1):page583_i33@pure_quanta.q_short(chips)';

PART_NAME
 PC1173 'Q_CAP_C0402-1UF,16V,10%,X6S,CHA':;

SECTION_NUMBER 1
 '@S9S_MB_2U_LIB.S9S_MB_2U(SCH_1):PAGE583_I115@PURE_QUANTA.Q_CAP(CHIPS)':
 C_PATH='@s9s_mb_2u_lib.s9s_mb_2u(sch_1):page583_i115@pure_quanta.q_cap(chips)';

PART_NAME
 PC337 'Q_CAP_C0402-1UF,16V,10%,X6S,CHA':;

SECTION_NUMBER 1
 '@S9S_MB_2U_LIB.S9S_MB_2U(SCH_1):PAGE583_I96@PURE_QUANTA.Q_CAP(CHIPS)':
 C_PATH='@s9s_mb_2u_lib.s9s_mb_2u(sch_1):page583_i96@pure_quanta.q_cap(chips)';

PART_NAME
 PC336 'Q_CAP_0402-470PF,50V,10%,X7R,TA':;

SECTION_NUMBER 1
 '@S9S_MB_2U_LIB.S9S_MB_2U(SCH_1):PAGE583_I61@PURE_QUANTA.Q_CAP(CHIPS)':
 C_PATH='@s9s_mb_2u_lib.s9s_mb_2u(sch_1):page583_i61@pure_quanta.q_cap(chips)',
 CDSVAR_REPCELL_ONSEMI='pure_quanta|Q_cap',
 VAR_0_ONSEMI='VALUE|2200PF|VOLTAGE|50V|TOLERANCE|10%|PACK_TYPE|C0402|MATERIAL|X~
7R|PART_NUMBER|CH2226K1B06|STANDARD||LIFECYCLE||ASS_PART||PART_NUMBER|CH2226K1B0~
6|JEDEC_TYPE|C0402|ALT_SYMBOLS|(C0402-0201)|VALUE|2200PF|RATED_VOLTAGE|50V|TOL|1~
0%|CLASS|DISCRETE|DESCRIPTION|CAP CHIP 2200P 50V(+-10%,X7R,0402)MUR|COMPONENT_TY~
PE|CHIP0402|LEAD_LENGTH||LPID||DATE|20150614|VARIANT_DEVICE_TYPE|Q_CAP-2200PF,50~
V,10%,C0402,X7R';

PART_NAME
 PC335 'Q_CAP_0402-4.7UF,6.3V,20%,X6S,A':;

SECTION_NUMBER 1
 '@S9S_MB_2U_LIB.S9S_MB_2U(SCH_1):PAGE583_I116@PURE_QUANTA.Q_CAP(CHIPS)':
 C_PATH='@s9s_mb_2u_lib.s9s_mb_2u(sch_1):page583_i116@pure_quanta.q_cap(chips)',
 CDSVAR_REPCELL_ONSEMI='pure_quanta|Q_cap',
 VAR_0_ONSEMI='VALUE|4.7UF|VOLTAGE|6.3V|TOLERANCE|20%|PACK_TYPE|0402|MATERIAL|EM~
PTY|PART_NUMBER|CH5471MEB01|STANDARD||LIFECYCLE||ASS_PART||PART_NUMBER|CH5471MEB~
01|JEDEC_TYPE|C0402|ALT_SYMBOLS|(C0402_OCTAGON,C0402_OCTAGONXA,C0402-0201)|VALUE~
|NA|RATED_VOLTAGE|6.3V|TOL|20%|CLASS|IO|DESCRIPTION|CAP CHIP 4.7UF 6.3V(+-20%,X6~
S,0402)|COMPONENT_TYPE|CHIP0402|LEAD_LENGTH||LPID||DATE|20151211|VARIANT_DEVICE_~
TYPE|Q_CAP-4.7UF,6.3V,20%,0402,EMPT';

PART_NAME
 PC334 'Q_CAP_C0402-100NF,50V,10%,EMPTA':;

SECTION_NUMBER 1
 '@S9S_MB_2U_LIB.S9S_MB_2U(SCH_1):PAGE583_I94@PURE_QUANTA.Q_CAP(CHIPS)':
 C_PATH='@s9s_mb_2u_lib.s9s_mb_2u(sch_1):page583_i94@pure_quanta.q_cap(chips)';

PART_NAME
 PC333 'Q_CAP_0402-1000PF,50V,5%,EMPTYA':;

SECTION_NUMBER 1
 '@S9S_MB_2U_LIB.S9S_MB_2U(SCH_1):PAGE583_I130@PURE_QUANTA.Q_CAP(CHIPS)':
 C_PATH='@s9s_mb_2u_lib.s9s_mb_2u(sch_1):page583_i130@pure_quanta.q_cap(chips)';

PART_NAME
 PC332 'Q_CAP_0402-1000PF,50V,5%,X7R,TA':;

SECTION_NUMBER 1
 '@S9S_MB_2U_LIB.S9S_MB_2U(SCH_1):PAGE583_I128@PURE_QUANTA.Q_CAP(CHIPS)':
 C_PATH='@s9s_mb_2u_lib.s9s_mb_2u(sch_1):page583_i128@pure_quanta.q_cap(chips)';

PART_NAME
 PC331 'Q_CAP_0402-3300PF,50V,10%,X7R,A':;

SECTION_NUMBER 1
 '@S9S_MB_2U_LIB.S9S_MB_2U(SCH_1):PAGE583_I43@PURE_QUANTA.Q_CAP(CHIPS)':
 C_PATH='@s9s_mb_2u_lib.s9s_mb_2u(sch_1):page583_i43@pure_quanta.q_cap(chips)',
 CDSVAR_REPCELL_ONSEMI='pure_quanta|Q_cap',
 VAR_0_ONSEMI='VALUE|1NF|VOLTAGE|50V|TOLERANCE|10%|PACK_TYPE|0402|MATERIAL|X7R|P~
ART_NUMBER|CH21006KB16|STANDARD||LIFECYCLE||ASS_PART||PART_NUMBER|CH21006KB16|JE~
DEC_TYPE|C0402|ALT_SYMBOLS|(C0402-0201)|VALUE|1NF|RATED_VOLTAGE|50V|TOL|10%|CLAS~
S|DISCRETE|DESCRIPTION|CAP CHIP 1N 50V(+-10%,X7R,0402)EP|COMPONENT_TYPE|CHIP0402~
|LEAD_LENGTH||LPID||DATE|20100811|VARIANT_DEVICE_TYPE|Q_CAP-1NF,50V,10%,0402,X7R~
,CH2';

PART_NAME
 PC330 'Q_CAP_C0402-1UF,16V,10%,X6S,CHA':;

SECTION_NUMBER 1
 '@S9S_MB_2U_LIB.S9S_MB_2U(SCH_1):PAGE583_I38@PURE_QUANTA.Q_CAP(CHIPS)':
 C_PATH='@s9s_mb_2u_lib.s9s_mb_2u(sch_1):page583_i38@pure_quanta.q_cap(chips)';

PART_NAME
 PC329 'Q_CAP_C0402-1UF,16V,10%,X6S,CHA':;

SECTION_NUMBER 1
 '@S9S_MB_2U_LIB.S9S_MB_2U(SCH_1):PAGE583_I20@PURE_QUANTA.Q_CAP(CHIPS)':
 C_PATH='@s9s_mb_2u_lib.s9s_mb_2u(sch_1):page583_i20@pure_quanta.q_cap(chips)';

PART_NAME
 PC328 'Q_CAP_C0402-100NF,50V,10%,X7R,A':;

SECTION_NUMBER 1
 '@S9S_MB_2U_LIB.S9S_MB_2U(SCH_1):PAGE583_I151@PURE_QUANTA.Q_CAP(CHIPS)':
 C_PATH='@s9s_mb_2u_lib.s9s_mb_2u(sch_1):page583_i151@pure_quanta.q_cap(chips)';

PART_NAME
 PC327 'Q_CAP_C0603-10UF,4V,20%,EMPTY,A':;

SECTION_NUMBER 1
 '@S9S_MB_2U_LIB.S9S_MB_2U(SCH_1):PAGE583_I150@PURE_QUANTA.Q_CAP(CHIPS)':
 C_PATH='@s9s_mb_2u_lib.s9s_mb_2u(sch_1):page583_i150@pure_quanta.q_cap(chips)';

PART_NAME
 JP1 'CONN3_210HP1030BR1-CONN3_210-HA':;

SECTION_NUMBER 1
 '@S9S_MB_2U_LIB.S9S_MB_2U(SCH_1):PAGE583_I10@PURE_QUANTA.CONN3_210HP1030BR1(CHIPS)':
 C_PATH='@s9s_mb_2u_lib.s9s_mb_2u(sch_1):page583_i10@pure_quanta.conn3_210hp1030br~
1(chips)';

PART_NAME
 J86 'DELTA_L-DELTA-L,THLF,EMPTY,TP24':;

SECTION_NUMBER 1
 '@S9S_MB_2U_LIB.S9S_MB_2U(SCH_1):PAGE611_I66@PURE_QUANTA.DELTA_L(CHIPS)':
 C_PATH='@s9s_mb_2u_lib.s9s_mb_2u(sch_1):page611_i66@pure_quanta.delta_l(chips)';

PART_NAME
 J85 'DELTA_L-DELTA-L,THLF,EMPTY,TP24':;

SECTION_NUMBER 1
 '@S9S_MB_2U_LIB.S9S_MB_2U(SCH_1):PAGE611_I67@PURE_QUANTA.DELTA_L(CHIPS)':
 C_PATH='@s9s_mb_2u_lib.s9s_mb_2u(sch_1):page611_i67@pure_quanta.delta_l(chips)';

PART_NAME
 J84 'DELTA_L-DELTA-L,THLF,EMPTY,TP24':;

SECTION_NUMBER 1
 '@S9S_MB_2U_LIB.S9S_MB_2U(SCH_1):PAGE611_I68@PURE_QUANTA.DELTA_L(CHIPS)':
 C_PATH='@s9s_mb_2u_lib.s9s_mb_2u(sch_1):page611_i68@pure_quanta.delta_l(chips)';

PART_NAME
 J83 'DELTA_L-DELTA-L,THLF,EMPTY,TP24':;

SECTION_NUMBER 1
 '@S9S_MB_2U_LIB.S9S_MB_2U(SCH_1):PAGE611_I69@PURE_QUANTA.DELTA_L(CHIPS)':
 C_PATH='@s9s_mb_2u_lib.s9s_mb_2u(sch_1):page611_i69@pure_quanta.delta_l(chips)';

PART_NAME
 J82 'DELTA_L-DELTA-L,THLF,EMPTY,TP24':;

SECTION_NUMBER 1
 '@S9S_MB_2U_LIB.S9S_MB_2U(SCH_1):PAGE611_I70@PURE_QUANTA.DELTA_L(CHIPS)':
 C_PATH='@s9s_mb_2u_lib.s9s_mb_2u(sch_1):page611_i70@pure_quanta.delta_l(chips)';

PART_NAME
 J81 'DELTA_L-DELTA-L,THLF,EMPTY,TP24':;

SECTION_NUMBER 1
 '@S9S_MB_2U_LIB.S9S_MB_2U(SCH_1):PAGE611_I71@PURE_QUANTA.DELTA_L(CHIPS)':
 C_PATH='@s9s_mb_2u_lib.s9s_mb_2u(sch_1):page611_i71@pure_quanta.delta_l(chips)';

PART_NAME
 J80 'DELTA_L-DELTA-L,THLF,EMPTY,TP24':;

SECTION_NUMBER 1
 '@S9S_MB_2U_LIB.S9S_MB_2U(SCH_1):PAGE611_I32@PURE_QUANTA.DELTA_L(CHIPS)':
 C_PATH='@s9s_mb_2u_lib.s9s_mb_2u(sch_1):page611_i32@pure_quanta.delta_l(chips)';

PART_NAME
 J79 'DELTA_L-DELTA-L,THLF,EMPTY,TP24':;

SECTION_NUMBER 1
 '@S9S_MB_2U_LIB.S9S_MB_2U(SCH_1):PAGE611_I56@PURE_QUANTA.DELTA_L(CHIPS)':
 C_PATH='@s9s_mb_2u_lib.s9s_mb_2u(sch_1):page611_i56@pure_quanta.delta_l(chips)';

PART_NAME
 J78 'DELTA_L-DELTA-L,THLF,EMPTY,TP24':;

SECTION_NUMBER 1
 '@S9S_MB_2U_LIB.S9S_MB_2U(SCH_1):PAGE611_I52@PURE_QUANTA.DELTA_L(CHIPS)':
 C_PATH='@s9s_mb_2u_lib.s9s_mb_2u(sch_1):page611_i52@pure_quanta.delta_l(chips)';

PART_NAME
 J77 'DELTA_L-DELTA-L,THLF,EMPTY,TP24':;

SECTION_NUMBER 1
 '@S9S_MB_2U_LIB.S9S_MB_2U(SCH_1):PAGE611_I50@PURE_QUANTA.DELTA_L(CHIPS)':
 C_PATH='@s9s_mb_2u_lib.s9s_mb_2u(sch_1):page611_i50@pure_quanta.delta_l(chips)';

PART_NAME
 J76 'DELTA_L-DELTA-L,THLF,EMPTY,TP24':;

SECTION_NUMBER 1
 '@S9S_MB_2U_LIB.S9S_MB_2U(SCH_1):PAGE611_I33@PURE_QUANTA.DELTA_L(CHIPS)':
 C_PATH='@s9s_mb_2u_lib.s9s_mb_2u(sch_1):page611_i33@pure_quanta.delta_l(chips)';

PART_NAME
 J75 'DELTA_L-DELTA-L,THLF,EMPTY,TP24':;

SECTION_NUMBER 1
 '@S9S_MB_2U_LIB.S9S_MB_2U(SCH_1):PAGE611_I34@PURE_QUANTA.DELTA_L(CHIPS)':
 C_PATH='@s9s_mb_2u_lib.s9s_mb_2u(sch_1):page611_i34@pure_quanta.delta_l(chips)';

PART_NAME
 J74 'DELTA_L-DELTA-L,THLF,EMPTY,TP24':;

SECTION_NUMBER 1
 '@S9S_MB_2U_LIB.S9S_MB_2U(SCH_1):PAGE611_I65@PURE_QUANTA.DELTA_L(CHIPS)':
 C_PATH='@s9s_mb_2u_lib.s9s_mb_2u(sch_1):page611_i65@pure_quanta.delta_l(chips)';

PART_NAME
 J73 'DELTA_L-DELTA-L,THLF,EMPTY,TP24':;

SECTION_NUMBER 1
 '@S9S_MB_2U_LIB.S9S_MB_2U(SCH_1):PAGE611_I64@PURE_QUANTA.DELTA_L(CHIPS)':
 C_PATH='@s9s_mb_2u_lib.s9s_mb_2u(sch_1):page611_i64@pure_quanta.delta_l(chips)';

PART_NAME
 J72 'DELTA_L-DELTA-L,THLF,EMPTY,TP24':;

SECTION_NUMBER 1
 '@S9S_MB_2U_LIB.S9S_MB_2U(SCH_1):PAGE611_I63@PURE_QUANTA.DELTA_L(CHIPS)':
 C_PATH='@s9s_mb_2u_lib.s9s_mb_2u(sch_1):page611_i63@pure_quanta.delta_l(chips)';

PART_NAME
 J71 'DELTA_L-DELTA-L,THLF,EMPTY,TP24':;

SECTION_NUMBER 1
 '@S9S_MB_2U_LIB.S9S_MB_2U(SCH_1):PAGE611_I62@PURE_QUANTA.DELTA_L(CHIPS)':
 C_PATH='@s9s_mb_2u_lib.s9s_mb_2u(sch_1):page611_i62@pure_quanta.delta_l(chips)';

PART_NAME
 J70 'DELTA_L-DELTA-L,THLF,EMPTY,TP24':;

SECTION_NUMBER 1
 '@S9S_MB_2U_LIB.S9S_MB_2U(SCH_1):PAGE611_I61@PURE_QUANTA.DELTA_L(CHIPS)':
 C_PATH='@s9s_mb_2u_lib.s9s_mb_2u(sch_1):page611_i61@pure_quanta.delta_l(chips)';

PART_NAME
 J69 'DELTA_L-DELTA-L,THLF,EMPTY,TP24':;

SECTION_NUMBER 1
 '@S9S_MB_2U_LIB.S9S_MB_2U(SCH_1):PAGE611_I60@PURE_QUANTA.DELTA_L(CHIPS)':
 C_PATH='@s9s_mb_2u_lib.s9s_mb_2u(sch_1):page611_i60@pure_quanta.delta_l(chips)';

PART_NAME
 J68 'DELTA_L-DELTA-L,THLF,EMPTY,TP24':;

SECTION_NUMBER 1
 '@S9S_MB_2U_LIB.S9S_MB_2U(SCH_1):PAGE611_I31@PURE_QUANTA.DELTA_L(CHIPS)':
 C_PATH='@s9s_mb_2u_lib.s9s_mb_2u(sch_1):page611_i31@pure_quanta.delta_l(chips)';

PART_NAME
 J67 'DELTA_L-DELTA-L,THLF,EMPTY,TP24':;

SECTION_NUMBER 1
 '@S9S_MB_2U_LIB.S9S_MB_2U(SCH_1):PAGE611_I24@PURE_QUANTA.DELTA_L(CHIPS)':
 C_PATH='@s9s_mb_2u_lib.s9s_mb_2u(sch_1):page611_i24@pure_quanta.delta_l(chips)';

PART_NAME
 J66 'DELTA_L-DELTA-L,THLF,EMPTY,TP24':;

SECTION_NUMBER 1
 '@S9S_MB_2U_LIB.S9S_MB_2U(SCH_1):PAGE611_I9@PURE_QUANTA.DELTA_L(CHIPS)':
 C_PATH='@s9s_mb_2u_lib.s9s_mb_2u(sch_1):page611_i9@pure_quanta.delta_l(chips)';

PART_NAME
 J65 'DELTA_L-DELTA-L,THLF,EMPTY,TP24':;

SECTION_NUMBER 1
 '@S9S_MB_2U_LIB.S9S_MB_2U(SCH_1):PAGE611_I10@PURE_QUANTA.DELTA_L(CHIPS)':
 C_PATH='@s9s_mb_2u_lib.s9s_mb_2u(sch_1):page611_i10@pure_quanta.delta_l(chips)';

PART_NAME
 J64 'DELTA_L-DELTA-L,THLF,EMPTY,TP24':;

SECTION_NUMBER 1
 '@S9S_MB_2U_LIB.S9S_MB_2U(SCH_1):PAGE611_I5@PURE_QUANTA.DELTA_L(CHIPS)':
 C_PATH='@s9s_mb_2u_lib.s9s_mb_2u(sch_1):page611_i5@pure_quanta.delta_l(chips)';

PART_NAME
 J63 'DELTA_L-DELTA-L,THLF,EMPTY,TP24':;

SECTION_NUMBER 1
 '@S9S_MB_2U_LIB.S9S_MB_2U(SCH_1):PAGE611_I1@PURE_QUANTA.DELTA_L(CHIPS)':
 C_PATH='@s9s_mb_2u_lib.s9s_mb_2u(sch_1):page611_i1@pure_quanta.delta_l(chips)';

PART_NAME
 U19 'MOSFET_N_SMLF-BSS138K,BSS138K,A':;

SECTION_NUMBER 1
 '@S9S_MB_2U_LIB.S9S_MB_2U(SCH_1):PAGE569_I51@PURE_QUANTA.MOSFET_N(CHIPS)':
 C_PATH='@s9s_mb_2u_lib.s9s_mb_2u(sch_1):page569_i51@pure_quanta.mosfet_n(chips)';

PART_NAME
 R1941 'Q_RES_0402LF-33.2,1%,1/16W,CHIA':;

SECTION_NUMBER 1
 '@S9S_MB_2U_LIB.S9S_MB_2U(SCH_1):PAGE569_I84@PURE_QUANTA.Q_RES(CHIPS)':
 C_PATH='@s9s_mb_2u_lib.s9s_mb_2u(sch_1):page569_i84@pure_quanta.q_res(chips)';

PART_NAME
 R1940 'Q_RES_0402LF-33.2,1%,1/16W,CHIA':;

SECTION_NUMBER 1
 '@S9S_MB_2U_LIB.S9S_MB_2U(SCH_1):PAGE569_I81@PURE_QUANTA.Q_RES(CHIPS)':
 C_PATH='@s9s_mb_2u_lib.s9s_mb_2u(sch_1):page569_i81@pure_quanta.q_res(chips)';

PART_NAME
 R1836 'Q_RES_0402LF-0,5%,1/16W,CHIP,CA':;

SECTION_NUMBER 1
 '@S9S_MB_2U_LIB.S9S_MB_2U(SCH_1):PAGE569_I63@PURE_QUANTA.Q_RES(CHIPS)':
 C_PATH='@s9s_mb_2u_lib.s9s_mb_2u(sch_1):page569_i63@pure_quanta.q_res(chips)';

PART_NAME
 R1835 'Q_RES_0402LF-1K,1%,1/16W,CHIP,A':;

SECTION_NUMBER 1
 '@S9S_MB_2U_LIB.S9S_MB_2U(SCH_1):PAGE569_I65@PURE_QUANTA.Q_RES(CHIPS)':
 C_PATH='@s9s_mb_2u_lib.s9s_mb_2u(sch_1):page569_i65@pure_quanta.q_res(chips)';

PART_NAME
 R1834 'Q_RES_0402LF-0,5%,1/16W,CHIP,CA':;

SECTION_NUMBER 1
 '@S9S_MB_2U_LIB.S9S_MB_2U(SCH_1):PAGE569_I61@PURE_QUANTA.Q_RES(CHIPS)':
 C_PATH='@s9s_mb_2u_lib.s9s_mb_2u(sch_1):page569_i61@pure_quanta.q_res(chips)';

PART_NAME
 R1783 'Q_RES_0402LF-1K,5%,1/16W,EMPTYA':;

SECTION_NUMBER 1
 '@S9S_MB_2U_LIB.S9S_MB_2U(SCH_1):PAGE569_I75@PURE_QUANTA.Q_RES(CHIPS)':
 C_PATH='@s9s_mb_2u_lib.s9s_mb_2u(sch_1):page569_i75@pure_quanta.q_res(chips)';

PART_NAME
 R1782 'Q_RES_0402LF-1K,5%,1/16W,EMPTYA':;

SECTION_NUMBER 1
 '@S9S_MB_2U_LIB.S9S_MB_2U(SCH_1):PAGE569_I71@PURE_QUANTA.Q_RES(CHIPS)':
 C_PATH='@s9s_mb_2u_lib.s9s_mb_2u(sch_1):page569_i71@pure_quanta.q_res(chips)';

PART_NAME
 R1781 'Q_RES_0402LF-1K,5%,1/16W,EMPTYA':;

SECTION_NUMBER 1
 '@S9S_MB_2U_LIB.S9S_MB_2U(SCH_1):PAGE569_I74@PURE_QUANTA.Q_RES(CHIPS)':
 C_PATH='@s9s_mb_2u_lib.s9s_mb_2u(sch_1):page569_i74@pure_quanta.q_res(chips)';

PART_NAME
 R1780 'Q_RES_0402LF-1K,5%,1/16W,CHIP,A':;

SECTION_NUMBER 1
 '@S9S_MB_2U_LIB.S9S_MB_2U(SCH_1):PAGE569_I73@PURE_QUANTA.Q_RES(CHIPS)':
 C_PATH='@s9s_mb_2u_lib.s9s_mb_2u(sch_1):page569_i73@pure_quanta.q_res(chips)';

PART_NAME
 R1608 'Q_RES_0402LF-4.7K,1%,1/16W,EMPA':;

SECTION_NUMBER 1
 '@S9S_MB_2U_LIB.S9S_MB_2U(SCH_1):PAGE569_I14@PURE_QUANTA.Q_RES(CHIPS)':
 C_PATH='@s9s_mb_2u_lib.s9s_mb_2u(sch_1):page569_i14@pure_quanta.q_res(chips)';

PART_NAME
 R1540 'Q_RES_0402LF-100K,1%,1/16W,EMPA':;

SECTION_NUMBER 1
 '@S9S_MB_2U_LIB.S9S_MB_2U(SCH_1):PAGE569_I49@PURE_QUANTA.Q_RES(CHIPS)':
 C_PATH='@s9s_mb_2u_lib.s9s_mb_2u(sch_1):page569_i49@pure_quanta.q_res(chips)';

PART_NAME
 R1539 'Q_RES_0402LF-10K,1%,1/16W,CHIPA':;

SECTION_NUMBER 1
 '@S9S_MB_2U_LIB.S9S_MB_2U(SCH_1):PAGE569_I52@PURE_QUANTA.Q_RES(CHIPS)':
 C_PATH='@s9s_mb_2u_lib.s9s_mb_2u(sch_1):page569_i52@pure_quanta.q_res(chips)';

PART_NAME
 R1538 'Q_RES_0402LF-0,5%,1/16W,CHIP,CA':;

SECTION_NUMBER 1
 '@S9S_MB_2U_LIB.S9S_MB_2U(SCH_1):PAGE569_I46@PURE_QUANTA.Q_RES(CHIPS)':
 C_PATH='@s9s_mb_2u_lib.s9s_mb_2u(sch_1):page569_i46@pure_quanta.q_res(chips)';

PART_NAME
 R1537 'Q_RES_0402LF-0,5%,1/16W,CHIP,CA':;

SECTION_NUMBER 1
 '@S9S_MB_2U_LIB.S9S_MB_2U(SCH_1):PAGE569_I45@PURE_QUANTA.Q_RES(CHIPS)':
 C_PATH='@s9s_mb_2u_lib.s9s_mb_2u(sch_1):page569_i45@pure_quanta.q_res(chips)';

PART_NAME
 R952 'Q_RES_0402LF-4.7K,1%,1/16W,EMPA':;

SECTION_NUMBER 1
 '@S9S_MB_2U_LIB.S9S_MB_2U(SCH_1):PAGE569_I16@PURE_QUANTA.Q_RES(CHIPS)':
 C_PATH='@s9s_mb_2u_lib.s9s_mb_2u(sch_1):page569_i16@pure_quanta.q_res(chips)';

PART_NAME
 R951 'Q_RES_0402LF-0,5%,1/16W,CHIP,CA':;

SECTION_NUMBER 1
 '@S9S_MB_2U_LIB.S9S_MB_2U(SCH_1):PAGE569_I36@PURE_QUANTA.Q_RES(CHIPS)':
 C_PATH='@s9s_mb_2u_lib.s9s_mb_2u(sch_1):page569_i36@pure_quanta.q_res(chips)';

PART_NAME
 R950 'Q_RES_0402LF-33,5%,1/16W,CHIP,A':;

SECTION_NUMBER 1
 '@S9S_MB_2U_LIB.S9S_MB_2U(SCH_1):PAGE569_I34@PURE_QUANTA.Q_RES(CHIPS)':
 C_PATH='@s9s_mb_2u_lib.s9s_mb_2u(sch_1):page569_i34@pure_quanta.q_res(chips)';

PART_NAME
 R949 'Q_RES_0402LF-33,5%,1/16W,CHIP,A':;

SECTION_NUMBER 1
 '@S9S_MB_2U_LIB.S9S_MB_2U(SCH_1):PAGE569_I35@PURE_QUANTA.Q_RES(CHIPS)':
 C_PATH='@s9s_mb_2u_lib.s9s_mb_2u(sch_1):page569_i35@pure_quanta.q_res(chips)';

PART_NAME
 R948 'Q_RES_0402LF-0,5%,1/16W,CHIP,CA':;

SECTION_NUMBER 1
 '@S9S_MB_2U_LIB.S9S_MB_2U(SCH_1):PAGE569_I33@PURE_QUANTA.Q_RES(CHIPS)':
 C_PATH='@s9s_mb_2u_lib.s9s_mb_2u(sch_1):page569_i33@pure_quanta.q_res(chips)';

PART_NAME
 R473 'Q_RES_0402LF-0,5%,1/16W,CHIP,CA':;

SECTION_NUMBER 1
 '@S9S_MB_2U_LIB.S9S_MB_2U(SCH_1):PAGE569_I27@PURE_QUANTA.Q_RES(CHIPS)':
 C_PATH='@s9s_mb_2u_lib.s9s_mb_2u(sch_1):page569_i27@pure_quanta.q_res(chips)';

PART_NAME
 R472 'Q_RES_0402LF-0,5%,1/16W,CHIP,CA':;

SECTION_NUMBER 1
 '@S9S_MB_2U_LIB.S9S_MB_2U(SCH_1):PAGE569_I25@PURE_QUANTA.Q_RES(CHIPS)':
 C_PATH='@s9s_mb_2u_lib.s9s_mb_2u(sch_1):page569_i25@pure_quanta.q_res(chips)';

PART_NAME
 L12 'Q_INDUCTOR_SMLF-BLM15AG121SN1DA':;

SECTION_NUMBER 1
 '@S9S_MB_2U_LIB.S9S_MB_2U(SCH_1):PAGE569_I47@PURE_QUANTA.Q_INDUCTOR(CHIPS)':
 C_PATH='@s9s_mb_a_lib.s9s_mb_a(sch_1):page569_i47@pure_quanta.q_inductor(chips)~
';

PART_NAME
 L11 'Q_INDUCTOR_SMLF-BLM15AG121SN1DA':;

SECTION_NUMBER 1
 '@S9S_MB_2U_LIB.S9S_MB_2U(SCH_1):PAGE569_I39@PURE_QUANTA.Q_INDUCTOR(CHIPS)':
 C_PATH='@s9s_mb_a_lib.s9s_mb_a(sch_1):page569_i39@pure_quanta.q_inductor(chips)~
';

PART_NAME
 J53 'CONN20_HLH2103LA00D7H-CONN20_HA':;

SECTION_NUMBER 1
 '@S9S_MB_2U_LIB.S9S_MB_2U(SCH_1):PAGE569_I18@PURE_QUANTA.CONN20_HLH2103LA00D7H(CHIPS)':
 C_PATH='@s9s_mb_2u_lib.s9s_mb_2u(sch_1):page569_i18@pure_quanta.conn20_hlh2103la0~
0d7h(chips)';

PART_NAME
 J50 'CONN12_1014699712001LF-CONN12_A':;

SECTION_NUMBER 1
 '@S9S_MB_2U_LIB.S9S_MB_2U(SCH_1):PAGE569_I4@PURE_QUANTA.CONN12_1014699712001LF(CHIPS)':
 C_PATH='@s9s_mb_2u_lib.s9s_mb_2u(sch_1):page569_i4@pure_quanta.conn12_10146997120~
01lf(chips)';

PART_NAME
 J49 'CONN12_1014699712001LF-CONN12_A':;

SECTION_NUMBER 1
 '@S9S_MB_2U_LIB.S9S_MB_2U(SCH_1):PAGE569_I2@PURE_QUANTA.CONN12_1014699712001LF(CHIPS)':
 C_PATH='@s9s_mb_2u_lib.s9s_mb_2u(sch_1):page569_i2@pure_quanta.conn12_10146997120~
01lf(chips)';

PART_NAME
 J46 'CONN44_23220445-CONN44_2322044A':;

SECTION_NUMBER 1
 '@S9S_MB_2U_LIB.S9S_MB_2U(SCH_1):PAGE569_I60@PURE_QUANTA.CONN44_23220445(CHIPS)':
 C_PATH='@s9s_mb_2u_lib.s9s_mb_2u(sch_1):page569_i60@pure_quanta.conn44_23220445(c~
hips)';

PART_NAME
 R1646 'Q_RES_0402LF-4.7K,5%,1/16W,CHIA':;

SECTION_NUMBER 1
 '@S9S_MB_2U_LIB.S9S_MB_2U(SCH_1):PAGE568_I23@PURE_QUANTA.Q_RES(CHIPS)':
 C_PATH='@s9s_mb_2u_lib.s9s_mb_2u(sch_1):page568_i23@pure_quanta.q_res(chips)';

PART_NAME
 R1645 'Q_RES_0402LF-4.7K,5%,1/16W,CHIA':;

SECTION_NUMBER 1
 '@S9S_MB_2U_LIB.S9S_MB_2U(SCH_1):PAGE568_I20@PURE_QUANTA.Q_RES(CHIPS)':
 C_PATH='@s9s_mb_2u_lib.s9s_mb_2u(sch_1):page568_i20@pure_quanta.q_res(chips)';

PART_NAME
 R955 'Q_RES_0402LF-33,5%,1/16W,CHIP,A':;

SECTION_NUMBER 1
 '@S9S_MB_2U_LIB.S9S_MB_2U(SCH_1):PAGE568_I7@PURE_QUANTA.Q_RES(CHIPS)':
 C_PATH='@s9s_mb_2u_lib.s9s_mb_2u(sch_1):page568_i7@pure_quanta.q_res(chips)';

PART_NAME
 R724 'Q_RES_0402LF-33,5%,1/16W,CHIP,A':;

SECTION_NUMBER 1
 '@S9S_MB_2U_LIB.S9S_MB_2U(SCH_1):PAGE568_I3@PURE_QUANTA.Q_RES(CHIPS)':
 C_PATH='@s9s_mb_2u_lib.s9s_mb_2u(sch_1):page568_i3@pure_quanta.q_res(chips)';

PART_NAME
 R723 'Q_RES_0402LF-33,5%,1/16W,CHIP,A':;

SECTION_NUMBER 1
 '@S9S_MB_2U_LIB.S9S_MB_2U(SCH_1):PAGE568_I4@PURE_QUANTA.Q_RES(CHIPS)':
 C_PATH='@s9s_mb_2u_lib.s9s_mb_2u(sch_1):page568_i4@pure_quanta.q_res(chips)';

PART_NAME
 J45 'CONN24_HLH3127LA00J7H-CONN24_HA':;

SECTION_NUMBER 1
 '@S9S_MB_2U_LIB.S9S_MB_2U(SCH_1):PAGE568_I14@PURE_QUANTA.CONN24_HLH3127LA00J7H(CHIPS)':
 C_PATH='@s9s_mb_2u_lib.s9s_mb_2u(sch_1):page568_i14@pure_quanta.conn24_hlh3127la0~
0j7h(chips)';

PART_NAME
 J44 'CONN24_HLH3127LA00J7H-CONN24_HA':;

SECTION_NUMBER 1
 '@S9S_MB_2U_LIB.S9S_MB_2U(SCH_1):PAGE568_I11@PURE_QUANTA.CONN24_HLH3127LA00J7H(CHIPS)':
 C_PATH='@s9s_mb_2u_lib.s9s_mb_2u(sch_1):page568_i11@pure_quanta.conn24_hlh3127la0~
0j7h(chips)';

PART_NAME
 H55 'HOLE_TH-EMPTY,HOLE1087':;

SECTION_NUMBER 1
 '@S9S_MB_2U_LIB.S9S_MB_2U(SCH_1):PAGE612_I59@PURE_QUANTA.HOLE(CHIPS)':
 C_PATH='@s9s_mb_2u_lib.s9s_mb_2u(sch_1):page612_i59@pure_quanta.hole(chips)';

PART_NAME
 H54 'HOLE_TH-EMPTY,HOLE1087':;

SECTION_NUMBER 1
 '@S9S_MB_2U_LIB.S9S_MB_2U(SCH_1):PAGE612_I58@PURE_QUANTA.HOLE(CHIPS)':
 C_PATH='@s9s_mb_2u_lib.s9s_mb_2u(sch_1):page612_i58@pure_quanta.hole(chips)';

PART_NAME
 H49 'HOLE_TH-EMPTY,HOLE1199':;

SECTION_NUMBER 1
 '@S9S_MB_2U_LIB.S9S_MB_2U(SCH_1):PAGE612_I53@PURE_QUANTA.HOLE(CHIPS)':
 C_PATH='@s9s_mb_2u_lib.s9s_mb_2u(sch_1):page612_i53@pure_quanta.hole(chips)';

PART_NAME
 H47 'HOLE_TH-EMPTY,HOLE1199':;

SECTION_NUMBER 1
 '@S9S_MB_2U_LIB.S9S_MB_2U(SCH_1):PAGE612_I52@PURE_QUANTA.HOLE(CHIPS)':
 C_PATH='@s9s_mb_2u_lib.s9s_mb_2u(sch_1):page612_i52@pure_quanta.hole(chips)';

PART_NAME
 H45 'HOLE_TH-EMPTY,HOLE1199':;

SECTION_NUMBER 1
 '@S9S_MB_2U_LIB.S9S_MB_2U(SCH_1):PAGE612_I48@PURE_QUANTA.HOLE(CHIPS)':
 C_PATH='@s9s_mb_2u_lib.s9s_mb_2u(sch_1):page612_i48@pure_quanta.hole(chips)';

PART_NAME
 H44 'HOLE_TH-EMPTY,HOLE1199':;

SECTION_NUMBER 1
 '@S9S_MB_2U_LIB.S9S_MB_2U(SCH_1):PAGE612_I49@PURE_QUANTA.HOLE(CHIPS)':
 C_PATH='@s9s_mb_2u_lib.s9s_mb_2u(sch_1):page612_i49@pure_quanta.hole(chips)';

PART_NAME
 H43 'HOLE_TH-EMPTY,HOLE1068':;

SECTION_NUMBER 1
 '@S9S_MB_2U_LIB.S9S_MB_2U(SCH_1):PAGE612_I47@PURE_QUANTA.HOLE(CHIPS)':
 C_PATH='@s9s_mb_2u_lib.s9s_mb_2u(sch_1):page612_i47@pure_quanta.hole(chips)';

PART_NAME
 H42 'HOLE_TH-EMPTY,HOLE1068':;

SECTION_NUMBER 1
 '@S9S_MB_2U_LIB.S9S_MB_2U(SCH_1):PAGE612_I46@PURE_QUANTA.HOLE(CHIPS)':
 C_PATH='@s9s_mb_2u_lib.s9s_mb_2u(sch_1):page612_i46@pure_quanta.hole(chips)';

PART_NAME
 H41 'HOLE_TH-EMPTY,HOLE1068':;

SECTION_NUMBER 1
 '@S9S_MB_2U_LIB.S9S_MB_2U(SCH_1):PAGE612_I45@PURE_QUANTA.HOLE(CHIPS)':
 C_PATH='@s9s_mb_2u_lib.s9s_mb_2u(sch_1):page612_i45@pure_quanta.hole(chips)';

PART_NAME
 H40 'HOLE_TH-EMPTY,HOLE693':;

SECTION_NUMBER 1
 '@S9S_MB_2U_LIB.S9S_MB_2U(SCH_1):PAGE612_I43@PURE_QUANTA.HOLE(CHIPS)':
 C_PATH='@s9s_mb_2u_lib.s9s_mb_2u(sch_1):page612_i43@pure_quanta.hole(chips)';

PART_NAME
 H39 'HOLE_TH-EMPTY,HOLE693':;

SECTION_NUMBER 1
 '@S9S_MB_2U_LIB.S9S_MB_2U(SCH_1):PAGE612_I41@PURE_QUANTA.HOLE(CHIPS)':
 C_PATH='@s9s_mb_2u_lib.s9s_mb_2u(sch_1):page612_i41@pure_quanta.hole(chips)';

PART_NAME
 H38 'HOLE_TH-EMPTY,TMP-Q_HOLE78':;

SECTION_NUMBER 1
 '@S9S_MB_2U_LIB.S9S_MB_2U(SCH_1):PAGE612_I38@PURE_QUANTA.HOLE(CHIPS)':
 C_PATH='@s9s_mb_2u_lib.s9s_mb_2u(sch_1):page612_i38@pure_quanta.hole(chips)';

PART_NAME
 H37 'HOLE_TH-EMPTY,HOLE1098':;

SECTION_NUMBER 1
 '@S9S_MB_2U_LIB.S9S_MB_2U(SCH_1):PAGE612_I36@PURE_QUANTA.HOLE(CHIPS)':
 C_PATH='@s9s_mb_2u_lib.s9s_mb_2u(sch_1):page612_i36@pure_quanta.hole(chips)';

PART_NAME
 H36 'HOLE_TH-EMPTY,TMP-Q_HOLE78':;

SECTION_NUMBER 1
 '@S9S_MB_2U_LIB.S9S_MB_2U(SCH_1):PAGE612_I37@PURE_QUANTA.HOLE(CHIPS)':
 C_PATH='@s9s_mb_2u_lib.s9s_mb_2u(sch_1):page612_i37@pure_quanta.hole(chips)';

PART_NAME
 H35 'HOLE_TH-EMPTY,HOLE1098':;

SECTION_NUMBER 1
 '@S9S_MB_2U_LIB.S9S_MB_2U(SCH_1):PAGE612_I35@PURE_QUANTA.HOLE(CHIPS)':
 C_PATH='@s9s_mb_2u_lib.s9s_mb_2u(sch_1):page612_i35@pure_quanta.hole(chips)';

PART_NAME
 H34 'HOLE_TH-EMPTY,HOLE491':;

SECTION_NUMBER 1
 '@S9S_MB_2U_LIB.S9S_MB_2U(SCH_1):PAGE612_I34@PURE_QUANTA.HOLE(CHIPS)':
 C_PATH='@s9s_mb_2u_lib.s9s_mb_2u(sch_1):page612_i34@pure_quanta.hole(chips)';

PART_NAME
 H33 'HOLE_TH-EMPTY,HOLE491':;

SECTION_NUMBER 1
 '@S9S_MB_2U_LIB.S9S_MB_2U(SCH_1):PAGE612_I33@PURE_QUANTA.HOLE(CHIPS)':
 C_PATH='@s9s_mb_2u_lib.s9s_mb_2u(sch_1):page612_i33@pure_quanta.hole(chips)';

PART_NAME
 H32 'HOLE_TH-EMPTY,HOLE1214':;

SECTION_NUMBER 1
 '@S9S_MB_2U_LIB.S9S_MB_2U(SCH_1):PAGE612_I32@PURE_QUANTA.HOLE(CHIPS)':
 C_PATH='@s9s_mb_2u_lib.s9s_mb_2u(sch_1):page612_i32@pure_quanta.hole(chips)';

PART_NAME
 H31 'HOLE_TH-EMPTY,HOLE1214':;

SECTION_NUMBER 1
 '@S9S_MB_2U_LIB.S9S_MB_2U(SCH_1):PAGE612_I31@PURE_QUANTA.HOLE(CHIPS)':
 C_PATH='@s9s_mb_2u_lib.s9s_mb_2u(sch_1):page612_i31@pure_quanta.hole(chips)';

PART_NAME
 H30 'HOLE_TH-EMPTY,DUMMY50':;

SECTION_NUMBER 1
 '@S9S_MB_2U_LIB.S9S_MB_2U(SCH_1):PAGE612_I29@PURE_QUANTA.HOLE(CHIPS)':
 C_PATH='@s9s_mb_2u_lib.s9s_mb_2u(sch_1):page612_i29@pure_quanta.hole(chips)';

PART_NAME
 H29 'HOLE_TH-EMPTY,DUMMY50':;

SECTION_NUMBER 1
 '@S9S_MB_2U_LIB.S9S_MB_2U(SCH_1):PAGE612_I30@PURE_QUANTA.HOLE(CHIPS)':
 C_PATH='@s9s_mb_2u_lib.s9s_mb_2u(sch_1):page612_i30@pure_quanta.hole(chips)';

PART_NAME
 H28 'HOLE_TH-EMPTY,DUMMY50':;

SECTION_NUMBER 1
 '@S9S_MB_2U_LIB.S9S_MB_2U(SCH_1):PAGE612_I28@PURE_QUANTA.HOLE(CHIPS)':
 C_PATH='@s9s_mb_2u_lib.s9s_mb_2u(sch_1):page612_i28@pure_quanta.hole(chips)';

PART_NAME
 H27 'HOLE_TH-EMPTY,DUMMY50':;

SECTION_NUMBER 1
 '@S9S_MB_2U_LIB.S9S_MB_2U(SCH_1):PAGE612_I27@PURE_QUANTA.HOLE(CHIPS)':
 C_PATH='@s9s_mb_2u_lib.s9s_mb_2u(sch_1):page612_i27@pure_quanta.hole(chips)';

PART_NAME
 H26 'HOLE_TH-EMPTY,HOLE1079':;

SECTION_NUMBER 1
 '@S9S_MB_2U_LIB.S9S_MB_2U(SCH_1):PAGE612_I23@PURE_QUANTA.HOLE(CHIPS)':
 C_PATH='@s9s_mb_2u_lib.s9s_mb_2u(sch_1):page612_i23@pure_quanta.hole(chips)';

PART_NAME
 H25 'HOLE_TH-EMPTY,HOLE1079':;

SECTION_NUMBER 1
 '@S9S_MB_2U_LIB.S9S_MB_2U(SCH_1):PAGE612_I20@PURE_QUANTA.HOLE(CHIPS)':
 C_PATH='@s9s_mb_2u_lib.s9s_mb_2u(sch_1):page612_i20@pure_quanta.hole(chips)';

PART_NAME
 H24 'HOLE_TH-EMPTY,HOLE1079':;

SECTION_NUMBER 1
 '@S9S_MB_2U_LIB.S9S_MB_2U(SCH_1):PAGE612_I24@PURE_QUANTA.HOLE(CHIPS)':
 C_PATH='@s9s_mb_2u_lib.s9s_mb_2u(sch_1):page612_i24@pure_quanta.hole(chips)';

PART_NAME
 H23 'HOLE_TH-EMPTY,HOLE1079':;

SECTION_NUMBER 1
 '@S9S_MB_2U_LIB.S9S_MB_2U(SCH_1):PAGE612_I19@PURE_QUANTA.HOLE(CHIPS)':
 C_PATH='@s9s_mb_2u_lib.s9s_mb_2u(sch_1):page612_i19@pure_quanta.hole(chips)';

PART_NAME
 H22 'HOLE_TH-EMPTY,HOLE1079':;

SECTION_NUMBER 1
 '@S9S_MB_2U_LIB.S9S_MB_2U(SCH_1):PAGE612_I25@PURE_QUANTA.HOLE(CHIPS)':
 C_PATH='@s9s_mb_2u_lib.s9s_mb_2u(sch_1):page612_i25@pure_quanta.hole(chips)';

PART_NAME
 H21 'HOLE_TH-EMPTY,HOLE1079':;

SECTION_NUMBER 1
 '@S9S_MB_2U_LIB.S9S_MB_2U(SCH_1):PAGE612_I17@PURE_QUANTA.HOLE(CHIPS)':
 C_PATH='@s9s_mb_2u_lib.s9s_mb_2u(sch_1):page612_i17@pure_quanta.hole(chips)';

PART_NAME
 H20 'HOLE_TH-EMPTY,HOLE1079':;

SECTION_NUMBER 1
 '@S9S_MB_2U_LIB.S9S_MB_2U(SCH_1):PAGE612_I26@PURE_QUANTA.HOLE(CHIPS)':
 C_PATH='@s9s_mb_2u_lib.s9s_mb_2u(sch_1):page612_i26@pure_quanta.hole(chips)';

PART_NAME
 H19 'HOLE_TH-EMPTY,HOLE1079':;

SECTION_NUMBER 1
 '@S9S_MB_2U_LIB.S9S_MB_2U(SCH_1):PAGE612_I18@PURE_QUANTA.HOLE(CHIPS)':
 C_PATH='@s9s_mb_2u_lib.s9s_mb_2u(sch_1):page612_i18@pure_quanta.hole(chips)';

PART_NAME
 H18 'HOLE_TH-EMPTY,HOLE1079':;

SECTION_NUMBER 1
 '@S9S_MB_2U_LIB.S9S_MB_2U(SCH_1):PAGE612_I22@PURE_QUANTA.HOLE(CHIPS)':
 C_PATH='@s9s_mb_2u_lib.s9s_mb_2u(sch_1):page612_i22@pure_quanta.hole(chips)';

PART_NAME
 H17 'HOLE_TH-EMPTY,HOLE1079':;

SECTION_NUMBER 1
 '@S9S_MB_2U_LIB.S9S_MB_2U(SCH_1):PAGE612_I16@PURE_QUANTA.HOLE(CHIPS)':
 C_PATH='@s9s_mb_2u_lib.s9s_mb_2u(sch_1):page612_i16@pure_quanta.hole(chips)';

PART_NAME
 H16 'HOLE_TH-EMPTY,HOLE1079':;

SECTION_NUMBER 1
 '@S9S_MB_2U_LIB.S9S_MB_2U(SCH_1):PAGE612_I21@PURE_QUANTA.HOLE(CHIPS)':
 C_PATH='@s9s_mb_2u_lib.s9s_mb_2u(sch_1):page612_i21@pure_quanta.hole(chips)';

PART_NAME
 H15 'HOLE_TH-EMPTY,HOLE1079':;

SECTION_NUMBER 1
 '@S9S_MB_2U_LIB.S9S_MB_2U(SCH_1):PAGE612_I15@PURE_QUANTA.HOLE(CHIPS)':
 C_PATH='@s9s_mb_2u_lib.s9s_mb_2u(sch_1):page612_i15@pure_quanta.hole(chips)';

PART_NAME
 H13 'HOLE_TH-EMPTY,HOLE1087':;

SECTION_NUMBER 1
 '@S9S_MB_2U_LIB.S9S_MB_2U(SCH_1):PAGE612_I2@PURE_QUANTA.HOLE(CHIPS)':
 C_PATH='@s9s_mb_2u_lib.s9s_mb_2u(sch_1):page612_i2@pure_quanta.hole(chips)';

PART_NAME
 H12 'HOLE_TH-EMPTY,HOLE1087':;

SECTION_NUMBER 1
 '@S9S_MB_2U_LIB.S9S_MB_2U(SCH_1):PAGE612_I4@PURE_QUANTA.HOLE(CHIPS)':
 C_PATH='@s9s_mb_2u_lib.s9s_mb_2u(sch_1):page612_i4@pure_quanta.hole(chips)';

PART_NAME
 H11 'HOLE_TH-EMPTY,HOLE1087':;

SECTION_NUMBER 1
 '@S9S_MB_2U_LIB.S9S_MB_2U(SCH_1):PAGE612_I3@PURE_QUANTA.HOLE(CHIPS)':
 C_PATH='@s9s_mb_2u_lib.s9s_mb_2u(sch_1):page612_i3@pure_quanta.hole(chips)';

PART_NAME
 H10 'HOLE_TH-EMPTY,HOLE1087':;

SECTION_NUMBER 1
 '@S9S_MB_2U_LIB.S9S_MB_2U(SCH_1):PAGE612_I6@PURE_QUANTA.HOLE(CHIPS)':
 C_PATH='@s9s_mb_2u_lib.s9s_mb_2u(sch_1):page612_i6@pure_quanta.hole(chips)';

PART_NAME
 H9 'HOLE_TH-EMPTY,HOLE1087':;

SECTION_NUMBER 1
 '@S9S_MB_2U_LIB.S9S_MB_2U(SCH_1):PAGE612_I5@PURE_QUANTA.HOLE(CHIPS)':
 C_PATH='@s9s_mb_2u_lib.s9s_mb_2u(sch_1):page612_i5@pure_quanta.hole(chips)';

PART_NAME
 H8 'HOLE_TH-EMPTY,HOLE1087':;

SECTION_NUMBER 1
 '@S9S_MB_2U_LIB.S9S_MB_2U(SCH_1):PAGE612_I8@PURE_QUANTA.HOLE(CHIPS)':
 C_PATH='@s9s_mb_2u_lib.s9s_mb_2u(sch_1):page612_i8@pure_quanta.hole(chips)';

PART_NAME
 H7 'HOLE_TH-EMPTY,HOLE1087':;

SECTION_NUMBER 1
 '@S9S_MB_2U_LIB.S9S_MB_2U(SCH_1):PAGE612_I7@PURE_QUANTA.HOLE(CHIPS)':
 C_PATH='@s9s_mb_2u_lib.s9s_mb_2u(sch_1):page612_i7@pure_quanta.hole(chips)';

PART_NAME
 H6 'HOLE_TH-EMPTY,HOLE1087':;

SECTION_NUMBER 1
 '@S9S_MB_2U_LIB.S9S_MB_2U(SCH_1):PAGE612_I10@PURE_QUANTA.HOLE(CHIPS)':
 C_PATH='@s9s_mb_2u_lib.s9s_mb_2u(sch_1):page612_i10@pure_quanta.hole(chips)';

PART_NAME
 H5 'HOLE_TH-EMPTY,HOLE1087':;

SECTION_NUMBER 1
 '@S9S_MB_2U_LIB.S9S_MB_2U(SCH_1):PAGE612_I9@PURE_QUANTA.HOLE(CHIPS)':
 C_PATH='@s9s_mb_2u_lib.s9s_mb_2u(sch_1):page612_i9@pure_quanta.hole(chips)';

PART_NAME
 H4 'HOLE_TH-EMPTY,HOLE1087':;

SECTION_NUMBER 1
 '@S9S_MB_2U_LIB.S9S_MB_2U(SCH_1):PAGE612_I13@PURE_QUANTA.HOLE(CHIPS)':
 C_PATH='@s9s_mb_2u_lib.s9s_mb_2u(sch_1):page612_i13@pure_quanta.hole(chips)';

PART_NAME
 H3 'HOLE_TH-EMPTY,HOLE1087':;

SECTION_NUMBER 1
 '@S9S_MB_2U_LIB.S9S_MB_2U(SCH_1):PAGE612_I11@PURE_QUANTA.HOLE(CHIPS)':
 C_PATH='@s9s_mb_2u_lib.s9s_mb_2u(sch_1):page612_i11@pure_quanta.hole(chips)';

PART_NAME
 H2 'HOLE_TH-EMPTY,HOLE1087':;

SECTION_NUMBER 1
 '@S9S_MB_2U_LIB.S9S_MB_2U(SCH_1):PAGE612_I14@PURE_QUANTA.HOLE(CHIPS)':
 C_PATH='@s9s_mb_2u_lib.s9s_mb_2u(sch_1):page612_i14@pure_quanta.hole(chips)';

PART_NAME
 H1 'HOLE_TH-EMPTY,HOLE1087':;

SECTION_NUMBER 1
 '@S9S_MB_2U_LIB.S9S_MB_2U(SCH_1):PAGE612_I12@PURE_QUANTA.HOLE(CHIPS)':
 C_PATH='@s9s_mb_2u_lib.s9s_mb_2u(sch_1):page612_i12@pure_quanta.hole(chips)';

PART_NAME
 ME8 'DUMMY_SYMBOL-QUANTA_LOGO_7X26,A':;

SECTION_NUMBER 1
 '@S9S_MB_2U_LIB.S9S_MB_2U(SCH_1):PAGE613_I19@PURE_QUANTA.DUMMY_SYMBOL(CHIPS)':
 C_PATH='@s9s_mb_2u_lib.s9s_mb_2u(sch_1):page613_i19@pure_quanta.dummy_symbol(chip~
s)';

PART_NAME
 ME7 'ME_DUMMY_SYMBOL-PICKUP_SMDC10,A':;

SECTION_NUMBER -1
 '@S9S_MB_2U_LIB.S9S_MB_2U(SCH_1):PAGE613_I2@PURE_QUANTA.ME_DUMMY_SYMBOL(CHIPS)':
 C_PATH='@s9s_mb_2u_lib.s9s_mb_2u(sch_1):page613_i2@pure_quanta.me_dummy_symbol(ch~
ips)';

PART_NAME
 ME6 'ME_DUMMY_SYMBOL-PICKUP_SMDC10,A':;

SECTION_NUMBER -1
 '@S9S_MB_2U_LIB.S9S_MB_2U(SCH_1):PAGE613_I4@PURE_QUANTA.ME_DUMMY_SYMBOL(CHIPS)':
 C_PATH='@s9s_mb_2u_lib.s9s_mb_2u(sch_1):page613_i4@pure_quanta.me_dummy_symbol(ch~
ips)';

PART_NAME
 ME5 'ME_DUMMY_SYMBOL-PICKUP_SMDC10,A':;

SECTION_NUMBER -1
 '@S9S_MB_2U_LIB.S9S_MB_2U(SCH_1):PAGE613_I3@PURE_QUANTA.ME_DUMMY_SYMBOL(CHIPS)':
 C_PATH='@s9s_mb_2u_lib.s9s_mb_2u(sch_1):page613_i3@pure_quanta.me_dummy_symbol(ch~
ips)';

PART_NAME
 ME4 'ME_DUMMY_SYMBOL-PICKUP_SMDC20,A':;

SECTION_NUMBER -1
 '@S9S_MB_2U_LIB.S9S_MB_2U(SCH_1):PAGE613_I9@PURE_QUANTA.ME_DUMMY_SYMBOL(CHIPS)':
 C_PATH='@s9s_mb_2u_lib.s9s_mb_2u(sch_1):page613_i9@pure_quanta.me_dummy_symbol(ch~
ips)';

PART_NAME
 ME3 'ME_DUMMY_SYMBOL-PICKUP_SMDC20,A':;

SECTION_NUMBER -1
 '@S9S_MB_2U_LIB.S9S_MB_2U(SCH_1):PAGE613_I11@PURE_QUANTA.ME_DUMMY_SYMBOL(CHIPS)':
 C_PATH='@s9s_mb_2u_lib.s9s_mb_2u(sch_1):page613_i11@pure_quanta.me_dummy_symbol(c~
hips)';

PART_NAME
 ME2 'ME_DUMMY_SYMBOL-PICKUP_SMDC20,A':;

SECTION_NUMBER -1
 '@S9S_MB_2U_LIB.S9S_MB_2U(SCH_1):PAGE613_I10@PURE_QUANTA.ME_DUMMY_SYMBOL(CHIPS)':
 C_PATH='@s9s_mb_2u_lib.s9s_mb_2u(sch_1):page613_i10@pure_quanta.me_dummy_symbol(c~
hips)';

PART_NAME
 DM16 'DUMMY_SYMBOL-PCB_VENDOR_LOGO_1A':;

SECTION_NUMBER 1
 '@S9S_MB_2U_LIB.S9S_MB_2U(SCH_1):PAGE613_I1@PURE_QUANTA.DUMMY_SYMBOL(CHIPS)':
 C_PATH='@s9s_mb_2u_lib.s9s_mb_2u(sch_1):page613_i1@pure_quanta.dummy_symbol(chips~
)';

PART_NAME
 DM15 'DUMMY_SYMBOL-BARCODE,MECH,EMPTA':;

SECTION_NUMBER 1
 '@S9S_MB_2U_LIB.S9S_MB_2U(SCH_1):PAGE613_I5@PURE_QUANTA.DUMMY_SYMBOL(CHIPS)':
 C_PATH='@s9s_mb_2u_lib.s9s_mb_2u(sch_1):page613_i5@pure_quanta.dummy_symbol(chips~
)';

PART_NAME
 DM14 'DUMMY_SYMBOL-BARCODE,MECH,EMPTA':;

SECTION_NUMBER 1
 '@S9S_MB_2U_LIB.S9S_MB_2U(SCH_1):PAGE613_I6@PURE_QUANTA.DUMMY_SYMBOL(CHIPS)':
 C_PATH='@s9s_mb_2u_lib.s9s_mb_2u(sch_1):page613_i6@pure_quanta.dummy_symbol(chips~
)';

PART_NAME
 DM13 'DUMMY_SYMBOL-BATTERY_SYMBOL,MEA':;

SECTION_NUMBER 1
 '@S9S_MB_2U_LIB.S9S_MB_2U(SCH_1):PAGE613_I13@PURE_QUANTA.DUMMY_SYMBOL(CHIPS)':
 C_PATH='@s9s_mb_2u_lib.s9s_mb_2u(sch_1):page613_i13@pure_quanta.dummy_symbol(chip~
s)';

PART_NAME
 DM10 'DUMMY_SYMBOL-PCBA_LABEL_15X5,MA':;

SECTION_NUMBER 1
 '@S9S_MB_2U_LIB.S9S_MB_2U(SCH_1):PAGE613_I8@PURE_QUANTA.DUMMY_SYMBOL(CHIPS)':
 C_PATH='@s9s_mb_2u_lib.s9s_mb_2u(sch_1):page613_i8@pure_quanta.dummy_symbol(chips~
)';

PART_NAME
 DM9 'DUMMY_SYMBOL-MECHANIC_SYMBOL,MA':;

SECTION_NUMBER 1
 '@S9S_MB_2U_LIB.S9S_MB_2U(SCH_1):PAGE613_I17@PURE_QUANTA.DUMMY_SYMBOL(CHIPS)':
 C_PATH='@s9s_mb_2u_lib.s9s_mb_2u(sch_1):page613_i17@pure_quanta.dummy_symbol(chip~
s)';

PART_NAME
 DM8 'DUMMY_SYMBOL-EFI BIOS LABEL,MEA':;

SECTION_NUMBER 1
 '@S9S_MB_2U_LIB.S9S_MB_2U(SCH_1):PAGE613_I18@PURE_QUANTA.DUMMY_SYMBOL(CHIPS)':
 C_PATH='@s9s_mb_2u_lib.s9s_mb_2u(sch_1):page613_i18@pure_quanta.dummy_symbol(chip~
s)';

PART_NAME
 DM7 'DUMMY_SYMBOL-PB-E1_SMALL,MECH,A':;

SECTION_NUMBER 1
 '@S9S_MB_2U_LIB.S9S_MB_2U(SCH_1):PAGE613_I14@PURE_QUANTA.DUMMY_SYMBOL(CHIPS)':
 C_PATH='@s9s_mb_2u_lib.s9s_mb_2u(sch_1):page613_i14@pure_quanta.dummy_symbol(chip~
s)';

PART_NAME
 DM4 'DUMMY_SYMBOL-WEEE,MECH,EMPTY,DA':;

SECTION_NUMBER 1
 '@S9S_MB_2U_LIB.S9S_MB_2U(SCH_1):PAGE613_I15@PURE_QUANTA.DUMMY_SYMBOL(CHIPS)':
 C_PATH='@s9s_mb_2u_lib.s9s_mb_2u(sch_1):page613_i15@pure_quanta.dummy_symbol(chip~
s)';

PART_NAME
 R1841 'Q_RES_0402LF-10K,1%,1/16W,EMPTA':;

SECTION_NUMBER 1
 '@S9S_MB_2U_LIB.S9S_MB_2U(SCH_1):PAGE544_I156@PURE_QUANTA.Q_RES(CHIPS)':
 C_PATH='@s9s_mb_2u_lib.s9s_mb_2u(sch_1):page544_i156@pure_quanta.q_res(chips)';

PART_NAME
 R1725 'Q_RES_0402LF-33.2,1%,1/16W,CHIA':;

SECTION_NUMBER 1
 '@S9S_MB_2U_LIB.S9S_MB_2U(SCH_1):PAGE544_I133@PURE_QUANTA.Q_RES(CHIPS)':
 C_PATH='@s9s_mb_2u_lib.s9s_mb_2u(sch_1):page544_i133@pure_quanta.q_res(chips)';

PART_NAME
 R1560 'Q_RES_0402LF-0,5%,1/16W,EMPTY,A':;

SECTION_NUMBER 1
 '@S9S_MB_2U_LIB.S9S_MB_2U(SCH_1):PAGE544_I112@PURE_QUANTA.Q_RES(CHIPS)':
 C_PATH='@s9s_mb_2u_lib.s9s_mb_2u(sch_1):page544_i112@pure_quanta.q_res(chips)';

PART_NAME
 R1559 'Q_RES_0402LF-0,5%,1/16W,EMPTY,A':;

SECTION_NUMBER 1
 '@S9S_MB_2U_LIB.S9S_MB_2U(SCH_1):PAGE544_I111@PURE_QUANTA.Q_RES(CHIPS)':
 C_PATH='@s9s_mb_2u_lib.s9s_mb_2u(sch_1):page544_i111@pure_quanta.q_res(chips)';

PART_NAME
 R1550 'Q_RES_0402LF-4.7K,1%,1/16W,CHIA':;

SECTION_NUMBER 1
 '@S9S_MB_2U_LIB.S9S_MB_2U(SCH_1):PAGE544_I137@PURE_QUANTA.Q_RES(CHIPS)':
 C_PATH='@s9s_mb_2u_lib.s9s_mb_2u(sch_1):page544_i137@pure_quanta.q_res(chips)';

PART_NAME
 R1549 'Q_RES_0402LF-4.7K,1%,1/16W,CHIA':;

SECTION_NUMBER 1
 '@S9S_MB_2U_LIB.S9S_MB_2U(SCH_1):PAGE544_I139@PURE_QUANTA.Q_RES(CHIPS)':
 C_PATH='@s9s_mb_2u_lib.s9s_mb_2u(sch_1):page544_i139@pure_quanta.q_res(chips)';

PART_NAME
 R700 'Q_RES_0402LF-0,5%,1/16W,CHIP,CA':;

SECTION_NUMBER 1
 '@S9S_MB_2U_LIB.S9S_MB_2U(SCH_1):PAGE544_I98@PURE_QUANTA.Q_RES(CHIPS)':
 C_PATH='@s9s_mb_2u_lib.s9s_mb_2u(sch_1):page544_i98@pure_quanta.q_res(chips)';

PART_NAME
 R366 'Q_RES_0402LF-332,1%,1/16W,CHIPA':;

SECTION_NUMBER 1
 '@S9S_MB_2U_LIB.S9S_MB_2U(SCH_1):PAGE544_I122@PURE_QUANTA.Q_RES(CHIPS)':
 C_PATH='@s9s_mb_2u_lib.s9s_mb_2u(sch_1):page544_i122@pure_quanta.q_res(chips)';

PART_NAME
 R365 'Q_RES_0402LF-0,5%,1/16W,CHIP,CA':;

SECTION_NUMBER 1
 '@S9S_MB_2U_LIB.S9S_MB_2U(SCH_1):PAGE544_I129@PURE_QUANTA.Q_RES(CHIPS)':
 C_PATH='@s9s_mb_2u_lib.s9s_mb_2u(sch_1):page544_i129@pure_quanta.q_res(chips)';

PART_NAME
 Q33 'MOSFET_PCH_GDS_ESD_PROTECTED-PA':;

SECTION_NUMBER 1
 '@S9S_MB_2U_LIB.S9S_MB_2U(SCH_1):PAGE544_I126@PURE_QUANTA.MOSFET_PCH_GDS_ESD_PROTECTED(CHIPS)':
 C_PATH='@s9s_mb_2u_lib.s9s_mb_2u(sch_1):page544_i126@pure_quanta.mosfet_pch_gds_e~
sd_protected(chips)';

PART_NAME
 D6 'Q_LED_SMLF-LED_RED,19-217/R6C-A':;

SECTION_NUMBER 1
 '@S9S_MB_2U_LIB.S9S_MB_2U(SCH_1):PAGE544_I124@PURE_QUANTA.Q_LED(CHIPS)':
 C_PATH='@s9s_mb_2u_lib.s9s_mb_2u(sch_1):page544_i124@pure_quanta.q_led(chips)';

PART_NAME
 R1928 'Q_RES_0402LF-10K,1%,1/16W,CHIPA':;

SECTION_NUMBER 1
 '@S9S_MB_2U_LIB.S9S_MB_2U(SCH_1):PAGE504_I442@PURE_QUANTA.Q_RES(CHIPS)':
 C_PATH='@s9s_mb_2u_lib.s9s_mb_2u(sch_1):page504_i442@pure_quanta.q_res(chips)';

PART_NAME
 R1927 'Q_RES_0402LF-0,5%,1/16W,CHIP,CA':;

SECTION_NUMBER 1
 '@S9S_MB_2U_LIB.S9S_MB_2U(SCH_1):PAGE504_I441@PURE_QUANTA.Q_RES(CHIPS)':
 C_PATH='@s9s_mb_2u_lib.s9s_mb_2u(sch_1):page504_i441@pure_quanta.q_res(chips)';

PART_NAME
 R1674 'Q_RES_0402LF-0,5%,1/16W,CHIP,CA':;

SECTION_NUMBER 1
 '@S9S_MB_2U_LIB.S9S_MB_2U(SCH_1):PAGE504_I437@PURE_QUANTA.Q_RES(CHIPS)':
 C_PATH='@s9s_mb_2u_lib.s9s_mb_2u(sch_1):page504_i437@pure_quanta.q_res(chips)';

PART_NAME
 R503 'Q_RES_0402LF-100,1%,1/16W,CHIPA':;

SECTION_NUMBER 1
 '@S9S_MB_2U_LIB.S9S_MB_2U(SCH_1):PAGE504_I432@PURE_QUANTA.Q_RES(CHIPS)':
 C_PATH='@s9s_mb_2u_lib.s9s_mb_2u(sch_1):page504_i432@pure_quanta.q_res(chips)';

PART_NAME
 R455 'Q_RES_0402LF-10K,1%,1/16W,EMPTA':;

SECTION_NUMBER 1
 '@S9S_MB_2U_LIB.S9S_MB_2U(SCH_1):PAGE504_I435@PURE_QUANTA.Q_RES(CHIPS)':
 C_PATH='@s9s_mb_2u_lib.s9s_mb_2u(sch_1):page504_i435@pure_quanta.q_res(chips)';

PART_NAME
 R441 'Q_RES_0402LF-33.2,1%,1/16W,CHIA':;

SECTION_NUMBER 1
 '@S9S_MB_2U_LIB.S9S_MB_2U(SCH_1):PAGE504_I314@PURE_QUANTA.Q_RES(CHIPS)':
 C_PATH='@s9s_mb_2u_lib.s9s_mb_2u(sch_1):page504_i314@pure_quanta.q_res(chips)';

PART_NAME
 R440 'Q_RES_0402LF-33.2,1%,1/16W,CHIA':;

SECTION_NUMBER 1
 '@S9S_MB_2U_LIB.S9S_MB_2U(SCH_1):PAGE504_I313@PURE_QUANTA.Q_RES(CHIPS)':
 C_PATH='@s9s_mb_2u_lib.s9s_mb_2u(sch_1):page504_i313@pure_quanta.q_res(chips)';

PART_NAME
 R434 'Q_RES_0402LF-0,5%,1/16W,CHIP,CA':;

SECTION_NUMBER 1
 '@S9S_MB_2U_LIB.S9S_MB_2U(SCH_1):PAGE504_I396@PURE_QUANTA.Q_RES(CHIPS)':
 C_PATH='@s9s_mb_2u_lib.s9s_mb_2u(sch_1):page504_i396@pure_quanta.q_res(chips)';

PART_NAME
 R433 'Q_RES_0402LF-0,5%,1/16W,CHIP,CA':;

SECTION_NUMBER 1
 '@S9S_MB_2U_LIB.S9S_MB_2U(SCH_1):PAGE504_I393@PURE_QUANTA.Q_RES(CHIPS)':
 C_PATH='@s9s_mb_2u_lib.s9s_mb_2u(sch_1):page504_i393@pure_quanta.q_res(chips)';

PART_NAME
 R432 'Q_RES_0402LF-0,5%,1/16W,CHIP,CA':;

SECTION_NUMBER 1
 '@S9S_MB_2U_LIB.S9S_MB_2U(SCH_1):PAGE504_I394@PURE_QUANTA.Q_RES(CHIPS)':
 C_PATH='@s9s_mb_2u_lib.s9s_mb_2u(sch_1):page504_i394@pure_quanta.q_res(chips)';

PART_NAME
 J58 'SCONN140_623403242-SCONN140_6-A':;

SECTION_NUMBER 1
 '@S9S_MB_2U_LIB.S9S_MB_2U(SCH_1):PAGE504_I381@PURE_QUANTA.SCONN140_623403242(CHIPS)':
 C_PATH='@s9s_mb_2u_lib.s9s_mb_2u(sch_1):page504_i381@pure_quanta.sconn140_6234032~
42(chips)';

PART_NAME
 C1422 'Q_CAP_0402-0.01UF,25V,10%,EMPTA':;

SECTION_NUMBER 1
 '@S9S_MB_2U_LIB.S9S_MB_2U(SCH_1):PAGE504_I439@PURE_QUANTA.Q_CAP(CHIPS)':
 C_PATH='@s9s_mb_2u_lib.s9s_mb_2u(sch_1):page504_i439@pure_quanta.q_cap(chips)';

PART_NAME
 R1217 'Q_RES_0402LF-10K,1%,1/16W,CHIPA':;

SECTION_NUMBER 1
 '@S9S_MB_2U_LIB.S9S_MB_2U(SCH_1):PAGE617_I37@PURE_QUANTA.Q_RES(CHIPS)':
 C_PATH='@s9s_mb_2u_lib.s9s_mb_2u(sch_1):page617_i37@pure_quanta.q_res(chips)';

PART_NAME
 R1216 'Q_RES_0402LF-10K,1%,1/16W,CHIPA':;

SECTION_NUMBER 1
 '@S9S_MB_2U_LIB.S9S_MB_2U(SCH_1):PAGE617_I36@PURE_QUANTA.Q_RES(CHIPS)':
 C_PATH='@s9s_mb_2u_lib.s9s_mb_2u(sch_1):page617_i36@pure_quanta.q_res(chips)';

PART_NAME
 R383 'Q_RES_0402LF-10K,1%,1/16W,EMPTA':;

SECTION_NUMBER 1
 '@S9S_MB_2U_LIB.S9S_MB_2U(SCH_1):PAGE617_I45@PURE_QUANTA.Q_RES(CHIPS)':
 C_PATH='@s9s_mb_2u_lib.s9s_mb_2u(sch_1):page617_i45@pure_quanta.q_res(chips)';

PART_NAME
 R330 'Q_RES_1206LF-0,,1/2W,CHIP,CS00A':;

SECTION_NUMBER 1
 '@S9S_MB_2U_LIB.S9S_MB_2U(SCH_1):PAGE617_I9@PURE_QUANTA.Q_RES(CHIPS)':
 C_PATH='@s9s_mb_2u_lib.s9s_mb_2u(sch_1):page617_i9@pure_quanta.q_res(chips)';

PART_NAME
 R329 'Q_RES_1206LF-0,,1/2W,EMPTY,CS0A':;

SECTION_NUMBER 1
 '@S9S_MB_2U_LIB.S9S_MB_2U(SCH_1):PAGE617_I8@PURE_QUANTA.Q_RES(CHIPS)':
 C_PATH='@s9s_mb_2u_lib.s9s_mb_2u(sch_1):page617_i8@pure_quanta.q_res(chips)';

PART_NAME
 R327 'Q_RES_0402LF-10K,1%,1/16W,CHIPA':;

SECTION_NUMBER 1
 '@S9S_MB_2U_LIB.S9S_MB_2U(SCH_1):PAGE617_I30@PURE_QUANTA.Q_RES(CHIPS)':
 C_PATH='@s9s_mb_2u_lib.s9s_mb_2u(sch_1):page617_i30@pure_quanta.q_res(chips)';

PART_NAME
 R326 'Q_RES_0402LF-10K,1%,1/16W,CHIPA':;

SECTION_NUMBER 1
 '@S9S_MB_2U_LIB.S9S_MB_2U(SCH_1):PAGE617_I29@PURE_QUANTA.Q_RES(CHIPS)':
 C_PATH='@s9s_mb_2u_lib.s9s_mb_2u(sch_1):page617_i29@pure_quanta.q_res(chips)';

PART_NAME
 R325 'Q_RES_0402LF-10K,1%,1/16W,CHIPA':;

SECTION_NUMBER 1
 '@S9S_MB_2U_LIB.S9S_MB_2U(SCH_1):PAGE617_I28@PURE_QUANTA.Q_RES(CHIPS)':
 C_PATH='@s9s_mb_2u_lib.s9s_mb_2u(sch_1):page617_i28@pure_quanta.q_res(chips)';

PART_NAME
 R324 'Q_RES_1206LF-0,,1/2W,CHIP,CS00A':;

SECTION_NUMBER 1
 '@S9S_MB_2U_LIB.S9S_MB_2U(SCH_1):PAGE617_I3@PURE_QUANTA.Q_RES(CHIPS)':
 C_PATH='@s9s_mb_2u_lib.s9s_mb_2u(sch_1):page617_i3@pure_quanta.q_res(chips)';

PART_NAME
 R323 'Q_RES_1206LF-0,,1/2W,EMPTY,CS0A':;

SECTION_NUMBER 1
 '@S9S_MB_2U_LIB.S9S_MB_2U(SCH_1):PAGE617_I4@PURE_QUANTA.Q_RES(CHIPS)':
 C_PATH='@s9s_mb_2u_lib.s9s_mb_2u(sch_1):page617_i4@pure_quanta.q_res(chips)';

PART_NAME
 R321 'Q_RES_0402LF-10K,1%,1/16W,CHIPA':;

SECTION_NUMBER 1
 '@S9S_MB_2U_LIB.S9S_MB_2U(SCH_1):PAGE617_I21@PURE_QUANTA.Q_RES(CHIPS)':
 C_PATH='@s9s_mb_2u_lib.s9s_mb_2u(sch_1):page617_i21@pure_quanta.q_res(chips)';

PART_NAME
 R320 'Q_RES_0402LF-10K,1%,1/16W,CHIPA':;

SECTION_NUMBER 1
 '@S9S_MB_2U_LIB.S9S_MB_2U(SCH_1):PAGE617_I20@PURE_QUANTA.Q_RES(CHIPS)':
 C_PATH='@s9s_mb_2u_lib.s9s_mb_2u(sch_1):page617_i20@pure_quanta.q_res(chips)';

PART_NAME
 R319 'Q_RES_0402LF-10K,1%,1/16W,CHIPA':;

SECTION_NUMBER 1
 '@S9S_MB_2U_LIB.S9S_MB_2U(SCH_1):PAGE617_I19@PURE_QUANTA.Q_RES(CHIPS)':
 C_PATH='@s9s_mb_2u_lib.s9s_mb_2u(sch_1):page617_i19@pure_quanta.q_res(chips)';

PART_NAME
 C1366 'Q_CAP_C0402-22UF,4V,20%,X6S,CHA':;

SECTION_NUMBER 1
 '@S9S_MB_2U_LIB.S9S_MB_2U(SCH_1):PAGE617_I49@PURE_QUANTA.Q_CAP(CHIPS)':
 C_PATH='@s9s_mb_2u_lib.s9s_mb_2u(sch_1):page617_i49@pure_quanta.q_cap(chips)';

PART_NAME
 C1365 'Q_CAP_C0402-22UF,4V,20%,X6S,CHA':;

SECTION_NUMBER 1
 '@S9S_MB_2U_LIB.S9S_MB_2U(SCH_1):PAGE617_I47@PURE_QUANTA.Q_CAP(CHIPS)':
 C_PATH='@s9s_mb_2u_lib.s9s_mb_2u(sch_1):page617_i47@pure_quanta.q_cap(chips)';

PART_NAME
 C1364 'Q_CAP_C0402-22UF,4V,20%,X6S,CHA':;

SECTION_NUMBER 1
 '@S9S_MB_2U_LIB.S9S_MB_2U(SCH_1):PAGE617_I53@PURE_QUANTA.Q_CAP(CHIPS)':
 C_PATH='@s9s_mb_2u_lib.s9s_mb_2u(sch_1):page617_i53@pure_quanta.q_cap(chips)';

PART_NAME
 C1363 'Q_CAP_C0402-22UF,4V,20%,X6S,CHA':;

SECTION_NUMBER 1
 '@S9S_MB_2U_LIB.S9S_MB_2U(SCH_1):PAGE617_I51@PURE_QUANTA.Q_CAP(CHIPS)':
 C_PATH='@s9s_mb_2u_lib.s9s_mb_2u(sch_1):page617_i51@pure_quanta.q_cap(chips)';

PART_NAME
 U105 'ADS1015IDGSR-ADS1015IDGSR,SMLFA':;

SECTION_NUMBER 1
 '@S9S_MB_2U_LIB.S9S_MB_2U(SCH_1):PAGE571_I1@PURE_QUANTA.ADS1015IDGSR(CHIPS)':
 C_PATH='@s9s_mb_2u_lib.s9s_mb_2u(sch_1):page571_i1@pure_quanta.ads1015idgsr(chips~
)';

PART_NAME
 R1800 'Q_RES_0402LF-1K,0.1%,1/16W,CHIA':;

SECTION_NUMBER 1
 '@S9S_MB_2U_LIB.S9S_MB_2U(SCH_1):PAGE571_I46@PURE_QUANTA.Q_RES(CHIPS)':
 C_PATH='@s9s_mb_2u_lib.s9s_mb_2u(sch_1):page571_i46@pure_quanta.q_res(chips)';

PART_NAME
 R1799 'Q_RES_0402LF-0,1%,1/16W,CHIP,TA':;

SECTION_NUMBER 1
 '@S9S_MB_2U_LIB.S9S_MB_2U(SCH_1):PAGE571_I44@PURE_QUANTA.Q_RES(CHIPS)':
 C_PATH='@s9s_mb_2u_lib.s9s_mb_2u(sch_1):page571_i44@pure_quanta.q_res(chips)';

PART_NAME
 R1794 'Q_RES_0402LF-4.7K,1%,1/16W,EMPA':;

SECTION_NUMBER 1
 '@S9S_MB_2U_LIB.S9S_MB_2U(SCH_1):PAGE571_I10@PURE_QUANTA.Q_RES(CHIPS)':
 C_PATH='@s9s_mb_2u_lib.s9s_mb_2u(sch_1):page571_i10@pure_quanta.q_res(chips)';

PART_NAME
 R1793 'Q_RES_0402LF-0,5%,1/16W,CHIP,CA':;

SECTION_NUMBER 1
 '@S9S_MB_2U_LIB.S9S_MB_2U(SCH_1):PAGE571_I19@PURE_QUANTA.Q_RES(CHIPS)':
 C_PATH='@s9s_mb_2u_lib.s9s_mb_2u(sch_1):page571_i19@pure_quanta.q_res(chips)';

PART_NAME
 R1792 'Q_RES_0402LF-0,5%,1/16W,CHIP,CA':;

SECTION_NUMBER 1
 '@S9S_MB_2U_LIB.S9S_MB_2U(SCH_1):PAGE571_I20@PURE_QUANTA.Q_RES(CHIPS)':
 C_PATH='@s9s_mb_2u_lib.s9s_mb_2u(sch_1):page571_i20@pure_quanta.q_res(chips)';

PART_NAME
 R1791 'Q_RES_0402LF-1K,0.1%,1/16W,CHIA':;

SECTION_NUMBER 1
 '@S9S_MB_2U_LIB.S9S_MB_2U(SCH_1):PAGE571_I43@PURE_QUANTA.Q_RES(CHIPS)':
 C_PATH='@s9s_mb_2u_lib.s9s_mb_2u(sch_1):page571_i43@pure_quanta.q_res(chips)';

PART_NAME
 R1790 'Q_RES_0402LF-0,1%,1/16W,CHIP,TA':;

SECTION_NUMBER 1
 '@S9S_MB_2U_LIB.S9S_MB_2U(SCH_1):PAGE571_I40@PURE_QUANTA.Q_RES(CHIPS)':
 C_PATH='@s9s_mb_2u_lib.s9s_mb_2u(sch_1):page571_i40@pure_quanta.q_res(chips)';

PART_NAME
 R1789 'Q_RES_0402LF-1K,0.1%,1/16W,CHIA':;

SECTION_NUMBER 1
 '@S9S_MB_2U_LIB.S9S_MB_2U(SCH_1):PAGE571_I34@PURE_QUANTA.Q_RES(CHIPS)':
 C_PATH='@s9s_mb_2u_lib.s9s_mb_2u(sch_1):page571_i34@pure_quanta.q_res(chips)';

PART_NAME
 R1788 'Q_RES_0402LF-0,1%,1/16W,CHIP,TA':;

SECTION_NUMBER 1
 '@S9S_MB_2U_LIB.S9S_MB_2U(SCH_1):PAGE571_I31@PURE_QUANTA.Q_RES(CHIPS)':
 C_PATH='@s9s_mb_2u_lib.s9s_mb_2u(sch_1):page571_i31@pure_quanta.q_res(chips)';

PART_NAME
 R1787 'Q_RES_0402LF-1K,0.1%,1/16W,CHIA':;

SECTION_NUMBER 1
 '@S9S_MB_2U_LIB.S9S_MB_2U(SCH_1):PAGE571_I28@PURE_QUANTA.Q_RES(CHIPS)':
 C_PATH='@s9s_mb_2u_lib.s9s_mb_2u(sch_1):page571_i28@pure_quanta.q_res(chips)';

PART_NAME
 R1786 'Q_RES_0402LF-0,1%,1/16W,CHIP,TA':;

SECTION_NUMBER 1
 '@S9S_MB_2U_LIB.S9S_MB_2U(SCH_1):PAGE571_I27@PURE_QUANTA.Q_RES(CHIPS)':
 C_PATH='@s9s_mb_2u_lib.s9s_mb_2u(sch_1):page571_i27@pure_quanta.q_res(chips)';

PART_NAME
 R1785 'Q_RES_0402LF-4.7K,1%,1/16W,CHIA':;

SECTION_NUMBER 1
 '@S9S_MB_2U_LIB.S9S_MB_2U(SCH_1):PAGE571_I17@PURE_QUANTA.Q_RES(CHIPS)':
 C_PATH='@s9s_mb_2u_lib.s9s_mb_2u(sch_1):page571_i17@pure_quanta.q_res(chips)';

PART_NAME
 R1784 'Q_RES_0402LF-4.7K,1%,1/16W,EMPA':;

SECTION_NUMBER 1
 '@S9S_MB_2U_LIB.S9S_MB_2U(SCH_1):PAGE571_I14@PURE_QUANTA.Q_RES(CHIPS)':
 C_PATH='@s9s_mb_2u_lib.s9s_mb_2u(sch_1):page571_i14@pure_quanta.q_res(chips)';

PART_NAME
 C1351 'Q_CAP_0402-0.1UF,25V,10%,X7R,CA':;

SECTION_NUMBER 1
 '@S9S_MB_2U_LIB.S9S_MB_2U(SCH_1):PAGE571_I45@PURE_QUANTA.Q_CAP(CHIPS)':
 C_PATH='@s9s_mb_2u_lib.s9s_mb_2u(sch_1):page571_i45@pure_quanta.q_cap(chips)';

PART_NAME
 C1347 'Q_CAP_0402-0.1UF,25V,10%,X7R,CA':;

SECTION_NUMBER 1
 '@S9S_MB_2U_LIB.S9S_MB_2U(SCH_1):PAGE571_I3@PURE_QUANTA.Q_CAP(CHIPS)':
 C_PATH='@s9s_mb_2u_lib.s9s_mb_2u(sch_1):page571_i3@pure_quanta.q_cap(chips)';

PART_NAME
 C1346 'Q_CAP_0402-0.1UF,25V,10%,X7R,CA':;

SECTION_NUMBER 1
 '@S9S_MB_2U_LIB.S9S_MB_2U(SCH_1):PAGE571_I42@PURE_QUANTA.Q_CAP(CHIPS)':
 C_PATH='@s9s_mb_2u_lib.s9s_mb_2u(sch_1):page571_i42@pure_quanta.q_cap(chips)';

PART_NAME
 C1345 'Q_CAP_0402-0.1UF,25V,10%,X7R,CA':;

SECTION_NUMBER 1
 '@S9S_MB_2U_LIB.S9S_MB_2U(SCH_1):PAGE571_I39@PURE_QUANTA.Q_CAP(CHIPS)':
 C_PATH='@s9s_mb_2u_lib.s9s_mb_2u(sch_1):page571_i39@pure_quanta.q_cap(chips)';

PART_NAME
 C1344 'Q_CAP_0402-0.1UF,25V,10%,X7R,CA':;

SECTION_NUMBER 1
 '@S9S_MB_2U_LIB.S9S_MB_2U(SCH_1):PAGE571_I37@PURE_QUANTA.Q_CAP(CHIPS)':
 C_PATH='@s9s_mb_2u_lib.s9s_mb_2u(sch_1):page571_i37@pure_quanta.q_cap(chips)';

PART_NAME
 R1735 'Q_RES_0402LF-100,1%,1/16W,CHIPA':;

SECTION_NUMBER 1
 '@S9S_MB_2U_LIB.S9S_MB_2U(SCH_1):PAGE452_I194@PURE_QUANTA.Q_RES(CHIPS)':
 C_PATH='@s9s_mb_2u_lib.s9s_mb_2u(sch_1):page452_i194@pure_quanta.q_res(chips)';

PART_NAME
 R1717 'Q_RES_0402LF-49.9     ,1%  ,1/A':;

SECTION_NUMBER 1
 '@S9S_MB_2U_LIB.S9S_MB_2U(SCH_1):PAGE452_I193@PURE_QUANTA.Q_RES(CHIPS)':
 C_PATH='@s9s_mb_2u_lib.s9s_mb_2u(sch_1):page452_i193@pure_quanta.q_res(chips)';

PART_NAME
 PU35 'ISL69260IRAZT-ISL69260IRAZ-T,SA':;

SECTION_NUMBER 1
 '@S9S_MB_2U_LIB.S9S_MB_2U(SCH_1):PAGE452_I196@PURE_QUANTA.ISL69260IRAZT(CHIPS)':
 C_PATH='@s9s_mb_2u_lib.s9s_mb_2u(sch_1):page452_i196@pure_quanta.isl69260irazt(ch~
ips)',
 VAR_0_ONSEMI='VAR_REPLACED|ISL69260IRAZT|VAR_PARTNAME|FD5001|VALUE|FD5001|PART_~
TYPE|SMLF|MATERIAL|IC|PART_NUMBER|AL005001004|STANDARD||LIFECYCLE||PART_NUMBER|A~
L005001004|JEDEC_TYPE|VFQFPN40_TH_0-4_5X5XC|DESCRIPTION|IC OTHER(40P) FD5001(QFN~
)|MANUFTR|ONS|MANUF_PN|FD5001|RD_CMPLS_LVL|EP(V1)|CMPLS_LVL||FROM_PJ|S9S-KIMI|CL~
ASS|IC|DIP_SMD||DATA|ONS_FD5001.pdf|EE_CHECK_LIST||FP_ECN|FD5001.msg|PSL||CREATO~
R||STATUS||MSD|NA|ESD_CDM|NA|ESD_HBM|NA|ESD_MM|NA|PIN_LENGTH_SHORT_PIN|0 MILS|PI~
N_LENGTH_LONG_PIN|0 MILS|CREATEDAY|20200421|VARIANT_DEVICE_TYPE|FD5001-FD5001,SM~
LF,IC,AL005001',
 CDSVAR_REPCELL_ONSEMI='pure_quanta|fd5001';

PART_NAME
 PR1390 'Q_RES_0402LF-49.9     ,1%  ,1/A':;

SECTION_NUMBER 1
 '@S9S_MB_2U_LIB.S9S_MB_2U(SCH_1):PAGE452_I180@PURE_QUANTA.Q_RES(CHIPS)':
 C_PATH='@s9s_mb_2u_lib.s9s_mb_2u(sch_1):page452_i180@pure_quanta.q_res(chips)',
 VAR_0_ONSEMI='VALUE|0|TOLERANCE|5%|WATTAGE|1/16W|PACK_TYPE|0402LF|MATERIAL|CHIP~
|PART_NUMBER|CS00002JB38|STANDARD|End of Design|LIFECYCLE|Comp-Approve|PART_NUMB~
ER|CS00002JB38|JEDEC_TYPE|R0402|ALT_SYMBOLS|(R0402-0201)|VALUE|0|TOL|5%|WATTAGE|~
1/16W|CLASS|DISCRETE|DESCRIPTION|RESISTOR CHIP 0 1/16W +-5%(0402)|COMPONENT_TYPE~
|CHIP0402|LEAD_LENGTH||DFM_EXCLUSION||DAY|20100618|VARIANT_DEVICE_TYPE|Q_RES-0,5~
%,1/16W,0402LF,CHIP,C',
 CDSVAR_REPCELL_ONSEMI='pure_quanta|Q_res';

PART_NAME
 PR1380 'Q_RES_0402LF-49.9     ,1%  ,1/A':;

SECTION_NUMBER 1
 '@S9S_MB_2U_LIB.S9S_MB_2U(SCH_1):PAGE452_I183@PURE_QUANTA.Q_RES(CHIPS)':
 C_PATH='@s9s_mb_2u_lib.s9s_mb_2u(sch_1):page452_i183@pure_quanta.q_res(chips)',
 VAR_0_ONSEMI='VALUE|0|TOLERANCE|5%|WATTAGE|1/16W|PACK_TYPE|0402LF|MATERIAL|CHIP~
|PART_NUMBER|CS00002JB38|STANDARD|End of Design|LIFECYCLE|Comp-Approve|PART_NUMB~
ER|CS00002JB38|JEDEC_TYPE|R0402|ALT_SYMBOLS|(R0402-0201)|VALUE|0|TOL|5%|WATTAGE|~
1/16W|CLASS|DISCRETE|DESCRIPTION|RESISTOR CHIP 0 1/16W +-5%(0402)|COMPONENT_TYPE~
|CHIP0402|LEAD_LENGTH||DFM_EXCLUSION||DAY|20100618|VARIANT_DEVICE_TYPE|Q_RES-0,5~
%,1/16W,0402LF,CHIP,C',
 CDSVAR_REPCELL_ONSEMI='pure_quanta|Q_res';

PART_NAME
 PR1311 'Q_RES_0402LF-0,5%,1/16W,CHIP,CA':;

SECTION_NUMBER 1
 '@S9S_MB_2U_LIB.S9S_MB_2U(SCH_1):PAGE452_I195@PURE_QUANTA.Q_RES(CHIPS)':
 C_PATH='@s9s_mb_2u_lib.s9s_mb_2u(sch_1):page452_i195@pure_quanta.q_res(chips)';

PART_NAME
 PR592 'Q_RES_0402LF-100,1%,1/16W,CHIPA':;

SECTION_NUMBER 1
 '@S9S_MB_2U_LIB.S9S_MB_2U(SCH_1):PAGE452_I96@PURE_QUANTA.Q_RES(CHIPS)':
 C_PATH='@s9s_mb_2u_lib.s9s_mb_2u(sch_1):page452_i96@pure_quanta.q_res(chips)';

PART_NAME
 PR591 'Q_RES_0402LF-100,1%,1/16W,CHIPA':;

SECTION_NUMBER 1
 '@S9S_MB_2U_LIB.S9S_MB_2U(SCH_1):PAGE452_I94@PURE_QUANTA.Q_RES(CHIPS)':
 C_PATH='@s9s_mb_2u_lib.s9s_mb_2u(sch_1):page452_i94@pure_quanta.q_res(chips)';

PART_NAME
 PR378 'Q_RES_0402LF-1K,1%,1/16W,CHIP,A':;

SECTION_NUMBER 1
 '@S9S_MB_2U_LIB.S9S_MB_2U(SCH_1):PAGE452_I144@PURE_QUANTA.Q_RES(CHIPS)':
 C_PATH='@s9s_mb_2u_lib.s9s_mb_2u(sch_1):page452_i144@pure_quanta.q_res(chips)';

PART_NAME
 PR375 'Q_RES_0402LF-1,1%,1/16W,CHIP,CA':;

SECTION_NUMBER 1
 '@S9S_MB_2U_LIB.S9S_MB_2U(SCH_1):PAGE452_I158@PURE_QUANTA.Q_RES(CHIPS)':
 C_PATH='@s9s_mb_2u_lib.s9s_mb_2u(sch_1):page452_i158@pure_quanta.q_res(chips)';

PART_NAME
 PR373 'Q_RES_0402LF-1K,1%,1/16W,EMPTYA':;

SECTION_NUMBER 1
 '@S9S_MB_2U_LIB.S9S_MB_2U(SCH_1):PAGE452_I106@PURE_QUANTA.Q_RES(CHIPS)':
 C_PATH='@s9s_mb_2u_lib.s9s_mb_2u(sch_1):page452_i106@pure_quanta.q_res(chips)';

PART_NAME
 PR372 'Q_RES_0402LF-1K,1%,1/16W,CHIP,A':;

SECTION_NUMBER 1
 '@S9S_MB_2U_LIB.S9S_MB_2U(SCH_1):PAGE452_I113@PURE_QUANTA.Q_RES(CHIPS)':
 C_PATH='@s9s_mb_2u_lib.s9s_mb_2u(sch_1):page452_i113@pure_quanta.q_res(chips)';

PART_NAME
 PR371 'Q_RES_0402LF-0,5%,1/16W,CHIP,CA':;

SECTION_NUMBER 1
 '@S9S_MB_2U_LIB.S9S_MB_2U(SCH_1):PAGE452_I119@PURE_QUANTA.Q_RES(CHIPS)':
 C_PATH='@s9s_mb_2u_lib.s9s_mb_2u(sch_1):page452_i119@pure_quanta.q_res(chips)';

PART_NAME
 PR370 'Q_RES_0402LF-1K,1%,1/16W,CHIP,A':;

SECTION_NUMBER 1
 '@S9S_MB_2U_LIB.S9S_MB_2U(SCH_1):PAGE452_I112@PURE_QUANTA.Q_RES(CHIPS)':
 C_PATH='@s9s_mb_2u_lib.s9s_mb_2u(sch_1):page452_i112@pure_quanta.q_res(chips)';

PART_NAME
 PR369 'Q_RES_0402LF-1K,1%,1/16W,EMPTYA':;

SECTION_NUMBER 1
 '@S9S_MB_2U_LIB.S9S_MB_2U(SCH_1):PAGE452_I103@PURE_QUANTA.Q_RES(CHIPS)':
 C_PATH='@s9s_mb_2u_lib.s9s_mb_2u(sch_1):page452_i103@pure_quanta.q_res(chips)';

PART_NAME
 PR368 'Q_RES_0402LF-33.2,1%,1/16W,CHIA':;

SECTION_NUMBER 1
 '@S9S_MB_2U_LIB.S9S_MB_2U(SCH_1):PAGE452_I122@PURE_QUANTA.Q_RES(CHIPS)':
 C_PATH='@s9s_mb_2u_lib.s9s_mb_2u(sch_1):page452_i122@pure_quanta.q_res(chips)';

PART_NAME
 PR367 'Q_RES_0402LF-0,5%,1/16W,CHIP,CA':;

SECTION_NUMBER 1
 '@S9S_MB_2U_LIB.S9S_MB_2U(SCH_1):PAGE452_I121@PURE_QUANTA.Q_RES(CHIPS)':
 C_PATH='@s9s_mb_2u_lib.s9s_mb_2u(sch_1):page452_i121@pure_quanta.q_res(chips)';

PART_NAME
 PR366 'Q_RES_0402LF-0,5%,1/16W,CHIP,CA':;

SECTION_NUMBER 1
 '@S9S_MB_2U_LIB.S9S_MB_2U(SCH_1):PAGE452_I124@PURE_QUANTA.Q_RES(CHIPS)':
 C_PATH='@s9s_mb_2u_lib.s9s_mb_2u(sch_1):page452_i124@pure_quanta.q_res(chips)';

PART_NAME
 PR365 'Q_RES_0402LF-0,5%,1/16W,CHIP,CA':;

SECTION_NUMBER 1
 '@S9S_MB_2U_LIB.S9S_MB_2U(SCH_1):PAGE452_I125@PURE_QUANTA.Q_RES(CHIPS)':
 C_PATH='@s9s_mb_2u_lib.s9s_mb_2u(sch_1):page452_i125@pure_quanta.q_res(chips)';

PART_NAME
 PR364 'Q_RES_0402LF-150,1%,1/16W,CHIPA':;

SECTION_NUMBER 1
 '@S9S_MB_2U_LIB.S9S_MB_2U(SCH_1):PAGE452_I127@PURE_QUANTA.Q_RES(CHIPS)':
 C_PATH='@s9s_mb_2u_lib.s9s_mb_2u(sch_1):page452_i127@pure_quanta.q_res(chips)';

PART_NAME
 PR363 'Q_RES_0402LF-0,5%,1/16W,CHIP,CA':;

SECTION_NUMBER 1
 '@S9S_MB_2U_LIB.S9S_MB_2U(SCH_1):PAGE452_I128@PURE_QUANTA.Q_RES(CHIPS)':
 C_PATH='@s9s_mb_2u_lib.s9s_mb_2u(sch_1):page452_i128@pure_quanta.q_res(chips)';

PART_NAME
 PR362 'Q_RES_0402LF-0,5%,1/16W,CHIP,CA':;

SECTION_NUMBER 1
 '@S9S_MB_2U_LIB.S9S_MB_2U(SCH_1):PAGE452_I126@PURE_QUANTA.Q_RES(CHIPS)':
 C_PATH='@s9s_mb_2u_lib.s9s_mb_2u(sch_1):page452_i126@pure_quanta.q_res(chips)';

PART_NAME
 PR361 'Q_RES_0402LF-1K,1%,1/16W,CHIP,A':;

SECTION_NUMBER 1
 '@S9S_MB_2U_LIB.S9S_MB_2U(SCH_1):PAGE452_I129@PURE_QUANTA.Q_RES(CHIPS)':
 C_PATH='@s9s_mb_2u_lib.s9s_mb_2u(sch_1):page452_i129@pure_quanta.q_res(chips)';

PART_NAME
 PR358 'Q_RES_0402LF-4.64K,0.5%,1/16W,A':;

SECTION_NUMBER 1
 '@S9S_MB_2U_LIB.S9S_MB_2U(SCH_1):PAGE452_I185@PURE_QUANTA.Q_RES(CHIPS)':
 C_PATH='@s9s_mb_2u_lib.s9s_mb_2u(sch_1):page452_i185@pure_quanta.q_res(chips)',
 VAR_0_ONSEMI='VALUE|102K|TOLERANCE|1%|WATTAGE|1/16W|PACK_TYPE|0402LF|MATERIAL|C~
HIP|PART_NUMBER|CS41022FB19|STANDARD|End of Design|LIFECYCLE|Comp-Approve|PART_N~
UMBER|CS41022FB19|JEDEC_TYPE|R0402|ALT_SYMBOLS|(R0402-0201)|VALUE|102K|TOL|1%|WA~
TTAGE|1/16W|CLASS|DISCRETE|DESCRIPTION|RES CHIP 102K 1/16W +-1%(0402)|COMPONENT_~
TYPE|CHIP0402|LEAD_LENGTH||DFM_EXCLUSION||DAY|20110826|VARIANT_DEVICE_TYPE|Q_RES~
-102K,1%,1/16W,0402LF,CHI',
 CDSVAR_REPCELL_ONSEMI='pure_quanta|Q_res';

PART_NAME
 PR357 'Q_RES_0402LF-28K,1%,1/16W,EMPTA':;

SECTION_NUMBER 1
 '@S9S_MB_2U_LIB.S9S_MB_2U(SCH_1):PAGE452_I84@PURE_QUANTA.Q_RES(CHIPS)':
 C_PATH='@s9s_mb_2u_lib.s9s_mb_2u(sch_1):page452_i84@pure_quanta.q_res(chips)';

PART_NAME
 PJ54 'Q_SHORT_SM-EMPTY,SHORT6':;

SECTION_NUMBER 1
 '@S9S_MB_2U_LIB.S9S_MB_2U(SCH_1):PAGE452_I95@PURE_QUANTA.Q_SHORT(CHIPS)':
 C_PATH='@s9s_mb_2u_lib.s9s_mb_2u(sch_1):page452_i95@pure_quanta.q_short(chips)';

PART_NAME
 PC1196 'Q_CAP_C0402-1UF,16V,10%,X6S,CHA':;

SECTION_NUMBER 1
 '@S9S_MB_2U_LIB.S9S_MB_2U(SCH_1):PAGE452_I156@PURE_QUANTA.Q_CAP(CHIPS)':
 C_PATH='@s9s_mb_2u_lib.s9s_mb_2u(sch_1):page452_i156@pure_quanta.q_cap(chips)';

PART_NAME
 PC632 'Q_CAP_C0402-1UF,16V,10%,X6S,CHA':;

SECTION_NUMBER 1
 '@S9S_MB_2U_LIB.S9S_MB_2U(SCH_1):PAGE452_I157@PURE_QUANTA.Q_CAP(CHIPS)':
 C_PATH='@s9s_mb_2u_lib.s9s_mb_2u(sch_1):page452_i157@pure_quanta.q_cap(chips)';

PART_NAME
 PC631 'Q_CAP_0402-470PF,50V,10%,X7R,TA':;

SECTION_NUMBER 1
 '@S9S_MB_2U_LIB.S9S_MB_2U(SCH_1):PAGE452_I141@PURE_QUANTA.Q_CAP(CHIPS)':
 C_PATH='@s9s_mb_2u_lib.s9s_mb_2u(sch_1):page452_i141@pure_quanta.q_cap(chips)',
 VAR_0_ONSEMI='VALUE|2200PF|VOLTAGE|50V|TOLERANCE|10%|PACK_TYPE|C0402|MATERIAL|X~
7R|PART_NUMBER|CH2226K1B06|STANDARD||LIFECYCLE||ASS_PART||PART_NUMBER|CH2226K1B0~
6|JEDEC_TYPE|C0402|ALT_SYMBOLS|(C0402-0201)|VALUE|2200PF|RATED_VOLTAGE|50V|TOL|1~
0%|CLASS|DISCRETE|DESCRIPTION|CAP CHIP 2200P 50V(+-10%,X7R,0402)MUR|COMPONENT_TY~
PE|CHIP0402|LEAD_LENGTH||LPID||DATE|20150614|VARIANT_DEVICE_TYPE|Q_CAP-2200PF,50~
V,10%,C0402,X7R',
 CDSVAR_REPCELL_ONSEMI='pure_quanta|Q_cap';

PART_NAME
 PC630 'Q_CAP_0402-4.7UF,6.3V,20%,X6S,A':;

SECTION_NUMBER 1
 '@S9S_MB_2U_LIB.S9S_MB_2U(SCH_1):PAGE452_I138@PURE_QUANTA.Q_CAP(CHIPS)':
 C_PATH='@s9s_mb_2u_lib.s9s_mb_2u(sch_1):page452_i138@pure_quanta.q_cap(chips)',
 VAR_0_ONSEMI='VALUE|4.7UF|VOLTAGE|6.3V|TOLERANCE|20%|PACK_TYPE|0402|MATERIAL|EM~
PTY|PART_NUMBER|CH5471MEB01|STANDARD||LIFECYCLE||ASS_PART||PART_NUMBER|CH5471MEB~
01|JEDEC_TYPE|C0402|ALT_SYMBOLS|(C0402_OCTAGON,C0402_OCTAGONXA,C0402-0201)|VALUE~
|NA|RATED_VOLTAGE|6.3V|TOL|20%|CLASS|IO|DESCRIPTION|CAP CHIP 4.7UF 6.3V(+-20%,X6~
S,0402)|COMPONENT_TYPE|CHIP0402|LEAD_LENGTH||LPID||DATE|20151211|VARIANT_DEVICE_~
TYPE|Q_CAP-4.7UF,6.3V,20%,0402,EMPT',
 CDSVAR_REPCELL_ONSEMI='pure_quanta|Q_cap';

PART_NAME
 PC629 'Q_CAP_C0402-100NF,50V,10%,EMPTA':;

SECTION_NUMBER 1
 '@S9S_MB_2U_LIB.S9S_MB_2U(SCH_1):PAGE452_I139@PURE_QUANTA.Q_CAP(CHIPS)':
 C_PATH='@s9s_mb_2u_lib.s9s_mb_2u(sch_1):page452_i139@pure_quanta.q_cap(chips)';

PART_NAME
 PC628 'Q_CAP_0402-0.1UF,25V,10%,X7R,CA':;

SECTION_NUMBER 1
 '@S9S_MB_2U_LIB.S9S_MB_2U(SCH_1):PAGE452_I108@PURE_QUANTA.Q_CAP(CHIPS)':
 C_PATH='@s9s_mb_2u_lib.s9s_mb_2u(sch_1):page452_i108@pure_quanta.q_cap(chips)',
 VAR_0_ONSEMI='VALUE|1UF|VOLTAGE|16V|TOLERANCE|10%|PACK_TYPE|C0402|MATERIAL|X6S|~
PART_NUMBER|CH5103KEB01|STANDARD||LIFECYCLE||ASS_PART||PART_NUMBER|CH5103KEB01|J~
EDEC_TYPE|C0402|ALT_SYMBOLS|(C0402-0201)|VALUE|1UF|RATED_VOLTAGE|16V|TOL|10%|CLA~
SS|DISCRETE|DESCRIPTION|CAP CHIP 1UF 16V(10%,X6S,0402)|COMPONENT_TYPE|CHIP0402|L~
EAD_LENGTH||LPID||DATE|20140828|VARIANT_DEVICE_TYPE|Q_CAP-1UF,16V,10%,C0402,X6S,~
CH',
 CDSVAR_REPCELL_ONSEMI='pure_quanta|Q_cap';

PART_NAME
 PC627 'Q_CAP_0402-3300PF,50V,10%,X7R,A':;

SECTION_NUMBER 1
 '@S9S_MB_2U_LIB.S9S_MB_2U(SCH_1):PAGE452_I123@PURE_QUANTA.Q_CAP(CHIPS)':
 C_PATH='@s9s_mb_2u_lib.s9s_mb_2u(sch_1):page452_i123@pure_quanta.q_cap(chips)',
 VAR_0_ONSEMI='VALUE|1NF|VOLTAGE|50V|TOLERANCE|10%|PACK_TYPE|0402|MATERIAL|X7R|P~
ART_NUMBER|CH21006KB16|STANDARD||LIFECYCLE||ASS_PART||PART_NUMBER|CH21006KB16|JE~
DEC_TYPE|C0402|ALT_SYMBOLS|(C0402-0201)|VALUE|1NF|RATED_VOLTAGE|50V|TOL|10%|CLAS~
S|DISCRETE|DESCRIPTION|CAP CHIP 1N 50V(+-10%,X7R,0402)EP|COMPONENT_TYPE|CHIP0402~
|LEAD_LENGTH||LPID||DATE|20100811|VARIANT_DEVICE_TYPE|Q_CAP-1NF,50V,10%,0402,X7R~
,CH2',
 CDSVAR_REPCELL_ONSEMI='pure_quanta|Q_cap';

PART_NAME
 PC626 'Q_CAP_0402-1000PF,50V,5%,EMPTYA':;

SECTION_NUMBER 1
 '@S9S_MB_2U_LIB.S9S_MB_2U(SCH_1):PAGE452_I132@PURE_QUANTA.Q_CAP(CHIPS)':
 C_PATH='@s9s_mb_2u_lib.s9s_mb_2u(sch_1):page452_i132@pure_quanta.q_cap(chips)';

PART_NAME
 PC624 'Q_CAP_0402-0.1UF,25V,10%,X7R,CA':;

SECTION_NUMBER 1
 '@S9S_MB_2U_LIB.S9S_MB_2U(SCH_1):PAGE452_I105@PURE_QUANTA.Q_CAP(CHIPS)':
 C_PATH='@s9s_mb_2u_lib.s9s_mb_2u(sch_1):page452_i105@pure_quanta.q_cap(chips)',
 VAR_0_ONSEMI='VALUE|1UF|VOLTAGE|16V|TOLERANCE|10%|PACK_TYPE|C0402|MATERIAL|X6S|~
PART_NUMBER|CH5103KEB01|STANDARD||LIFECYCLE||ASS_PART||PART_NUMBER|CH5103KEB01|J~
EDEC_TYPE|C0402|ALT_SYMBOLS|(C0402-0201)|VALUE|1UF|RATED_VOLTAGE|16V|TOL|10%|CLA~
SS|DISCRETE|DESCRIPTION|CAP CHIP 1UF 16V(10%,X6S,0402)|COMPONENT_TYPE|CHIP0402|L~
EAD_LENGTH||LPID||DATE|20140828|VARIANT_DEVICE_TYPE|Q_CAP-1UF,16V,10%,C0402,X6S,~
CH',
 CDSVAR_REPCELL_ONSEMI='pure_quanta|Q_cap';

PART_NAME
 C1335 'Q_CAP_0402-0.1UF,25V,10%,X7R,CA':;

SECTION_NUMBER 1
 '@S9S_MB_2U_LIB.S9S_MB_2U(SCH_1):PAGE452_I188@PURE_QUANTA.Q_CAP(CHIPS)':
 C_PATH='@s9s_mb_2u_lib.s9s_mb_2u(sch_1):page452_i188@pure_quanta.q_cap(chips)';

PART_NAME
 C1334 'Q_CAP_C0402-10UF,6.3V,20%,X6S,A':;

SECTION_NUMBER 1
 '@S9S_MB_2U_LIB.S9S_MB_2U(SCH_1):PAGE452_I187@PURE_QUANTA.Q_CAP(CHIPS)':
 C_PATH='@s9s_mb_2u_lib.s9s_mb_2u(sch_1):page452_i187@pure_quanta.q_cap(chips)';

PART_NAME
 U100 'RT9059GQW-RT9059GQW,SMLF,IC,ALA':;

SECTION_NUMBER 1
 '@S9S_MB_2U_LIB.S9S_MB_2U(SCH_1):PAGE577_I1@PURE_QUANTA.RT9059GQW(CHIPS)':
 C_PATH='@s9s_mb_2u_lib.s9s_mb_2u(sch_1):page577_i1@pure_quanta.rt9059gqw(chips)';

PART_NAME
 R1867 'Q_RES_0402LF-12K,1%,1/16W,CHIPA':;

SECTION_NUMBER 1
 '@S9S_MB_2U_LIB.S9S_MB_2U(SCH_1):PAGE577_I28@PURE_QUANTA.Q_RES(CHIPS)':
 C_PATH='@s9s_mb_2u_lib.s9s_mb_2u(sch_1):page577_i28@pure_quanta.q_res(chips)';

PART_NAME
 R1866 'Q_RES_0402LF-25.5K,1%,1/16W,CHA':;

SECTION_NUMBER 1
 '@S9S_MB_2U_LIB.S9S_MB_2U(SCH_1):PAGE577_I27@PURE_QUANTA.Q_RES(CHIPS)':
 C_PATH='@s9s_mb_2u_lib.s9s_mb_2u(sch_1):page577_i27@pure_quanta.q_res(chips)';

PART_NAME
 R1819 'Q_RES_0402LF-0,5%,1/16W,EMPTY,A':;

SECTION_NUMBER 1
 '@S9S_MB_2U_LIB.S9S_MB_2U(SCH_1):PAGE577_I25@PURE_QUANTA.Q_RES(CHIPS)':
 C_PATH='@s9s_mb_2u_lib.s9s_mb_2u(sch_1):page577_i25@pure_quanta.q_res(chips)';

PART_NAME
 R1818 'Q_RES_0402LF-0,5%,1/16W,CHIP,CA':;

SECTION_NUMBER 1
 '@S9S_MB_2U_LIB.S9S_MB_2U(SCH_1):PAGE577_I20@PURE_QUANTA.Q_RES(CHIPS)':
 C_PATH='@s9s_mb_2u_lib.s9s_mb_2u(sch_1):page577_i20@pure_quanta.q_res(chips)';

PART_NAME
 R1729 'Q_RES_0402LF-10K,1%,1/16W,CHIPA':;

SECTION_NUMBER 1
 '@S9S_MB_2U_LIB.S9S_MB_2U(SCH_1):PAGE577_I22@PURE_QUANTA.Q_RES(CHIPS)':
 C_PATH='@s9s_mb_2u_lib.s9s_mb_2u(sch_1):page577_i22@pure_quanta.q_res(chips)';

PART_NAME
 R1716 'Q_RES_0402LF-0,5%,1/16W,CHIP,CA':;

SECTION_NUMBER 1
 '@S9S_MB_2U_LIB.S9S_MB_2U(SCH_1):PAGE577_I13@PURE_QUANTA.Q_RES(CHIPS)':
 C_PATH='@s9s_mb_2u_lib.s9s_mb_2u(sch_1):page577_i13@pure_quanta.q_res(chips)';

PART_NAME
 C1330 'Q_CAP_0402-0.1UF,25V,10%,X7R,CA':;

SECTION_NUMBER 1
 '@S9S_MB_2U_LIB.S9S_MB_2U(SCH_1):PAGE577_I7@PURE_QUANTA.Q_CAP(CHIPS)':
 C_PATH='@s9s_mb_2u_lib.s9s_mb_2u(sch_1):page577_i7@pure_quanta.q_cap(chips)';

PART_NAME
 C1329 'Q_CAP_C0805-10UF,16V,10%,X6S,CA':
;

SECTION_NUMBER 1
 '@S9S_MB_2U_LIB.S9S_MB_2U(SCH_1):PAGE577_I5@PURE_QUANTA.Q_CAP(CHIPS)':
 C_PATH='@s9s_mb_2u_lib.s9s_mb_2u(sch_1):page577_i5@pure_quanta.q_cap(chips)';

PART_NAME
 C1328 'Q_CAP_C0805-10UF,16V,10%,X6S,CA':
;

SECTION_NUMBER 1
 '@S9S_MB_2U_LIB.S9S_MB_2U(SCH_1):PAGE577_I2@PURE_QUANTA.Q_CAP(CHIPS)':
 C_PATH='@s9s_mb_2u_lib.s9s_mb_2u(sch_1):page577_i2@pure_quanta.q_cap(chips)';

PART_NAME
 C1327 'Q_CAP_C0805-10UF,16V,10%,X6S,CA':
;

SECTION_NUMBER 1
 '@S9S_MB_2U_LIB.S9S_MB_2U(SCH_1):PAGE577_I17@PURE_QUANTA.Q_CAP(CHIPS)':
 C_PATH='@s9s_mb_2u_lib.s9s_mb_2u(sch_1):page577_i17@pure_quanta.q_cap(chips)';

PART_NAME
 U89 'MOSFET_N_SMLF-BSS138K,BSS138K,A':;

SECTION_NUMBER 1
 '@S9S_MB_2U_LIB.S9S_MB_2U(SCH_1):PAGE545_I149@PURE_QUANTA.MOSFET_N(CHIPS)':
 C_PATH='@s9s_mb_2u_lib.s9s_mb_2u(sch_1):page545_i149@pure_quanta.mosfet_n(chips)';

PART_NAME
 R1939 'Q_RES_0402LF-33.2,1%,1/16W,CHIA':;

SECTION_NUMBER 1
 '@S9S_MB_2U_LIB.S9S_MB_2U(SCH_1):PAGE545_I232@PURE_QUANTA.Q_RES(CHIPS)':
 C_PATH='@s9s_mb_2u_lib.s9s_mb_2u(sch_1):page545_i232@pure_quanta.q_res(chips)';

PART_NAME
 R1938 'Q_RES_0402LF-33.2,1%,1/16W,CHIA':;

SECTION_NUMBER 1
 '@S9S_MB_2U_LIB.S9S_MB_2U(SCH_1):PAGE545_I235@PURE_QUANTA.Q_RES(CHIPS)':
 C_PATH='@s9s_mb_2u_lib.s9s_mb_2u(sch_1):page545_i235@pure_quanta.q_res(chips)';

PART_NAME
 R1937 'Q_RES_0402LF-33.2,1%,1/16W,CHIA':;

SECTION_NUMBER 1
 '@S9S_MB_2U_LIB.S9S_MB_2U(SCH_1):PAGE545_I227@PURE_QUANTA.Q_RES(CHIPS)':
 C_PATH='@s9s_mb_2u_lib.s9s_mb_2u(sch_1):page545_i227@pure_quanta.q_res(chips)';

PART_NAME
 R1936 'Q_RES_0402LF-33.2,1%,1/16W,CHIA':;

SECTION_NUMBER 1
 '@S9S_MB_2U_LIB.S9S_MB_2U(SCH_1):PAGE545_I229@PURE_QUANTA.Q_RES(CHIPS)':
 C_PATH='@s9s_mb_2u_lib.s9s_mb_2u(sch_1):page545_i229@pure_quanta.q_res(chips)';

PART_NAME
 R1918 'Q_RES_0402LF-0,5%,1/16W,CHIP,CA':;

SECTION_NUMBER 1
 '@S9S_MB_2U_LIB.S9S_MB_2U(SCH_1):PAGE545_I224@PURE_QUANTA.Q_RES(CHIPS)':
 C_PATH='@s9s_mb_2u_lib.s9s_mb_2u(sch_1):page545_i224@pure_quanta.q_res(chips)';

PART_NAME
 R1917 'Q_RES_0402LF-0,5%,1/16W,CHIP,CA':;

SECTION_NUMBER 1
 '@S9S_MB_2U_LIB.S9S_MB_2U(SCH_1):PAGE545_I221@PURE_QUANTA.Q_RES(CHIPS)':
 C_PATH='@s9s_mb_2u_lib.s9s_mb_2u(sch_1):page545_i221@pure_quanta.q_res(chips)';

PART_NAME
 R1740 'Q_RES_0402LF-100,1%,1/16W,CHIPA':;

SECTION_NUMBER 1
 '@S9S_MB_2U_LIB.S9S_MB_2U(SCH_1):PAGE545_I206@PURE_QUANTA.Q_RES(CHIPS)':
 C_PATH='@s9s_mb_2u_lib.s9s_mb_2u(sch_1):page545_i206@pure_quanta.q_res(chips)';

PART_NAME
 R1739 'Q_RES_0402LF-100,1%,1/16W,CHIPA':;

SECTION_NUMBER 1
 '@S9S_MB_2U_LIB.S9S_MB_2U(SCH_1):PAGE545_I205@PURE_QUANTA.Q_RES(CHIPS)':
 C_PATH='@s9s_mb_2u_lib.s9s_mb_2u(sch_1):page545_i205@pure_quanta.q_res(chips)';

PART_NAME
 R1738 'Q_RES_0402LF-100,1%,1/16W,CHIPA':;

SECTION_NUMBER 1
 '@S9S_MB_2U_LIB.S9S_MB_2U(SCH_1):PAGE545_I204@PURE_QUANTA.Q_RES(CHIPS)':
 C_PATH='@s9s_mb_2u_lib.s9s_mb_2u(sch_1):page545_i204@pure_quanta.q_res(chips)';

PART_NAME
 R1710 'Q_RES_0402LF-49.9     ,1%  ,1/A':;

SECTION_NUMBER 1
 '@S9S_MB_2U_LIB.S9S_MB_2U(SCH_1):PAGE545_I165@PURE_QUANTA.Q_RES(CHIPS)':
 C_PATH='@s9s_mb_2u_lib.s9s_mb_2u(sch_1):page545_i165@pure_quanta.q_res(chips)';

PART_NAME
 R1195 'Q_RES_0402LF-750,1%,1/16W,CHIPA':;

SECTION_NUMBER 1
 '@S9S_MB_2U_LIB.S9S_MB_2U(SCH_1):PAGE545_I143@PURE_QUANTA.Q_RES(CHIPS)':
 C_PATH='@s9s_mb_2u_lib.s9s_mb_2u(sch_1):page545_i143@pure_quanta.q_res(chips)';

PART_NAME
 R1106 'Q_RES_0402LF-10K,1%,1/16W,CHIPA':;

SECTION_NUMBER 1
 '@S9S_MB_2U_LIB.S9S_MB_2U(SCH_1):PAGE545_I152@PURE_QUANTA.Q_RES(CHIPS)':
 C_PATH='@s9s_mb_2u_lib.s9s_mb_2u(sch_1):page545_i152@pure_quanta.q_res(chips)';

PART_NAME
 D0 'Q_LED_SMLF-LED_GREEN,19-213/GVA':;

SECTION_NUMBER 1
 '@S9S_MB_2U_LIB.S9S_MB_2U(SCH_1):PAGE545_I144@PURE_QUANTA.Q_LED(CHIPS)':
 C_PATH='@s9s_mb_2u_lib.s9s_mb_2u(sch_1):page545_i144@pure_quanta.q_led(chips)';

PART_NAME
 C1325 'Q_CAP_0402-0.1UF,25V,10%,X7R,CA':;

SECTION_NUMBER 1
 '@S9S_MB_2U_LIB.S9S_MB_2U(SCH_1):PAGE545_I166@PURE_QUANTA.Q_CAP(CHIPS)':
 C_PATH='@s9s_mb_2u_lib.s9s_mb_2u(sch_1):page545_i166@pure_quanta.q_cap(chips)';

PART_NAME
 R1823 'Q_RES_0402LF-1K,1%,1/16W,CHIP,A':;

SECTION_NUMBER 1
 '@S9S_MB_2U_LIB.S9S_MB_2U(SCH_1):PAGE542_I152@PURE_QUANTA.Q_RES(CHIPS)':
 C_PATH='@s9s_mb_2u_lib.s9s_mb_2u(sch_1):page542_i152@pure_quanta.q_res(chips)';

PART_NAME
 R1737 'Q_RES_0402LF-10K,1%,1/16W,CHIPA':;

SECTION_NUMBER 1
 '@S9S_MB_2U_LIB.S9S_MB_2U(SCH_1):PAGE542_I144@PURE_QUANTA.Q_RES(CHIPS)':
 C_PATH='@s9s_mb_2u_lib.s9s_mb_2u(sch_1):page542_i144@pure_quanta.q_res(chips)';

PART_NAME
 R1644 'Q_RES_0402LF-1K,1%,1/16W,CHIP,A':;

SECTION_NUMBER 1
 '@S9S_MB_2U_LIB.S9S_MB_2U(SCH_1):PAGE542_I149@PURE_QUANTA.Q_RES(CHIPS)':
 C_PATH='@s9s_mb_2u_lib.s9s_mb_2u(sch_1):page542_i149@pure_quanta.q_res(chips)';

PART_NAME
 R1100 'Q_RES_0402LF-33.2,1%,1/16W,CHIA':;

SECTION_NUMBER 1
 '@S9S_MB_2U_LIB.S9S_MB_2U(SCH_1):PAGE542_I139@PURE_QUANTA.Q_RES(CHIPS)':
 C_PATH='@s9s_mb_2u_lib.s9s_mb_2u(sch_1):page542_i139@pure_quanta.q_res(chips)';

PART_NAME
 R1099 'Q_RES_0402LF-10K,1%,1/16W,CHIPA':;

SECTION_NUMBER 1
 '@S9S_MB_2U_LIB.S9S_MB_2U(SCH_1):PAGE542_I136@PURE_QUANTA.Q_RES(CHIPS)':
 C_PATH='@s9s_mb_2u_lib.s9s_mb_2u(sch_1):page542_i136@pure_quanta.q_res(chips)';

PART_NAME
 OSC2 'Q_OSC4P_SMLF-25MHZ,OSC,BF62500A':;

SECTION_NUMBER 1
 '@S9S_MB_2U_LIB.S9S_MB_2U(SCH_1):PAGE542_I132@PURE_QUANTA.Q_OSC4P(CHIPS)':
 C_PATH='@s9s_mb_2u_lib.s9s_mb_2u(sch_1):page542_i132@pure_quanta.q_osc4p(chips)';

PART_NAME
 C1320 'Q_CAP_0402-0.1UF,25V,10%,X7R,CA':;

SECTION_NUMBER 1
 '@S9S_MB_2U_LIB.S9S_MB_2U(SCH_1):PAGE542_I134@PURE_QUANTA.Q_CAP(CHIPS)':
 C_PATH='@s9s_mb_2u_lib.s9s_mb_2u(sch_1):page542_i134@pure_quanta.q_cap(chips)';

PART_NAME
 U95 'SN74LVC1G07DCKR-SN74LVC1G07DCKA':;

SECTION_NUMBER 1
 '@S9S_MB_2U_LIB.S9S_MB_2U(SCH_1):PAGE567_I18@PURE_QUANTA.SN74LVC1G07DCKR(CHIPS)':
 C_PATH='@s9s_mb_2u_lib.s9s_mb_2u(sch_1):page567_i18@pure_quanta.sn74lvc1g07dckr(c~
hips)';

PART_NAME
 U94 'ADM1085AKSZREEL7-ADM1085AKSZ-RA':;

SECTION_NUMBER 1
 '@S9S_MB_2U_LIB.S9S_MB_2U(SCH_1):PAGE567_I1@PURE_QUANTA.ADM1085AKSZREEL7(CHIPS)':
 C_PATH='@s9s_mb_2u_lib.s9s_mb_2u(sch_1):page567_i1@pure_quanta.adm1085akszreel7(c~
hips)';

PART_NAME
 R1745 'Q_RES_0402LF-0,5%,1/16W,EMPTY,A':;

SECTION_NUMBER 1
 '@S9S_MB_2U_LIB.S9S_MB_2U(SCH_1):PAGE567_I33@PURE_QUANTA.Q_RES(CHIPS)':
 C_PATH='@s9s_mb_2u_lib.s9s_mb_2u(sch_1):page567_i33@pure_quanta.q_res(chips)';

PART_NAME
 R1695 'Q_RES_0402LF-0,5%,1/16W,EMPTY,A':;

SECTION_NUMBER 1
 '@S9S_MB_2U_LIB.S9S_MB_2U(SCH_1):PAGE567_I31@PURE_QUANTA.Q_RES(CHIPS)':
 C_PATH='@s9s_mb_2u_lib.s9s_mb_2u(sch_1):page567_i31@pure_quanta.q_res(chips)';

PART_NAME
 R1694 'Q_RES_0402LF-10K,1%,1/16W,CHIPA':;

SECTION_NUMBER 1
 '@S9S_MB_2U_LIB.S9S_MB_2U(SCH_1):PAGE567_I28@PURE_QUANTA.Q_RES(CHIPS)':
 C_PATH='@s9s_mb_2u_lib.s9s_mb_2u(sch_1):page567_i28@pure_quanta.q_res(chips)';

PART_NAME
 R1693 'Q_RES_0402LF-33.2,1%,1/16W,CHIA':;

SECTION_NUMBER 1
 '@S9S_MB_2U_LIB.S9S_MB_2U(SCH_1):PAGE567_I25@PURE_QUANTA.Q_RES(CHIPS)':
 C_PATH='@s9s_mb_2u_lib.s9s_mb_2u(sch_1):page567_i25@pure_quanta.q_res(chips)';

PART_NAME
 R1692 'Q_RES_0402LF-100K,1%,1/16W,EMPA':;

SECTION_NUMBER 1
 '@S9S_MB_2U_LIB.S9S_MB_2U(SCH_1):PAGE567_I15@PURE_QUANTA.Q_RES(CHIPS)':
 C_PATH='@s9s_mb_2u_lib.s9s_mb_2u(sch_1):page567_i15@pure_quanta.q_res(chips)';

PART_NAME
 R1691 'Q_RES_0402LF-10K,1%,1/16W,CHIPA':;

SECTION_NUMBER 1
 '@S9S_MB_2U_LIB.S9S_MB_2U(SCH_1):PAGE567_I14@PURE_QUANTA.Q_RES(CHIPS)':
 C_PATH='@s9s_mb_2u_lib.s9s_mb_2u(sch_1):page567_i14@pure_quanta.q_res(chips)';

PART_NAME
 R1690 'Q_RES_0402LF-10K,1%,1/16W,CHIPA':;

SECTION_NUMBER 1
 '@S9S_MB_2U_LIB.S9S_MB_2U(SCH_1):PAGE567_I2@PURE_QUANTA.Q_RES(CHIPS)':
 C_PATH='@s9s_mb_2u_lib.s9s_mb_2u(sch_1):page567_i2@pure_quanta.q_res(chips)';

PART_NAME
 R1689 'Q_RES_0402LF-6.19K,1%,1/16W,CHA':;

SECTION_NUMBER 1
 '@S9S_MB_2U_LIB.S9S_MB_2U(SCH_1):PAGE567_I6@PURE_QUANTA.Q_RES(CHIPS)':
 C_PATH='@s9s_mb_2u_lib.s9s_mb_2u(sch_1):page567_i6@pure_quanta.q_res(chips)';

PART_NAME
 R1688 'Q_RES_0402LF-100K,1%,1/16W,CHIA':;

SECTION_NUMBER 1
 '@S9S_MB_2U_LIB.S9S_MB_2U(SCH_1):PAGE567_I4@PURE_QUANTA.Q_RES(CHIPS)':
 C_PATH='@s9s_mb_2u_lib.s9s_mb_2u(sch_1):page567_i4@pure_quanta.q_res(chips)';

PART_NAME
 C1319 'Q_CAP_C0402-1UF,25V,10%,X6S,CHA':;

SECTION_NUMBER 1
 '@S9S_MB_2U_LIB.S9S_MB_2U(SCH_1):PAGE567_I29@PURE_QUANTA.Q_CAP(CHIPS)':
 C_PATH='@s9s_mb_2u_lib.s9s_mb_2u(sch_1):page567_i29@pure_quanta.q_cap(chips)';

PART_NAME
 C1318 'Q_CAP_C0402-1UF,25V,10%,X6S,CHA':;

SECTION_NUMBER 1
 '@S9S_MB_2U_LIB.S9S_MB_2U(SCH_1):PAGE567_I20@PURE_QUANTA.Q_CAP(CHIPS)':
 C_PATH='@s9s_mb_2u_lib.s9s_mb_2u(sch_1):page567_i20@pure_quanta.q_cap(chips)';

PART_NAME
 C1317 'Q_CAP_0402-0.1UF,25V,10%,X7R,CA':;

SECTION_NUMBER 1
 '@S9S_MB_2U_LIB.S9S_MB_2U(SCH_1):PAGE567_I22@PURE_QUANTA.Q_CAP(CHIPS)':
 C_PATH='@s9s_mb_2u_lib.s9s_mb_2u(sch_1):page567_i22@pure_quanta.q_cap(chips)';

PART_NAME
 C1316 'Q_CAP_C0402-0.047UF,25V,10%,X7A':;

SECTION_NUMBER 1
 '@S9S_MB_2U_LIB.S9S_MB_2U(SCH_1):PAGE567_I12@PURE_QUANTA.Q_CAP(CHIPS)':
 C_PATH='@s9s_mb_2u_lib.s9s_mb_2u(sch_1):page567_i12@pure_quanta.q_cap(chips)';

PART_NAME
 C1315 'Q_CAP_C0402-1UF,25V,10%,X6S,CHA':;

SECTION_NUMBER 1
 '@S9S_MB_2U_LIB.S9S_MB_2U(SCH_1):PAGE567_I8@PURE_QUANTA.Q_CAP(CHIPS)':
 C_PATH='@s9s_mb_2u_lib.s9s_mb_2u(sch_1):page567_i8@pure_quanta.q_cap(chips)';

PART_NAME
 U74 'MOSFET_N_SMLF-BSS138K,BSS138K,A':;

SECTION_NUMBER 1
 '@S9S_MB_2U_LIB.S9S_MB_2U(SCH_1):PAGE604_I13@PURE_QUANTA.MOSFET_N(CHIPS)':
 C_PATH='@s9s_mb_2u_lib.s9s_mb_2u(sch_1):page604_i13@pure_quanta.mosfet_n(chips)';

PART_NAME
 R1685 'Q_RES_0402LF-0,5%,1/16W,CHIP,CA':;

SECTION_NUMBER 1
 '@S9S_MB_2U_LIB.S9S_MB_2U(SCH_1):PAGE604_I45@PURE_QUANTA.Q_RES(CHIPS)':
 C_PATH='@s9s_mb_2u_lib.s9s_mb_2u(sch_1):page604_i45@pure_quanta.q_res(chips)';

PART_NAME
 R1684 'Q_RES_0402LF-2K,1%,1/16W,CHIP,A':;

SECTION_NUMBER 1
 '@S9S_MB_2U_LIB.S9S_MB_2U(SCH_1):PAGE604_I41@PURE_QUANTA.Q_RES(CHIPS)':
 C_PATH='@s9s_mb_2u_lib.s9s_mb_2u(sch_1):page604_i41@pure_quanta.q_res(chips)';

PART_NAME
 R1683 'Q_RES_0402LF-10K,1%,1/16W,EMPTA':;

SECTION_NUMBER 1
 '@S9S_MB_2U_LIB.S9S_MB_2U(SCH_1):PAGE604_I39@PURE_QUANTA.Q_RES(CHIPS)':
 C_PATH='@s9s_mb_2u_lib.s9s_mb_2u(sch_1):page604_i39@pure_quanta.q_res(chips)';

PART_NAME
 R543 'Q_RES_0402LF-26.1K,1%,1/16W,CHA':;

SECTION_NUMBER 1
 '@S9S_MB_2U_LIB.S9S_MB_2U(SCH_1):PAGE604_I17@PURE_QUANTA.Q_RES(CHIPS)':
 C_PATH='@s9s_mb_2u_lib.s9s_mb_2u(sch_1):page604_i17@pure_quanta.q_res(chips)';

PART_NAME
 PU80 'MPQ8633AGLEC807Z-MPQ8633AGLE-CA':;

SECTION_NUMBER 1
 '@S9S_MB_2U_LIB.S9S_MB_2U(SCH_1):PAGE604_I29@PURE_QUANTA.MPQ8633AGLEC807Z(CHIPS)':
 C_PATH='@s9s_mb_2u_lib.s9s_mb_2u(sch_1):page604_i29@pure_quanta.mpq8633aglec807z(~
chips)';

PART_NAME
 PR1340 'Q_RES_0402LF-36K,1%,1/16W,CHIPA':;

SECTION_NUMBER 1
 '@S9S_MB_2U_LIB.S9S_MB_2U(SCH_1):PAGE604_I15@PURE_QUANTA.Q_RES(CHIPS)':
 C_PATH='@s9s_mb_2u_lib.s9s_mb_2u(sch_1):page604_i15@pure_quanta.q_res(chips)';

PART_NAME
 PR1339 'Q_RES_0402LF-9.31K,1%,1/16W,CHA':;

SECTION_NUMBER 1
 '@S9S_MB_2U_LIB.S9S_MB_2U(SCH_1):PAGE604_I31@PURE_QUANTA.Q_RES(CHIPS)':
 C_PATH='@s9s_mb_2u_lib.s9s_mb_2u(sch_1):page604_i31@pure_quanta.q_res(chips)';

PART_NAME
 PR1338 'Q_RES_0402LF-0,5%,1/16W,CHIP,CA':;

SECTION_NUMBER 1
 '@S9S_MB_2U_LIB.S9S_MB_2U(SCH_1):PAGE604_I33@PURE_QUANTA.Q_RES(CHIPS)':
 C_PATH='@s9s_mb_2u_lib.s9s_mb_2u(sch_1):page604_i33@pure_quanta.q_res(chips)';

PART_NAME
 PR1314 'Q_RES_0402LF-18.2K,0.1%,1/16W,A':;

SECTION_NUMBER 1
 '@S9S_MB_2U_LIB.S9S_MB_2U(SCH_1):PAGE604_I20@PURE_QUANTA.Q_RES(CHIPS)':
 C_PATH='@s9s_mb_2u_lib.s9s_mb_2u(sch_1):page604_i20@pure_quanta.q_res(chips)';

PART_NAME
 PR1313 'Q_RES_0402LF-10K,1%,1/16W,CHIPA':;

SECTION_NUMBER 1
 '@S9S_MB_2U_LIB.S9S_MB_2U(SCH_1):PAGE604_I51@PURE_QUANTA.Q_RES(CHIPS)':
 C_PATH='@s9s_mb_2u_lib.s9s_mb_2u(sch_1):page604_i51@pure_quanta.q_res(chips)';

PART_NAME
 PL119 'Q_INDUCTOR_SMLF-1UH,IND,CV-10BA':;

SECTION_NUMBER 1
 '@S9S_MB_2U_LIB.S9S_MB_2U(SCH_1):PAGE604_I14@PURE_QUANTA.Q_INDUCTOR(CHIPS)':
 C_PATH='@s9s_mb_a_lib.s9s_mb_a(sch_1):page604_i14@pure_quanta.q_inductor(chips)~
';

PART_NAME
 PC1771 'Q_CAPP_RDLF-560UF,6.3V,20%,ALUA':;

SECTION_NUMBER 1
 '@S9S_MB_2U_LIB.S9S_MB_2U(SCH_1):PAGE604_I4@PURE_QUANTA.Q_CAPP(CHIPS)':
 C_PATH='@s9s_mb_2u_lib.s9s_mb_2u(sch_1):page604_i4@pure_quanta.q_capp(chips)';

PART_NAME
 PC1270 'Q_CAP_0805-22UF,4V,20%,X6S,TMPA':;

SECTION_NUMBER 1
 '@S9S_MB_2U_LIB.S9S_MB_2U(SCH_1):PAGE604_I5@PURE_QUANTA.Q_CAP(CHIPS)':
 C_PATH='@s9s_mb_2u_lib.s9s_mb_2u(sch_1):page604_i5@pure_quanta.q_cap(chips)';

PART_NAME
 PC1269 'Q_CAP_0805-22UF,4V,20%,X6S,TMPA':;

SECTION_NUMBER 1
 '@S9S_MB_2U_LIB.S9S_MB_2U(SCH_1):PAGE604_I7@PURE_QUANTA.Q_CAP(CHIPS)':
 C_PATH='@s9s_mb_2u_lib.s9s_mb_2u(sch_1):page604_i7@pure_quanta.q_cap(chips)';

PART_NAME
 PC1268 'Q_CAP_0805-22UF,4V,20%,X6S,TMPA':;

SECTION_NUMBER 1
 '@S9S_MB_2U_LIB.S9S_MB_2U(SCH_1):PAGE604_I9@PURE_QUANTA.Q_CAP(CHIPS)':
 C_PATH='@s9s_mb_2u_lib.s9s_mb_2u(sch_1):page604_i9@pure_quanta.q_cap(chips)';

PART_NAME
 PC1267 'Q_CAP_0402-0.1UF,25V,10%,X7R,CA':;

SECTION_NUMBER 1
 '@S9S_MB_2U_LIB.S9S_MB_2U(SCH_1):PAGE604_I10@PURE_QUANTA.Q_CAP(CHIPS)':
 C_PATH='@s9s_mb_2u_lib.s9s_mb_2u(sch_1):page604_i10@pure_quanta.q_cap(chips)';

PART_NAME
 PC1266 'Q_CAP_0402-100PF,50V,5%,NPO,CHA':;

SECTION_NUMBER 1
 '@S9S_MB_2U_LIB.S9S_MB_2U(SCH_1):PAGE604_I16@PURE_QUANTA.Q_CAP(CHIPS)':
 C_PATH='@s9s_mb_2u_lib.s9s_mb_2u(sch_1):page604_i16@pure_quanta.q_cap(chips)';

PART_NAME
 PC1265 'Q_CAP_0402-0.22UF,16V,10%,X7R,A':;

SECTION_NUMBER 1
 '@S9S_MB_2U_LIB.S9S_MB_2U(SCH_1):PAGE604_I18@PURE_QUANTA.Q_CAP(CHIPS)':
 C_PATH='@s9s_mb_2u_lib.s9s_mb_2u(sch_1):page604_i18@pure_quanta.q_cap(chips)';

PART_NAME
 PC1264 'Q_CAP_0402-0.1UF,25V,10%,X7R,CA':;

SECTION_NUMBER 1
 '@S9S_MB_2U_LIB.S9S_MB_2U(SCH_1):PAGE604_I21@PURE_QUANTA.Q_CAP(CHIPS)':
 C_PATH='@s9s_mb_2u_lib.s9s_mb_2u(sch_1):page604_i21@pure_quanta.q_cap(chips)';

PART_NAME
 PC1262 'Q_CAP_0402-0.1UF,25V,10%,X7R,CA':;

SECTION_NUMBER 1
 '@S9S_MB_2U_LIB.S9S_MB_2U(SCH_1):PAGE604_I24@PURE_QUANTA.Q_CAP(CHIPS)':
 C_PATH='@s9s_mb_2u_lib.s9s_mb_2u(sch_1):page604_i24@pure_quanta.q_cap(chips)';

PART_NAME
 PC1261 'Q_CAP_C0805-22UF,16V,20%,X6S,CA':;

SECTION_NUMBER 1
 '@S9S_MB_2U_LIB.S9S_MB_2U(SCH_1):PAGE604_I25@PURE_QUANTA.Q_CAP(CHIPS)':
 C_PATH='@s9s_mb_2u_lib.s9s_mb_2u(sch_1):page604_i25@pure_quanta.q_cap(chips)';

PART_NAME
 PC1260 'Q_CAP_C0805-22UF,16V,20%,X6S,CA':;

SECTION_NUMBER 1
 '@S9S_MB_2U_LIB.S9S_MB_2U(SCH_1):PAGE604_I26@PURE_QUANTA.Q_CAP(CHIPS)':
 C_PATH='@s9s_mb_2u_lib.s9s_mb_2u(sch_1):page604_i26@pure_quanta.q_cap(chips)';

PART_NAME
 PC1259 'Q_CAP_C0805-22UF,16V,20%,X6S,CA':;

SECTION_NUMBER 1
 '@S9S_MB_2U_LIB.S9S_MB_2U(SCH_1):PAGE604_I28@PURE_QUANTA.Q_CAP(CHIPS)':
 C_PATH='@s9s_mb_2u_lib.s9s_mb_2u(sch_1):page604_i28@pure_quanta.q_cap(chips)';

PART_NAME
 PC644 'Q_CAP_C0402-1UF,25V,10%,X6S,CHA':;

SECTION_NUMBER 1
 '@S9S_MB_2U_LIB.S9S_MB_2U(SCH_1):PAGE604_I35@PURE_QUANTA.Q_CAP(CHIPS)':
 C_PATH='@s9s_mb_2u_lib.s9s_mb_2u(sch_1):page604_i35@pure_quanta.q_cap(chips)';

PART_NAME
 C1304 'Q_CAP_0402-1000PF,50V,5%,X7R,TA':;

SECTION_NUMBER 1
 '@S9S_MB_2U_LIB.S9S_MB_2U(SCH_1):PAGE604_I50@PURE_QUANTA.Q_CAP(CHIPS)':
 C_PATH='@s9s_mb_2u_lib.s9s_mb_2u(sch_1):page604_i50@pure_quanta.q_cap(chips)';

PART_NAME
 C1303 'Q_CAP_0402-1000PF,50V,5%,EMPTYA':;

SECTION_NUMBER 1
 '@S9S_MB_2U_LIB.S9S_MB_2U(SCH_1):PAGE604_I42@PURE_QUANTA.Q_CAP(CHIPS)':
 C_PATH='@s9s_mb_2u_lib.s9s_mb_2u(sch_1):page604_i42@pure_quanta.q_cap(chips)';

PART_NAME
 R1926 'Q_RES_0402LF-0,5%,1/16W,CHIP,CA':;

SECTION_NUMBER 1
 '@S9S_MB_2U_LIB.S9S_MB_2U(SCH_1):PAGE562_I407@PURE_QUANTA.Q_RES(CHIPS)':
 C_PATH='@s9s_mb_2u_lib.s9s_mb_2u(sch_1):page562_i407@pure_quanta.q_res(chips)';

PART_NAME
 R1925 'Q_RES_0402LF-0,5%,1/16W,CHIP,CA':;

SECTION_NUMBER 1
 '@S9S_MB_2U_LIB.S9S_MB_2U(SCH_1):PAGE562_I406@PURE_QUANTA.Q_RES(CHIPS)':
 C_PATH='@s9s_mb_2u_lib.s9s_mb_2u(sch_1):page562_i406@pure_quanta.q_res(chips)';

PART_NAME
 R1857 'Q_RES_0402LF-10K,1%,1/16W,CHIPA':;

SECTION_NUMBER 1
 '@S9S_MB_2U_LIB.S9S_MB_2U(SCH_1):PAGE562_I374@PURE_QUANTA.Q_RES(CHIPS)':
 C_PATH='@s9s_mb_2u_lib.s9s_mb_2u(sch_1):page562_i374@pure_quanta.q_res(chips)';

PART_NAME
 R1856 'Q_RES_0402LF-100,1%,1/16W,CHIPA':;

SECTION_NUMBER 1
 '@S9S_MB_2U_LIB.S9S_MB_2U(SCH_1):PAGE562_I391@PURE_QUANTA.Q_RES(CHIPS)':
 C_PATH='@s9s_mb_2u_lib.s9s_mb_2u(sch_1):page562_i391@pure_quanta.q_res(chips)';

PART_NAME
 R1855 'Q_RES_0402LF-10K,1%,1/16W,CHIPA':;

SECTION_NUMBER 1
 '@S9S_MB_2U_LIB.S9S_MB_2U(SCH_1):PAGE562_I386@PURE_QUANTA.Q_RES(CHIPS)':
 C_PATH='@s9s_mb_2u_lib.s9s_mb_2u(sch_1):page562_i386@pure_quanta.q_res(chips)';

PART_NAME
 R1854 'Q_RES_0402LF-10K,1%,1/16W,CHIPA':;

SECTION_NUMBER 1
 '@S9S_MB_2U_LIB.S9S_MB_2U(SCH_1):PAGE562_I390@PURE_QUANTA.Q_RES(CHIPS)':
 C_PATH='@s9s_mb_2u_lib.s9s_mb_2u(sch_1):page562_i390@pure_quanta.q_res(chips)';

PART_NAME
 R1845 'Q_RES_0402LF-0,5%,1/16W,CHIP,CA':;

SECTION_NUMBER 1
 '@S9S_MB_2U_LIB.S9S_MB_2U(SCH_1):PAGE562_I278@PURE_QUANTA.Q_RES(CHIPS)':
 C_PATH='@s9s_mb_2u_lib.s9s_mb_2u(sch_1):page562_i278@pure_quanta.q_res(chips)';

PART_NAME
 R1833 'Q_RES_0402LF-0,5%,1/16W,CHIP,CA':;

SECTION_NUMBER 1
 '@S9S_MB_2U_LIB.S9S_MB_2U(SCH_1):PAGE562_I285@PURE_QUANTA.Q_RES(CHIPS)':
 C_PATH='@s9s_mb_2u_lib.s9s_mb_2u(sch_1):page562_i285@pure_quanta.q_res(chips)';

PART_NAME
 R1816 'Q_RES_0402LF-0,5%,1/16W,CHIP,CA':;

SECTION_NUMBER 1
 '@S9S_MB_2U_LIB.S9S_MB_2U(SCH_1):PAGE562_I270@PURE_QUANTA.Q_RES(CHIPS)':
 C_PATH='@s9s_mb_2u_lib.s9s_mb_2u(sch_1):page562_i270@pure_quanta.q_res(chips)';

PART_NAME
 R1815 'Q_RES_0402LF-0,5%,1/16W,CHIP,CA':;

SECTION_NUMBER 1
 '@S9S_MB_2U_LIB.S9S_MB_2U(SCH_1):PAGE562_I269@PURE_QUANTA.Q_RES(CHIPS)':
 C_PATH='@s9s_mb_2u_lib.s9s_mb_2u(sch_1):page562_i269@pure_quanta.q_res(chips)';

PART_NAME
 R1801 'Q_RES_0402LF-0,5%,1/16W,CHIP,CA':;

SECTION_NUMBER 1
 '@S9S_MB_2U_LIB.S9S_MB_2U(SCH_1):PAGE562_I398@PURE_QUANTA.Q_RES(CHIPS)':
 C_PATH='@s9s_mb_2u_lib.s9s_mb_2u(sch_1):page562_i398@pure_quanta.q_res(chips)';

PART_NAME
 R1798 'Q_RES_0402LF-0,5%,1/16W,CHIP,CA':;

SECTION_NUMBER 1
 '@S9S_MB_2U_LIB.S9S_MB_2U(SCH_1):PAGE562_I332@PURE_QUANTA.Q_RES(CHIPS)':
 C_PATH='@s9s_mb_2u_lib.s9s_mb_2u(sch_1):page562_i332@pure_quanta.q_res(chips)';

PART_NAME
 R1797 'Q_RES_0402LF-0,5%,1/16W,CHIP,CA':;

SECTION_NUMBER 1
 '@S9S_MB_2U_LIB.S9S_MB_2U(SCH_1):PAGE562_I331@PURE_QUANTA.Q_RES(CHIPS)':
 C_PATH='@s9s_mb_2u_lib.s9s_mb_2u(sch_1):page562_i331@pure_quanta.q_res(chips)';

PART_NAME
 R1711 'Q_RES_0402LF-0,5%,1/16W,CHIP,CA':;

SECTION_NUMBER 1
 '@S9S_MB_2U_LIB.S9S_MB_2U(SCH_1):PAGE562_I268@PURE_QUANTA.Q_RES(CHIPS)':
 C_PATH='@s9s_mb_2u_lib.s9s_mb_2u(sch_1):page562_i268@pure_quanta.q_res(chips)';

PART_NAME
 R506 'Q_RES_0402LF-0,5%,1/16W,CHIP,CA':;

SECTION_NUMBER 1
 '@S9S_MB_2U_LIB.S9S_MB_2U(SCH_1):PAGE562_I284@PURE_QUANTA.Q_RES(CHIPS)':
 C_PATH='@s9s_mb_2u_lib.s9s_mb_2u(sch_1):page562_i284@pure_quanta.q_res(chips)';

PART_NAME
 R142 'Q_RES_0402LF-0,5%,1/16W,CHIP,CA':;

SECTION_NUMBER 1
 '@S9S_MB_2U_LIB.S9S_MB_2U(SCH_1):PAGE562_I99@PURE_QUANTA.Q_RES(CHIPS)':
 C_PATH='@s9s_mb_2u_lib.s9s_mb_2u(sch_1):page562_i99@pure_quanta.q_res(chips)';

PART_NAME
 Q39 'MOSFET_NCH_DUAL-2N7002KDW,SMLFA':;

SECTION_NUMBER 1
 '@S9S_MB_2U_LIB.S9S_MB_2U(SCH_1):PAGE562_I381@PURE_QUANTA.MOSFET_NCH_DUAL(CHIPS)':
 C_PATH='@s9s_mb_2u_lib.s9s_mb_2u(sch_1):page562_i381@pure_quanta.mosfet_nch_dual(~
chips)';

SECTION_NUMBER 2
 '@S9S_MB_2U_LIB.S9S_MB_2U(SCH_1):PAGE562_I372@PURE_QUANTA.MOSFET_NCH_DUAL(CHIPS)':
 C_PATH='@s9s_mb_2u_lib.s9s_mb_2u(sch_1):page562_i372@pure_quanta.mosfet_nch_dual(~
chips)';

PART_NAME
 Q32 'MOSFET_PCH_GDS_ESD_PROTECTED-DA':;

SECTION_NUMBER 1
 '@S9S_MB_2U_LIB.S9S_MB_2U(SCH_1):PAGE562_I314@PURE_QUANTA.MOSFET_PCH_GDS_ESD_PROTECTED(CHIPS)':
 C_PATH='@s9s_mb_2u_lib.s9s_mb_2u(sch_1):page562_i314@pure_quanta.mosfet_pch_gds_e~
sd_protected(chips)';

PART_NAME
 J41 'SCONN168_623403212-SCONN168_6-A':;

SECTION_NUMBER 1
 '@S9S_MB_2U_LIB.S9S_MB_2U(SCH_1):PAGE562_I115@PURE_QUANTA.SCONN168_623403212(CHIPS)':
 C_PATH='@s9s_mb_2u_lib.s9s_mb_2u(sch_1):page562_i115@pure_quanta.sconn168_6234032~
12(chips)';

PART_NAME
 C1352 'Q_CAP_C0805-10UF,25V,10%,X6S,CA':;

SECTION_NUMBER 1
 '@S9S_MB_2U_LIB.S9S_MB_2U(SCH_1):PAGE562_I333@PURE_QUANTA.Q_CAP(CHIPS)':
 C_PATH='@s9s_mb_2u_lib.s9s_mb_2u(sch_1):page562_i333@pure_quanta.q_cap(chips)';

PART_NAME
 C1348 'Q_CAP_0603-1UF,25V,10%,X7R,CH5A':;

SECTION_NUMBER 1
 '@S9S_MB_2U_LIB.S9S_MB_2U(SCH_1):PAGE562_I323@PURE_QUANTA.Q_CAP(CHIPS)':
 C_PATH='@s9s_mb_2u_lib.s9s_mb_2u(sch_1):page562_i323@pure_quanta.q_cap(chips)';

PART_NAME
 C1302 'Q_CAP_C0402-22UF,4V,20%,X6S,CHA':;

SECTION_NUMBER 1
 '@S9S_MB_2U_LIB.S9S_MB_2U(SCH_1):PAGE562_I101@PURE_QUANTA.Q_CAP(CHIPS)':
 C_PATH='@s9s_mb_2u_lib.s9s_mb_2u(sch_1):page562_i101@pure_quanta.q_cap(chips)';

PART_NAME
 U73 'MOSFET_N_SMLF-BSS138K,BSS138K,A':;

SECTION_NUMBER 1
 '@S9S_MB_2U_LIB.S9S_MB_2U(SCH_1):PAGE454_I10@PURE_QUANTA.MOSFET_N(CHIPS)':
 C_PATH='@s9s_mb_2u_lib.s9s_mb_2u(sch_1):page454_i10@pure_quanta.mosfet_n(chips)';

PART_NAME
 R1679 'Q_RES_0402LF-0,5%,1/16W,CHIP,CA':;

SECTION_NUMBER 1
 '@S9S_MB_2U_LIB.S9S_MB_2U(SCH_1):PAGE454_I47@PURE_QUANTA.Q_RES(CHIPS)':
 C_PATH='@s9s_mb_2u_lib.s9s_mb_2u(sch_1):page454_i47@pure_quanta.q_res(chips)';

PART_NAME
 R1678 'Q_RES_0402LF-2K,1%,1/16W,CHIP,A':;

SECTION_NUMBER 1
 '@S9S_MB_2U_LIB.S9S_MB_2U(SCH_1):PAGE454_I41@PURE_QUANTA.Q_RES(CHIPS)':
 C_PATH='@s9s_mb_2u_lib.s9s_mb_2u(sch_1):page454_i41@pure_quanta.q_res(chips)';

PART_NAME
 R1677 'Q_RES_0402LF-10K,1%,1/16W,EMPTA':;

SECTION_NUMBER 1
 '@S9S_MB_2U_LIB.S9S_MB_2U(SCH_1):PAGE454_I37@PURE_QUANTA.Q_RES(CHIPS)':
 C_PATH='@s9s_mb_2u_lib.s9s_mb_2u(sch_1):page454_i37@pure_quanta.q_res(chips)';

PART_NAME
 R542 'Q_RES_0402LF-26.1K,1%,1/16W,CHA':;

SECTION_NUMBER 1
 '@S9S_MB_2U_LIB.S9S_MB_2U(SCH_1):PAGE454_I18@PURE_QUANTA.Q_RES(CHIPS)':
 C_PATH='@s9s_mb_2u_lib.s9s_mb_2u(sch_1):page454_i18@pure_quanta.q_res(chips)';

PART_NAME
 PU79 'MPQ8633AGLEC807Z-MPQ8633AGLE-CA':;

SECTION_NUMBER 1
 '@S9S_MB_2U_LIB.S9S_MB_2U(SCH_1):PAGE454_I25@PURE_QUANTA.MPQ8633AGLEC807Z(CHIPS)':
 C_PATH='@s9s_mb_2u_lib.s9s_mb_2u(sch_1):page454_i25@pure_quanta.mpq8633aglec807z(~
chips)';

PART_NAME
 PR1337 'Q_RES_0402LF-36K,1%,1/16W,CHIPA':;

SECTION_NUMBER 1
 '@S9S_MB_2U_LIB.S9S_MB_2U(SCH_1):PAGE454_I16@PURE_QUANTA.Q_RES(CHIPS)':
 C_PATH='@s9s_mb_2u_lib.s9s_mb_2u(sch_1):page454_i16@pure_quanta.q_res(chips)';

PART_NAME
 PR1336 'Q_RES_0402LF-9.31K,1%,1/16W,CHA':;

SECTION_NUMBER 1
 '@S9S_MB_2U_LIB.S9S_MB_2U(SCH_1):PAGE454_I26@PURE_QUANTA.Q_RES(CHIPS)':
 C_PATH='@s9s_mb_2u_lib.s9s_mb_2u(sch_1):page454_i26@pure_quanta.q_res(chips)';

PART_NAME
 PR1335 'Q_RES_0402LF-0,5%,1/16W,CHIP,CA':;

SECTION_NUMBER 1
 '@S9S_MB_2U_LIB.S9S_MB_2U(SCH_1):PAGE454_I34@PURE_QUANTA.Q_RES(CHIPS)':
 C_PATH='@s9s_mb_2u_lib.s9s_mb_2u(sch_1):page454_i34@pure_quanta.q_res(chips)';

PART_NAME
 PR1310 'Q_RES_0402LF-18.2K,0.1%,1/16W,A':;

SECTION_NUMBER 1
 '@S9S_MB_2U_LIB.S9S_MB_2U(SCH_1):PAGE454_I19@PURE_QUANTA.Q_RES(CHIPS)':
 C_PATH='@s9s_mb_2u_lib.s9s_mb_2u(sch_1):page454_i19@pure_quanta.q_res(chips)';

PART_NAME
 PR1309 'Q_RES_0402LF-10K,1%,1/16W,CHIPA':;

SECTION_NUMBER 1
 '@S9S_MB_2U_LIB.S9S_MB_2U(SCH_1):PAGE454_I42@PURE_QUANTA.Q_RES(CHIPS)':
 C_PATH='@s9s_mb_2u_lib.s9s_mb_2u(sch_1):page454_i42@pure_quanta.q_res(chips)';

PART_NAME
 PL118 'Q_INDUCTOR_SMLF-1UH,IND,CV-10BA':;

SECTION_NUMBER 1
 '@S9S_MB_2U_LIB.S9S_MB_2U(SCH_1):PAGE454_I12@PURE_QUANTA.Q_INDUCTOR(CHIPS)':
 C_PATH='@s9s_mb_a_lib.s9s_mb_a(sch_1):page454_i12@pure_quanta.q_inductor(chips)~
';

PART_NAME
 PC2643 'Q_CAP_C0402-1UF,25V,10%,X6S,CHA':;

SECTION_NUMBER 1
 '@S9S_MB_2U_LIB.S9S_MB_2U(SCH_1):PAGE454_I35@PURE_QUANTA.Q_CAP(CHIPS)':
 C_PATH='@s9s_mb_2u_lib.s9s_mb_2u(sch_1):page454_i35@pure_quanta.q_cap(chips)';

PART_NAME
 PC1417 'Q_CAP_C0805-22UF,16V,20%,X6S,CA':;

SECTION_NUMBER 1
 '@S9S_MB_2U_LIB.S9S_MB_2U(SCH_1):PAGE454_I49@PURE_QUANTA.Q_CAP(CHIPS)':
 C_PATH='@s9s_mb_2u_lib.s9s_mb_2u(sch_1):page454_i49@pure_quanta.q_cap(chips)';

PART_NAME
 PC1258 'Q_CAPP_RDLF-560UF,6.3V,20%,ALUA':;

SECTION_NUMBER 1
 '@S9S_MB_2U_LIB.S9S_MB_2U(SCH_1):PAGE454_I2@PURE_QUANTA.Q_CAPP(CHIPS)':
 C_PATH='@s9s_mb_2u_lib.s9s_mb_2u(sch_1):page454_i2@pure_quanta.q_capp(chips)';

PART_NAME
 PC1257 'Q_CAP_0805-22UF,4V,20%,X6S,TMPA':;

SECTION_NUMBER 1
 '@S9S_MB_2U_LIB.S9S_MB_2U(SCH_1):PAGE454_I3@PURE_QUANTA.Q_CAP(CHIPS)':
 C_PATH='@s9s_mb_2u_lib.s9s_mb_2u(sch_1):page454_i3@pure_quanta.q_cap(chips)';

PART_NAME
 PC1256 'Q_CAP_0805-22UF,4V,20%,X6S,TMPA':;

SECTION_NUMBER 1
 '@S9S_MB_2U_LIB.S9S_MB_2U(SCH_1):PAGE454_I4@PURE_QUANTA.Q_CAP(CHIPS)':
 C_PATH='@s9s_mb_2u_lib.s9s_mb_2u(sch_1):page454_i4@pure_quanta.q_cap(chips)';

PART_NAME
 PC1255 'Q_CAP_0805-22UF,4V,20%,X6S,TMPA':;

SECTION_NUMBER 1
 '@S9S_MB_2U_LIB.S9S_MB_2U(SCH_1):PAGE454_I5@PURE_QUANTA.Q_CAP(CHIPS)':
 C_PATH='@s9s_mb_2u_lib.s9s_mb_2u(sch_1):page454_i5@pure_quanta.q_cap(chips)';

PART_NAME
 PC1254 'Q_CAP_0402-0.1UF,25V,10%,X7R,CA':;

SECTION_NUMBER 1
 '@S9S_MB_2U_LIB.S9S_MB_2U(SCH_1):PAGE454_I7@PURE_QUANTA.Q_CAP(CHIPS)':
 C_PATH='@s9s_mb_2u_lib.s9s_mb_2u(sch_1):page454_i7@pure_quanta.q_cap(chips)';

PART_NAME
 PC1253 'Q_CAP_0402-100PF,50V,5%,NPO,CHA':;

SECTION_NUMBER 1
 '@S9S_MB_2U_LIB.S9S_MB_2U(SCH_1):PAGE454_I17@PURE_QUANTA.Q_CAP(CHIPS)':
 C_PATH='@s9s_mb_2u_lib.s9s_mb_2u(sch_1):page454_i17@pure_quanta.q_cap(chips)';

PART_NAME
 PC1252 'Q_CAP_0402-0.22UF,16V,10%,X7R,A':;

SECTION_NUMBER 1
 '@S9S_MB_2U_LIB.S9S_MB_2U(SCH_1):PAGE454_I15@PURE_QUANTA.Q_CAP(CHIPS)':
 C_PATH='@s9s_mb_2u_lib.s9s_mb_2u(sch_1):page454_i15@pure_quanta.q_cap(chips)';

PART_NAME
 PC1251 'Q_CAP_0402-0.1UF,25V,10%,X7R,CA':;

SECTION_NUMBER 1
 '@S9S_MB_2U_LIB.S9S_MB_2U(SCH_1):PAGE454_I21@PURE_QUANTA.Q_CAP(CHIPS)':
 C_PATH='@s9s_mb_2u_lib.s9s_mb_2u(sch_1):page454_i21@pure_quanta.q_cap(chips)';

PART_NAME
 PC1249 'Q_CAP_0402-0.1UF,25V,10%,X7R,CA':;

SECTION_NUMBER 1
 '@S9S_MB_2U_LIB.S9S_MB_2U(SCH_1):PAGE454_I24@PURE_QUANTA.Q_CAP(CHIPS)':
 C_PATH='@s9s_mb_2u_lib.s9s_mb_2u(sch_1):page454_i24@pure_quanta.q_cap(chips)';

PART_NAME
 PC1248 'Q_CAP_C0805-22UF,16V,20%,X6S,CA':;

SECTION_NUMBER 1
 '@S9S_MB_2U_LIB.S9S_MB_2U(SCH_1):PAGE454_I28@PURE_QUANTA.Q_CAP(CHIPS)':
 C_PATH='@s9s_mb_2u_lib.s9s_mb_2u(sch_1):page454_i28@pure_quanta.q_cap(chips)';

PART_NAME
 PC1247 'Q_CAP_C0805-22UF,16V,20%,X6S,CA':;

SECTION_NUMBER 1
 '@S9S_MB_2U_LIB.S9S_MB_2U(SCH_1):PAGE454_I29@PURE_QUANTA.Q_CAP(CHIPS)':
 C_PATH='@s9s_mb_2u_lib.s9s_mb_2u(sch_1):page454_i29@pure_quanta.q_cap(chips)';

PART_NAME
 C1301 'Q_CAP_0402-1000PF,50V,5%,X7R,TA':;

SECTION_NUMBER 1
 '@S9S_MB_2U_LIB.S9S_MB_2U(SCH_1):PAGE454_I46@PURE_QUANTA.Q_CAP(CHIPS)':
 C_PATH='@s9s_mb_2u_lib.s9s_mb_2u(sch_1):page454_i46@pure_quanta.q_cap(chips)';

PART_NAME
 C1300 'Q_CAP_0402-1000PF,50V,5%,EMPTYA':;

SECTION_NUMBER 1
 '@S9S_MB_2U_LIB.S9S_MB_2U(SCH_1):PAGE454_I40@PURE_QUANTA.Q_CAP(CHIPS)':
 C_PATH='@s9s_mb_2u_lib.s9s_mb_2u(sch_1):page454_i40@pure_quanta.q_cap(chips)';

PART_NAME
 R1687 'Q_RES_0402LF-2K,1%,1/16W,CHIP,A':;

SECTION_NUMBER 1
 '@S9S_MB_2U_LIB.S9S_MB_2U(SCH_1):PAGE610_I50@PURE_QUANTA.Q_RES(CHIPS)':
 C_PATH='@s9s_mb_2u_lib.s9s_mb_2u(sch_1):page610_i50@pure_quanta.q_res(chips)';

PART_NAME
 R1686 'Q_RES_0402LF-10K,1%,1/16W,EMPTA':;

SECTION_NUMBER 1
 '@S9S_MB_2U_LIB.S9S_MB_2U(SCH_1):PAGE610_I48@PURE_QUANTA.Q_RES(CHIPS)':
 C_PATH='@s9s_mb_2u_lib.s9s_mb_2u(sch_1):page610_i48@pure_quanta.q_res(chips)';

PART_NAME
 R1653 'Q_RES_0402LF-0,5%,1/16W,CHIP,CA':;

SECTION_NUMBER 1
 '@S9S_MB_2U_LIB.S9S_MB_2U(SCH_1):PAGE610_I35@PURE_QUANTA.Q_RES(CHIPS)':
 C_PATH='@s9s_mb_2u_lib.s9s_mb_2u(sch_1):page610_i35@pure_quanta.q_res(chips)';

PART_NAME
 PU82 'NB695GDZ-NB695GD-Z,SMLF,IC,AL0A':;

SECTION_NUMBER 1
 '@S9S_MB_2U_LIB.S9S_MB_2U(SCH_1):PAGE610_I14@PURE_QUANTA.NB695GDZ(CHIPS)':
 C_PATH='@s9s_mb_2u_lib.s9s_mb_2u(sch_1):page610_i14@pure_quanta.nb695gdz(chips)';

PART_NAME
 PR1344 'Q_RES_0402LF -100K,0.1%,1/16W,A':;

SECTION_NUMBER 1
 '@S9S_MB_2U_LIB.S9S_MB_2U(SCH_1):PAGE610_I20@PURE_QUANTA.Q_RES(CHIPS)':
 C_PATH='@s9s_mb_2u_lib.s9s_mb_2u(sch_1):page610_i20@pure_quanta.q_res(chips)';

PART_NAME
 PR1343 'Q_RES_0402LF-5.1,5%,1/16W,CHIPA':;

SECTION_NUMBER 1
 '@S9S_MB_2U_LIB.S9S_MB_2U(SCH_1):PAGE610_I24@PURE_QUANTA.Q_RES(CHIPS)':
 C_PATH='@s9s_mb_2u_lib.s9s_mb_2u(sch_1):page610_i24@pure_quanta.q_res(chips)';

PART_NAME
 PR1320 'Q_RES_0402LF-10K,1%,1/16W,CHIPA':;

SECTION_NUMBER 1
 '@S9S_MB_2U_LIB.S9S_MB_2U(SCH_1):PAGE610_I34@PURE_QUANTA.Q_RES(CHIPS)':
 C_PATH='@s9s_mb_2u_lib.s9s_mb_2u(sch_1):page610_i34@pure_quanta.q_res(chips)';

PART_NAME
 PL121 'Q_INDUCTOR_SMLF-1UH,IND,CV-10BA':;

SECTION_NUMBER 1
 '@S9S_MB_2U_LIB.S9S_MB_2U(SCH_1):PAGE610_I12@PURE_QUANTA.Q_INDUCTOR(CHIPS)':
 C_PATH='@s9s_mb_a_lib.s9s_mb_a(sch_1):page610_i12@pure_quanta.q_inductor(chips)~
';

PART_NAME
 PC1287 'Q_CAP_0805-22UF,4V,20%,X6S,TMPA':;

SECTION_NUMBER 1
 '@S9S_MB_2U_LIB.S9S_MB_2U(SCH_1):PAGE610_I3@PURE_QUANTA.Q_CAP(CHIPS)':
 C_PATH='@s9s_mb_2u_lib.s9s_mb_2u(sch_1):page610_i3@pure_quanta.q_cap(chips)';

PART_NAME
 PC1286 'Q_CAP_0805-22UF,4V,20%,X6S,TMPA':;

SECTION_NUMBER 1
 '@S9S_MB_2U_LIB.S9S_MB_2U(SCH_1):PAGE610_I9@PURE_QUANTA.Q_CAP(CHIPS)':
 C_PATH='@s9s_mb_2u_lib.s9s_mb_2u(sch_1):page610_i9@pure_quanta.q_cap(chips)';

PART_NAME
 PC1285 'Q_CAP_0805-22UF,4V,20%,X6S,TMPA':;

SECTION_NUMBER 1
 '@S9S_MB_2U_LIB.S9S_MB_2U(SCH_1):PAGE610_I10@PURE_QUANTA.Q_CAP(CHIPS)':
 C_PATH='@s9s_mb_2u_lib.s9s_mb_2u(sch_1):page610_i10@pure_quanta.q_cap(chips)';

PART_NAME
 PC1284 'Q_CAP_C0402-100NF,50V,10%,X7R,A':;

SECTION_NUMBER 1
 '@S9S_MB_2U_LIB.S9S_MB_2U(SCH_1):PAGE610_I11@PURE_QUANTA.Q_CAP(CHIPS)':
 C_PATH='@s9s_mb_2u_lib.s9s_mb_2u(sch_1):page610_i11@pure_quanta.q_cap(chips)';

PART_NAME
 PC1283 'Q_CAP_0402-0.22UF,16V,10%,X7R,A':;

SECTION_NUMBER 1
 '@S9S_MB_2U_LIB.S9S_MB_2U(SCH_1):PAGE610_I8@PURE_QUANTA.Q_CAP(CHIPS)':
 C_PATH='@s9s_mb_2u_lib.s9s_mb_2u(sch_1):page610_i8@pure_quanta.q_cap(chips)';

PART_NAME
 PC1282 'Q_CAP_C0402-100NF,50V,10%,X7R,A':;

SECTION_NUMBER 1
 '@S9S_MB_2U_LIB.S9S_MB_2U(SCH_1):PAGE610_I16@PURE_QUANTA.Q_CAP(CHIPS)':
 C_PATH='@s9s_mb_2u_lib.s9s_mb_2u(sch_1):page610_i16@pure_quanta.q_cap(chips)';

PART_NAME
 PC1281 'Q_CAP_C0805-22UF,16V,20%,X6S,CA':;

SECTION_NUMBER 1
 '@S9S_MB_2U_LIB.S9S_MB_2U(SCH_1):PAGE610_I17@PURE_QUANTA.Q_CAP(CHIPS)':
 C_PATH='@s9s_mb_2u_lib.s9s_mb_2u(sch_1):page610_i17@pure_quanta.q_cap(chips)';

PART_NAME
 PC1280 'Q_CAP_C0805-22UF,16V,20%,X6S,CA':;

SECTION_NUMBER 1
 '@S9S_MB_2U_LIB.S9S_MB_2U(SCH_1):PAGE610_I18@PURE_QUANTA.Q_CAP(CHIPS)':
 C_PATH='@s9s_mb_2u_lib.s9s_mb_2u(sch_1):page610_i18@pure_quanta.q_cap(chips)';

PART_NAME
 PC1207 'Q_CAP_0805-22UF,4V,20%,X6S,TMPA':;

SECTION_NUMBER 1
 '@S9S_MB_2U_LIB.S9S_MB_2U(SCH_1):PAGE610_I2@PURE_QUANTA.Q_CAP(CHIPS)':
 C_PATH='@s9s_mb_2u_lib.s9s_mb_2u(sch_1):page610_i2@pure_quanta.q_cap(chips)';

PART_NAME
 PC1170 'Q_CAP_C0402-1UF,25V,10%,X6S,CHA':;

SECTION_NUMBER 1
 '@S9S_MB_2U_LIB.S9S_MB_2U(SCH_1):PAGE610_I25@PURE_QUANTA.Q_CAP(CHIPS)':
 C_PATH='@s9s_mb_2u_lib.s9s_mb_2u(sch_1):page610_i25@pure_quanta.q_cap(chips)';

PART_NAME
 C1308 'Q_CAP_0402-1000PF,50V,5%,EMPTYA':;

SECTION_NUMBER 1
 '@S9S_MB_2U_LIB.S9S_MB_2U(SCH_1):PAGE610_I49@PURE_QUANTA.Q_CAP(CHIPS)':
 C_PATH='@s9s_mb_2u_lib.s9s_mb_2u(sch_1):page610_i49@pure_quanta.q_cap(chips)';

PART_NAME
 C1297 'Q_CAP_0402-1000PF,50V,5%,X7R,TA':;

SECTION_NUMBER 1
 '@S9S_MB_2U_LIB.S9S_MB_2U(SCH_1):PAGE610_I38@PURE_QUANTA.Q_CAP(CHIPS)':
 C_PATH='@s9s_mb_2u_lib.s9s_mb_2u(sch_1):page610_i38@pure_quanta.q_cap(chips)';

PART_NAME
 R1652 'Q_RES_0402LF-0,5%,1/16W,CHIP,CA':;

SECTION_NUMBER 1
 '@S9S_MB_2U_LIB.S9S_MB_2U(SCH_1):PAGE586_I28@PURE_QUANTA.Q_RES(CHIPS)':
 C_PATH='@s9s_mb_2u_lib.s9s_mb_2u(sch_1):page586_i28@pure_quanta.q_res(chips)';

PART_NAME
 R1445 'Q_RES_0402LF-2K,1%,1/16W,CHIP,A':;

SECTION_NUMBER 1
 '@S9S_MB_2U_LIB.S9S_MB_2U(SCH_1):PAGE586_I38@PURE_QUANTA.Q_RES(CHIPS)':
 C_PATH='@s9s_mb_2u_lib.s9s_mb_2u(sch_1):page586_i38@pure_quanta.q_res(chips)';

PART_NAME
 R1145 'Q_RES_0402LF-10K,1%,1/16W,EMPTA':;

SECTION_NUMBER 1
 '@S9S_MB_2U_LIB.S9S_MB_2U(SCH_1):PAGE586_I36@PURE_QUANTA.Q_RES(CHIPS)':
 C_PATH='@s9s_mb_2u_lib.s9s_mb_2u(sch_1):page586_i36@pure_quanta.q_res(chips)';

PART_NAME
 PU81 'NB695GDZ-NB695GD-Z,SMLF,IC,AL0A':;

SECTION_NUMBER 1
 '@S9S_MB_2U_LIB.S9S_MB_2U(SCH_1):PAGE586_I21@PURE_QUANTA.NB695GDZ(CHIPS)':
 C_PATH='@s9s_mb_2u_lib.s9s_mb_2u(sch_1):page586_i21@pure_quanta.nb695gdz(chips)';

PART_NAME
 PR1342 'Q_RES_0402LF -100K,0.1%,1/16W,A':;

SECTION_NUMBER 1
 '@S9S_MB_2U_LIB.S9S_MB_2U(SCH_1):PAGE586_I23@PURE_QUANTA.Q_RES(CHIPS)':
 C_PATH='@s9s_mb_2u_lib.s9s_mb_2u(sch_1):page586_i23@pure_quanta.q_res(chips)';

PART_NAME
 PR1341 'Q_RES_0402LF-5.1,5%,1/16W,CHIPA':;

SECTION_NUMBER 1
 '@S9S_MB_2U_LIB.S9S_MB_2U(SCH_1):PAGE586_I25@PURE_QUANTA.Q_RES(CHIPS)':
 C_PATH='@s9s_mb_2u_lib.s9s_mb_2u(sch_1):page586_i25@pure_quanta.q_res(chips)';

PART_NAME
 PR1317 'Q_RES_0402LF-10K,1%,1/16W,CHIPA':;

SECTION_NUMBER 1
 '@S9S_MB_2U_LIB.S9S_MB_2U(SCH_1):PAGE586_I31@PURE_QUANTA.Q_RES(CHIPS)':
 C_PATH='@s9s_mb_2u_lib.s9s_mb_2u(sch_1):page586_i31@pure_quanta.q_res(chips)';

PART_NAME
 PL120 'Q_INDUCTOR_SMLF-1UH,IND,CV-10BA':;

SECTION_NUMBER 1
 '@S9S_MB_2U_LIB.S9S_MB_2U(SCH_1):PAGE586_I9@PURE_QUANTA.Q_INDUCTOR(CHIPS)':
 C_PATH='@s9s_mb_2u_lib.s9s_mb_2u(sch_1):page586_i9@pure_quanta.q_inductor(chips)';

PART_NAME
 PC1279 'Q_CAP_0805-22UF,4V,20%,X6S,TMPA':;

SECTION_NUMBER 1
 '@S9S_MB_2U_LIB.S9S_MB_2U(SCH_1):PAGE586_I4@PURE_QUANTA.Q_CAP(CHIPS)':
 C_PATH='@s9s_mb_2u_lib.s9s_mb_2u(sch_1):page586_i4@pure_quanta.q_cap(chips)';

PART_NAME
 PC1278 'Q_CAP_0805-22UF,4V,20%,X6S,TMPA':;

SECTION_NUMBER 1
 '@S9S_MB_2U_LIB.S9S_MB_2U(SCH_1):PAGE586_I6@PURE_QUANTA.Q_CAP(CHIPS)':
 C_PATH='@s9s_mb_2u_lib.s9s_mb_2u(sch_1):page586_i6@pure_quanta.q_cap(chips)';

PART_NAME
 PC1277 'Q_CAP_0805-22UF,4V,20%,X6S,TMPA':;

SECTION_NUMBER 1
 '@S9S_MB_2U_LIB.S9S_MB_2U(SCH_1):PAGE586_I7@PURE_QUANTA.Q_CAP(CHIPS)':
 C_PATH='@s9s_mb_2u_lib.s9s_mb_2u(sch_1):page586_i7@pure_quanta.q_cap(chips)';

PART_NAME
 PC1276 'Q_CAP_C0402-100NF,50V,10%,X7R,A':;

SECTION_NUMBER 1
 '@S9S_MB_2U_LIB.S9S_MB_2U(SCH_1):PAGE586_I8@PURE_QUANTA.Q_CAP(CHIPS)':
 C_PATH='@s9s_mb_2u_lib.s9s_mb_2u(sch_1):page586_i8@pure_quanta.q_cap(chips)';

PART_NAME
 PC1275 'Q_CAP_0402-0.22UF,16V,10%,X7R,A':;

SECTION_NUMBER 1
 '@S9S_MB_2U_LIB.S9S_MB_2U(SCH_1):PAGE586_I12@PURE_QUANTA.Q_CAP(CHIPS)':
 C_PATH='@s9s_mb_2u_lib.s9s_mb_2u(sch_1):page586_i12@pure_quanta.q_cap(chips)';

PART_NAME
 PC1274 'Q_CAP_C0402-100NF,50V,10%,X7R,A':;

SECTION_NUMBER 1
 '@S9S_MB_2U_LIB.S9S_MB_2U(SCH_1):PAGE586_I13@PURE_QUANTA.Q_CAP(CHIPS)':
 C_PATH='@s9s_mb_2u_lib.s9s_mb_2u(sch_1):page586_i13@pure_quanta.q_cap(chips)';

PART_NAME
 PC1273 'Q_CAP_C0805-22UF,16V,20%,X6S,CA':;

SECTION_NUMBER 1
 '@S9S_MB_2U_LIB.S9S_MB_2U(SCH_1):PAGE586_I14@PURE_QUANTA.Q_CAP(CHIPS)':
 C_PATH='@s9s_mb_2u_lib.s9s_mb_2u(sch_1):page586_i14@pure_quanta.q_cap(chips)';

PART_NAME
 PC1272 'Q_CAP_C0805-22UF,16V,20%,X6S,CA':;

SECTION_NUMBER 1
 '@S9S_MB_2U_LIB.S9S_MB_2U(SCH_1):PAGE586_I16@PURE_QUANTA.Q_CAP(CHIPS)':
 C_PATH='@s9s_mb_2u_lib.s9s_mb_2u(sch_1):page586_i16@pure_quanta.q_cap(chips)';

PART_NAME
 PC1206 'Q_CAP_0805-22UF,4V,20%,X6S,TMPA':;

SECTION_NUMBER 1
 '@S9S_MB_2U_LIB.S9S_MB_2U(SCH_1):PAGE586_I2@PURE_QUANTA.Q_CAP(CHIPS)':
 C_PATH='@s9s_mb_2u_lib.s9s_mb_2u(sch_1):page586_i2@pure_quanta.q_cap(chips)';

PART_NAME
 PC645 'Q_CAP_C0402-1UF,25V,10%,X6S,CHA':;

SECTION_NUMBER 1
 '@S9S_MB_2U_LIB.S9S_MB_2U(SCH_1):PAGE586_I26@PURE_QUANTA.Q_CAP(CHIPS)':
 C_PATH='@s9s_mb_2u_lib.s9s_mb_2u(sch_1):page586_i26@pure_quanta.q_cap(chips)';

PART_NAME
 C1307 'Q_CAP_0402-1000PF,50V,5%,EMPTYA':;

SECTION_NUMBER 1
 '@S9S_MB_2U_LIB.S9S_MB_2U(SCH_1):PAGE586_I37@PURE_QUANTA.Q_CAP(CHIPS)':
 C_PATH='@s9s_mb_2u_lib.s9s_mb_2u(sch_1):page586_i37@pure_quanta.q_cap(chips)';

PART_NAME
 C1296 'Q_CAP_0402-1000PF,50V,5%,X7R,TA':;

SECTION_NUMBER 1
 '@S9S_MB_2U_LIB.S9S_MB_2U(SCH_1):PAGE586_I34@PURE_QUANTA.Q_CAP(CHIPS)':
 C_PATH='@s9s_mb_2u_lib.s9s_mb_2u(sch_1):page586_i34@pure_quanta.q_cap(chips)';

PART_NAME
 U6 '74LVC07APW_SMTLF-74LVC07APW,74A':;

SECTION_NUMBER 1
 '@S9S_MB_2U_LIB.S9S_MB_2U(SCH_1):PAGE487_I55@PURE_QUANTA.74LVC07APW(CHIPS)':
 C_PATH='@s9s_mb_2u_lib.s9s_mb_2u(sch_1):page487_i55@pure_quanta.\74lvc07apw\(chip~
s)';

SECTION_NUMBER 2
 '@S9S_MB_2U_LIB.S9S_MB_2U(SCH_1):PAGE487_I31@PURE_QUANTA.74LVC07APW(CHIPS)':
 C_PATH='@s9s_mb_2u_lib.s9s_mb_2u(sch_1):page487_i31@pure_quanta.\74lvc07apw\(chip~
s)';

SECTION_NUMBER 3
 '@S9S_MB_2U_LIB.S9S_MB_2U(SCH_1):PAGE487_I32@PURE_QUANTA.74LVC07APW(CHIPS)':
 C_PATH='@s9s_mb_2u_lib.s9s_mb_2u(sch_1):page487_i32@pure_quanta.\74lvc07apw\(chip~
s)';

SECTION_NUMBER 4
 '@S9S_MB_2U_LIB.S9S_MB_2U(SCH_1):PAGE487_I33@PURE_QUANTA.74LVC07APW(CHIPS)':
 C_PATH='@s9s_mb_2u_lib.s9s_mb_2u(sch_1):page487_i33@pure_quanta.\74lvc07apw\(chip~
s)';

SECTION_NUMBER 5
 '@S9S_MB_2U_LIB.S9S_MB_2U(SCH_1):PAGE487_I19@PURE_QUANTA.74LVC07APW(CHIPS)':
 C_PATH='@s9s_mb_2u_lib.s9s_mb_2u(sch_1):page487_i19@pure_quanta.\74lvc07apw\(chip~
s)';

SECTION_NUMBER 6
 '@S9S_MB_2U_LIB.S9S_MB_2U(SCH_1):PAGE487_I20@PURE_QUANTA.74LVC07APW(CHIPS)':
 C_PATH='@s9s_mb_2u_lib.s9s_mb_2u(sch_1):page487_i20@pure_quanta.\74lvc07apw\(chip~
s)';

PART_NAME
 R158 'Q_RES_0402LF-33,5%,1/16W,CHIP,A':;

SECTION_NUMBER 1
 '@S9S_MB_2U_LIB.S9S_MB_2U(SCH_1):PAGE487_I23@PURE_QUANTA.Q_RES(CHIPS)':
 C_PATH='@s9s_mb_2u_lib.s9s_mb_2u(sch_1):page487_i23@pure_quanta.q_res(chips)';

PART_NAME
 R157 'Q_RES_0402LF-100,1%,1/16W,EMPTA':;

SECTION_NUMBER 1
 '@S9S_MB_2U_LIB.S9S_MB_2U(SCH_1):PAGE487_I24@PURE_QUANTA.Q_RES(CHIPS)':
 C_PATH='@s9s_mb_2u_lib.s9s_mb_2u(sch_1):page487_i24@pure_quanta.q_res(chips)';

PART_NAME
 R156 'Q_RES_0402LF-33,5%,1/16W,CHIP,A':;

SECTION_NUMBER 1
 '@S9S_MB_2U_LIB.S9S_MB_2U(SCH_1):PAGE487_I25@PURE_QUANTA.Q_RES(CHIPS)':
 C_PATH='@s9s_mb_2u_lib.s9s_mb_2u(sch_1):page487_i25@pure_quanta.q_res(chips)';

PART_NAME
 R155 'Q_RES_0402LF-100,1%,1/16W,EMPTA':;

SECTION_NUMBER 1
 '@S9S_MB_2U_LIB.S9S_MB_2U(SCH_1):PAGE487_I26@PURE_QUANTA.Q_RES(CHIPS)':
 C_PATH='@s9s_mb_2u_lib.s9s_mb_2u(sch_1):page487_i26@pure_quanta.q_res(chips)';

PART_NAME
 R154 'Q_RES_0402LF-100,1%,1/16W,EMPTA':;

SECTION_NUMBER 1
 '@S9S_MB_2U_LIB.S9S_MB_2U(SCH_1):PAGE487_I35@PURE_QUANTA.Q_RES(CHIPS)':
 C_PATH='@s9s_mb_2u_lib.s9s_mb_2u(sch_1):page487_i35@pure_quanta.q_res(chips)';

PART_NAME
 R153 'Q_RES_0402LF-100,1%,1/16W,CHIPA':;

SECTION_NUMBER 1
 '@S9S_MB_2U_LIB.S9S_MB_2U(SCH_1):PAGE487_I36@PURE_QUANTA.Q_RES(CHIPS)':
 C_PATH='@s9s_mb_2u_lib.s9s_mb_2u(sch_1):page487_i36@pure_quanta.q_res(chips)';

PART_NAME
 R152 'Q_RES_0402LF-100,1%,1/16W,EMPTA':;

SECTION_NUMBER 1
 '@S9S_MB_2U_LIB.S9S_MB_2U(SCH_1):PAGE487_I38@PURE_QUANTA.Q_RES(CHIPS)':
 C_PATH='@s9s_mb_2u_lib.s9s_mb_2u(sch_1):page487_i38@pure_quanta.q_res(chips)';

PART_NAME
 R151 'Q_RES_0402LF-100,1%,1/16W,CHIPA':;

SECTION_NUMBER 1
 '@S9S_MB_2U_LIB.S9S_MB_2U(SCH_1):PAGE487_I37@PURE_QUANTA.Q_RES(CHIPS)':
 C_PATH='@s9s_mb_2u_lib.s9s_mb_2u(sch_1):page487_i37@pure_quanta.q_res(chips)';

PART_NAME
 R150 'Q_RES_0402LF-100,1%,1/16W,EMPTA':;

SECTION_NUMBER 1
 '@S9S_MB_2U_LIB.S9S_MB_2U(SCH_1):PAGE487_I39@PURE_QUANTA.Q_RES(CHIPS)':
 C_PATH='@s9s_mb_2u_lib.s9s_mb_2u(sch_1):page487_i39@pure_quanta.q_res(chips)';

PART_NAME
 R137 'Q_RES_0402LF-100,1%,1/16W,CHIPA':;

SECTION_NUMBER 1
 '@S9S_MB_2U_LIB.S9S_MB_2U(SCH_1):PAGE487_I42@PURE_QUANTA.Q_RES(CHIPS)':
 C_PATH='@s9s_mb_2u_lib.s9s_mb_2u(sch_1):page487_i42@pure_quanta.q_res(chips)';

PART_NAME
 R136 'Q_RES_0402LF-100,1%,1/16W,EMPTA':;

SECTION_NUMBER 1
 '@S9S_MB_2U_LIB.S9S_MB_2U(SCH_1):PAGE487_I43@PURE_QUANTA.Q_RES(CHIPS)':
 C_PATH='@s9s_mb_2u_lib.s9s_mb_2u(sch_1):page487_i43@pure_quanta.q_res(chips)';

PART_NAME
 R135 'Q_RES_0402LF-100,1%,1/16W,CHIPA':;

SECTION_NUMBER 1
 '@S9S_MB_2U_LIB.S9S_MB_2U(SCH_1):PAGE487_I44@PURE_QUANTA.Q_RES(CHIPS)':
 C_PATH='@s9s_mb_2u_lib.s9s_mb_2u(sch_1):page487_i44@pure_quanta.q_res(chips)';

PART_NAME
 R134 'Q_RES_0402LF-0,5%,1/16W,EMPTY,A':;

SECTION_NUMBER 1
 '@S9S_MB_2U_LIB.S9S_MB_2U(SCH_1):PAGE487_I21@PURE_QUANTA.Q_RES(CHIPS)':
 C_PATH='@s9s_mb_2u_lib.s9s_mb_2u(sch_1):page487_i21@pure_quanta.q_res(chips)';

PART_NAME
 R133 'Q_RES_0402LF-0,5%,1/16W,EMPTY,A':;

SECTION_NUMBER 1
 '@S9S_MB_2U_LIB.S9S_MB_2U(SCH_1):PAGE487_I22@PURE_QUANTA.Q_RES(CHIPS)':
 C_PATH='@s9s_mb_2u_lib.s9s_mb_2u(sch_1):page487_i22@pure_quanta.q_res(chips)';

PART_NAME
 R132 'Q_RES_0402LF-0,5%,1/16W,CHIP,CA':;

SECTION_NUMBER 1
 '@S9S_MB_2U_LIB.S9S_MB_2U(SCH_1):PAGE487_I3@PURE_QUANTA.Q_RES(CHIPS)':
 C_PATH='@s9s_mb_2u_lib.s9s_mb_2u(sch_1):page487_i3@pure_quanta.q_res(chips)';

PART_NAME
 R131 'Q_RES_0402LF-0,5%,1/16W,EMPTY,A':;

SECTION_NUMBER 1
 '@S9S_MB_2U_LIB.S9S_MB_2U(SCH_1):PAGE487_I4@PURE_QUANTA.Q_RES(CHIPS)':
 C_PATH='@s9s_mb_2u_lib.s9s_mb_2u(sch_1):page487_i4@pure_quanta.q_res(chips)';

PART_NAME
 R130 'Q_RES_0402LF-0,5%,1/16W,CHIP,CA':;

SECTION_NUMBER 1
 '@S9S_MB_2U_LIB.S9S_MB_2U(SCH_1):PAGE487_I5@PURE_QUANTA.Q_RES(CHIPS)':
 C_PATH='@s9s_mb_2u_lib.s9s_mb_2u(sch_1):page487_i5@pure_quanta.q_res(chips)';

PART_NAME
 R129 'Q_RES_0402LF-0,5%,1/16W,EMPTY,A':;

SECTION_NUMBER 1
 '@S9S_MB_2U_LIB.S9S_MB_2U(SCH_1):PAGE487_I6@PURE_QUANTA.Q_RES(CHIPS)':
 C_PATH='@s9s_mb_2u_lib.s9s_mb_2u(sch_1):page487_i6@pure_quanta.q_res(chips)';

PART_NAME
 R128 'Q_RES_0402LF-0,5%,1/16W,CHIP,CA':;

SECTION_NUMBER 1
 '@S9S_MB_2U_LIB.S9S_MB_2U(SCH_1):PAGE487_I7@PURE_QUANTA.Q_RES(CHIPS)':
 C_PATH='@s9s_mb_2u_lib.s9s_mb_2u(sch_1):page487_i7@pure_quanta.q_res(chips)';

PART_NAME
 R127 'Q_RES_0402LF-33,5%,1/16W,EMPTYA':;

SECTION_NUMBER 1
 '@S9S_MB_2U_LIB.S9S_MB_2U(SCH_1):PAGE487_I12@PURE_QUANTA.Q_RES(CHIPS)':
 C_PATH='@s9s_mb_2u_lib.s9s_mb_2u(sch_1):page487_i12@pure_quanta.q_res(chips)';

PART_NAME
 R126 'Q_RES_0402LF-0,5%,1/16W,CHIP,CA':;

SECTION_NUMBER 1
 '@S9S_MB_2U_LIB.S9S_MB_2U(SCH_1):PAGE487_I13@PURE_QUANTA.Q_RES(CHIPS)':
 C_PATH='@s9s_mb_2u_lib.s9s_mb_2u(sch_1):page487_i13@pure_quanta.q_res(chips)';

PART_NAME
 R125 'Q_RES_0402LF-33,5%,1/16W,EMPTYA':;

SECTION_NUMBER 1
 '@S9S_MB_2U_LIB.S9S_MB_2U(SCH_1):PAGE487_I14@PURE_QUANTA.Q_RES(CHIPS)':
 C_PATH='@s9s_mb_2u_lib.s9s_mb_2u(sch_1):page487_i14@pure_quanta.q_res(chips)';

PART_NAME
 R124 'Q_RES_0402LF-0,5%,1/16W,CHIP,CA':;

SECTION_NUMBER 1
 '@S9S_MB_2U_LIB.S9S_MB_2U(SCH_1):PAGE487_I15@PURE_QUANTA.Q_RES(CHIPS)':
 C_PATH='@s9s_mb_2u_lib.s9s_mb_2u(sch_1):page487_i15@pure_quanta.q_res(chips)';

PART_NAME
 R123 'Q_RES_0402LF-33,5%,1/16W,EMPTYA':;

SECTION_NUMBER 1
 '@S9S_MB_2U_LIB.S9S_MB_2U(SCH_1):PAGE487_I16@PURE_QUANTA.Q_RES(CHIPS)':
 C_PATH='@s9s_mb_2u_lib.s9s_mb_2u(sch_1):page487_i16@pure_quanta.q_res(chips)';

PART_NAME
 R122 'Q_RES_0402LF-0,5%,1/16W,CHIP,CA':;

SECTION_NUMBER 1
 '@S9S_MB_2U_LIB.S9S_MB_2U(SCH_1):PAGE487_I17@PURE_QUANTA.Q_RES(CHIPS)':
 C_PATH='@s9s_mb_2u_lib.s9s_mb_2u(sch_1):page487_i17@pure_quanta.q_res(chips)';

PART_NAME
 R121 'Q_RES_0402LF-33,5%,1/16W,EMPTYA':;

SECTION_NUMBER 1
 '@S9S_MB_2U_LIB.S9S_MB_2U(SCH_1):PAGE487_I18@PURE_QUANTA.Q_RES(CHIPS)':
 C_PATH='@s9s_mb_2u_lib.s9s_mb_2u(sch_1):page487_i18@pure_quanta.q_res(chips)';

PART_NAME
 C1295 'Q_CAP_0402-0.1UF,25V,10%,X7R,CA':;

SECTION_NUMBER 1
 '@S9S_MB_2U_LIB.S9S_MB_2U(SCH_1):PAGE487_I54@PURE_QUANTA.Q_CAP(CHIPS)':
 C_PATH='@s9s_mb_2u_lib.s9s_mb_2u(sch_1):page487_i54@pure_quanta.q_cap(chips)';

PART_NAME
 U5 '74LVC07APW_SMTLF-74LVC07APW,74A':;

SECTION_NUMBER 1
 '@S9S_MB_2U_LIB.S9S_MB_2U(SCH_1):PAGE486_I67@PURE_QUANTA.74LVC07APW(CHIPS)':
 C_PATH='@s9s_mb_2u_lib.s9s_mb_2u(sch_1):page486_i67@pure_quanta.\74lvc07apw\(chip~
s)';

SECTION_NUMBER 2
 '@S9S_MB_2U_LIB.S9S_MB_2U(SCH_1):PAGE486_I2@PURE_QUANTA.74LVC07APW(CHIPS)':
 C_PATH='@s9s_mb_2u_lib.s9s_mb_2u(sch_1):page486_i2@pure_quanta.\74lvc07apw\(chips~
)';

SECTION_NUMBER 3
 '@S9S_MB_2U_LIB.S9S_MB_2U(SCH_1):PAGE486_I3@PURE_QUANTA.74LVC07APW(CHIPS)':
 C_PATH='@s9s_mb_2u_lib.s9s_mb_2u(sch_1):page486_i3@pure_quanta.\74lvc07apw\(chips~
)';

SECTION_NUMBER 4
 '@S9S_MB_2U_LIB.S9S_MB_2U(SCH_1):PAGE486_I4@PURE_QUANTA.74LVC07APW(CHIPS)':
 C_PATH='@s9s_mb_2u_lib.s9s_mb_2u(sch_1):page486_i4@pure_quanta.\74lvc07apw\(chips~
)';

SECTION_NUMBER 5
 '@S9S_MB_2U_LIB.S9S_MB_2U(SCH_1):PAGE486_I5@PURE_QUANTA.74LVC07APW(CHIPS)':
 C_PATH='@s9s_mb_2u_lib.s9s_mb_2u(sch_1):page486_i5@pure_quanta.\74lvc07apw\(chips~
)';

SECTION_NUMBER 6
 '@S9S_MB_2U_LIB.S9S_MB_2U(SCH_1):PAGE486_I6@PURE_QUANTA.74LVC07APW(CHIPS)':
 C_PATH='@s9s_mb_2u_lib.s9s_mb_2u(sch_1):page486_i6@pure_quanta.\74lvc07apw\(chips~
)';

PART_NAME
 R186 'Q_RES_0402LF-33,5%,1/16W,CHIP,A':;

SECTION_NUMBER 1
 '@S9S_MB_2U_LIB.S9S_MB_2U(SCH_1):PAGE486_I61@PURE_QUANTA.Q_RES(CHIPS)':
 C_PATH='@s9s_mb_2u_lib.s9s_mb_2u(sch_1):page486_i61@pure_quanta.q_res(chips)';

PART_NAME
 R185 'Q_RES_0402LF-100,1%,1/16W,EMPTA':;

SECTION_NUMBER 1
 '@S9S_MB_2U_LIB.S9S_MB_2U(SCH_1):PAGE486_I60@PURE_QUANTA.Q_RES(CHIPS)':
 C_PATH='@s9s_mb_2u_lib.s9s_mb_2u(sch_1):page486_i60@pure_quanta.q_res(chips)';

PART_NAME
 R184 'Q_RES_0402LF-33,5%,1/16W,CHIP,A':;

SECTION_NUMBER 1
 '@S9S_MB_2U_LIB.S9S_MB_2U(SCH_1):PAGE486_I56@PURE_QUANTA.Q_RES(CHIPS)':
 C_PATH='@s9s_mb_2u_lib.s9s_mb_2u(sch_1):page486_i56@pure_quanta.q_res(chips)';

PART_NAME
 R183 'Q_RES_0402LF-100,1%,1/16W,EMPTA':;

SECTION_NUMBER 1
 '@S9S_MB_2U_LIB.S9S_MB_2U(SCH_1):PAGE486_I62@PURE_QUANTA.Q_RES(CHIPS)':
 C_PATH='@s9s_mb_2u_lib.s9s_mb_2u(sch_1):page486_i62@pure_quanta.q_res(chips)';

PART_NAME
 R182 'Q_RES_0402LF-100,1%,1/16W,EMPTA':;

SECTION_NUMBER 1
 '@S9S_MB_2U_LIB.S9S_MB_2U(SCH_1):PAGE486_I37@PURE_QUANTA.Q_RES(CHIPS)':
 C_PATH='@s9s_mb_2u_lib.s9s_mb_2u(sch_1):page486_i37@pure_quanta.q_res(chips)';

PART_NAME
 R181 'Q_RES_0402LF-100,1%,1/16W,CHIPA':;

SECTION_NUMBER 1
 '@S9S_MB_2U_LIB.S9S_MB_2U(SCH_1):PAGE486_I38@PURE_QUANTA.Q_RES(CHIPS)':
 C_PATH='@s9s_mb_2u_lib.s9s_mb_2u(sch_1):page486_i38@pure_quanta.q_res(chips)';

PART_NAME
 R180 'Q_RES_0402LF-100,1%,1/16W,EMPTA':;

SECTION_NUMBER 1
 '@S9S_MB_2U_LIB.S9S_MB_2U(SCH_1):PAGE486_I31@PURE_QUANTA.Q_RES(CHIPS)':
 C_PATH='@s9s_mb_2u_lib.s9s_mb_2u(sch_1):page486_i31@pure_quanta.q_res(chips)';

PART_NAME
 R179 'Q_RES_0402LF-100,1%,1/16W,CHIPA':;

SECTION_NUMBER 1
 '@S9S_MB_2U_LIB.S9S_MB_2U(SCH_1):PAGE486_I30@PURE_QUANTA.Q_RES(CHIPS)':
 C_PATH='@s9s_mb_2u_lib.s9s_mb_2u(sch_1):page486_i30@pure_quanta.q_res(chips)';

PART_NAME
 R178 'Q_RES_0402LF-100,1%,1/16W,EMPTA':;

SECTION_NUMBER 1
 '@S9S_MB_2U_LIB.S9S_MB_2U(SCH_1):PAGE486_I24@PURE_QUANTA.Q_RES(CHIPS)':
 C_PATH='@s9s_mb_2u_lib.s9s_mb_2u(sch_1):page486_i24@pure_quanta.q_res(chips)';

PART_NAME
 R177 'Q_RES_0402LF-100,1%,1/16W,CHIPA':;

SECTION_NUMBER 1
 '@S9S_MB_2U_LIB.S9S_MB_2U(SCH_1):PAGE486_I23@PURE_QUANTA.Q_RES(CHIPS)':
 C_PATH='@s9s_mb_2u_lib.s9s_mb_2u(sch_1):page486_i23@pure_quanta.q_res(chips)';

PART_NAME
 R176 'Q_RES_0402LF-100,1%,1/16W,EMPTA':;

SECTION_NUMBER 1
 '@S9S_MB_2U_LIB.S9S_MB_2U(SCH_1):PAGE486_I12@PURE_QUANTA.Q_RES(CHIPS)':
 C_PATH='@s9s_mb_2u_lib.s9s_mb_2u(sch_1):page486_i12@pure_quanta.q_res(chips)';

PART_NAME
 R175 'Q_RES_0402LF-100,1%,1/16W,CHIPA':;

SECTION_NUMBER 1
 '@S9S_MB_2U_LIB.S9S_MB_2U(SCH_1):PAGE486_I16@PURE_QUANTA.Q_RES(CHIPS)':
 C_PATH='@s9s_mb_2u_lib.s9s_mb_2u(sch_1):page486_i16@pure_quanta.q_res(chips)';

PART_NAME
 R174 'Q_RES_0402LF-0,5%,1/16W,EMPTY,A':;

SECTION_NUMBER 1
 '@S9S_MB_2U_LIB.S9S_MB_2U(SCH_1):PAGE486_I55@PURE_QUANTA.Q_RES(CHIPS)':
 C_PATH='@s9s_mb_2u_lib.s9s_mb_2u(sch_1):page486_i55@pure_quanta.q_res(chips)';

PART_NAME
 R173 'Q_RES_0402LF-0,5%,1/16W,EMPTY,A':;

SECTION_NUMBER 1
 '@S9S_MB_2U_LIB.S9S_MB_2U(SCH_1):PAGE486_I49@PURE_QUANTA.Q_RES(CHIPS)':
 C_PATH='@s9s_mb_2u_lib.s9s_mb_2u(sch_1):page486_i49@pure_quanta.q_res(chips)';

PART_NAME
 R171 'Q_RES_0402LF-0,5%,1/16W,CHIP,CA':;

SECTION_NUMBER 1
 '@S9S_MB_2U_LIB.S9S_MB_2U(SCH_1):PAGE486_I52@PURE_QUANTA.Q_RES(CHIPS)':
 C_PATH='@s9s_mb_2u_lib.s9s_mb_2u(sch_1):page486_i52@pure_quanta.q_res(chips)';

PART_NAME
 R170 'Q_RES_0402LF-0,5%,1/16W,EMPTY,A':;

SECTION_NUMBER 1
 '@S9S_MB_2U_LIB.S9S_MB_2U(SCH_1):PAGE486_I53@PURE_QUANTA.Q_RES(CHIPS)':
 C_PATH='@s9s_mb_2u_lib.s9s_mb_2u(sch_1):page486_i53@pure_quanta.q_res(chips)';

PART_NAME
 R168 'Q_RES_0402LF-0,5%,1/16W,CHIP,CA':;

SECTION_NUMBER 1
 '@S9S_MB_2U_LIB.S9S_MB_2U(SCH_1):PAGE486_I43@PURE_QUANTA.Q_RES(CHIPS)':
 C_PATH='@s9s_mb_2u_lib.s9s_mb_2u(sch_1):page486_i43@pure_quanta.q_res(chips)';

PART_NAME
 R167 'Q_RES_0402LF-0,5%,1/16W,EMPTY,A':;

SECTION_NUMBER 1
 '@S9S_MB_2U_LIB.S9S_MB_2U(SCH_1):PAGE486_I42@PURE_QUANTA.Q_RES(CHIPS)':
 C_PATH='@s9s_mb_2u_lib.s9s_mb_2u(sch_1):page486_i42@pure_quanta.q_res(chips)';

PART_NAME
 R166 'Q_RES_0402LF-0,5%,1/16W,CHIP,CA':;

SECTION_NUMBER 1
 '@S9S_MB_2U_LIB.S9S_MB_2U(SCH_1):PAGE486_I33@PURE_QUANTA.Q_RES(CHIPS)':
 C_PATH='@s9s_mb_2u_lib.s9s_mb_2u(sch_1):page486_i33@pure_quanta.q_res(chips)';

PART_NAME
 R165 'Q_RES_0402LF-33,5%,1/16W,EMPTYA':;

SECTION_NUMBER 1
 '@S9S_MB_2U_LIB.S9S_MB_2U(SCH_1):PAGE486_I32@PURE_QUANTA.Q_RES(CHIPS)':
 C_PATH='@s9s_mb_2u_lib.s9s_mb_2u(sch_1):page486_i32@pure_quanta.q_res(chips)';

PART_NAME
 R164 'Q_RES_0402LF-0,5%,1/16W,CHIP,CA':;

SECTION_NUMBER 1
 '@S9S_MB_2U_LIB.S9S_MB_2U(SCH_1):PAGE486_I26@PURE_QUANTA.Q_RES(CHIPS)':
 C_PATH='@s9s_mb_2u_lib.s9s_mb_2u(sch_1):page486_i26@pure_quanta.q_res(chips)';

PART_NAME
 R163 'Q_RES_0402LF-33,5%,1/16W,EMPTYA':;

SECTION_NUMBER 1
 '@S9S_MB_2U_LIB.S9S_MB_2U(SCH_1):PAGE486_I25@PURE_QUANTA.Q_RES(CHIPS)':
 C_PATH='@s9s_mb_2u_lib.s9s_mb_2u(sch_1):page486_i25@pure_quanta.q_res(chips)';

PART_NAME
 R162 'Q_RES_0402LF-0,5%,1/16W,CHIP,CA':;

SECTION_NUMBER 1
 '@S9S_MB_2U_LIB.S9S_MB_2U(SCH_1):PAGE486_I19@PURE_QUANTA.Q_RES(CHIPS)':
 C_PATH='@s9s_mb_2u_lib.s9s_mb_2u(sch_1):page486_i19@pure_quanta.q_res(chips)';

PART_NAME
 R161 'Q_RES_0402LF-33,5%,1/16W,EMPTYA':;

SECTION_NUMBER 1
 '@S9S_MB_2U_LIB.S9S_MB_2U(SCH_1):PAGE486_I18@PURE_QUANTA.Q_RES(CHIPS)':
 C_PATH='@s9s_mb_2u_lib.s9s_mb_2u(sch_1):page486_i18@pure_quanta.q_res(chips)';

PART_NAME
 R160 'Q_RES_0402LF-0,5%,1/16W,CHIP,CA':;

SECTION_NUMBER 1
 '@S9S_MB_2U_LIB.S9S_MB_2U(SCH_1):PAGE486_I17@PURE_QUANTA.Q_RES(CHIPS)':
 C_PATH='@s9s_mb_2u_lib.s9s_mb_2u(sch_1):page486_i17@pure_quanta.q_res(chips)';

PART_NAME
 R159 'Q_RES_0402LF-33,5%,1/16W,EMPTYA':;

SECTION_NUMBER 1
 '@S9S_MB_2U_LIB.S9S_MB_2U(SCH_1):PAGE486_I10@PURE_QUANTA.Q_RES(CHIPS)':
 C_PATH='@s9s_mb_2u_lib.s9s_mb_2u(sch_1):page486_i10@pure_quanta.q_res(chips)';

PART_NAME
 C1294 'Q_CAP_0402-0.1UF,25V,10%,X7R,CA':;

SECTION_NUMBER 1
 '@S9S_MB_2U_LIB.S9S_MB_2U(SCH_1):PAGE486_I65@PURE_QUANTA.Q_CAP(CHIPS)':
 C_PATH='@s9s_mb_2u_lib.s9s_mb_2u(sch_1):page486_i65@pure_quanta.q_cap(chips)';

PART_NAME
 U97 'TS3A24157RSER-TS3A24157RSER,SMA':;

SECTION_NUMBER 1
 '@S9S_MB_2U_LIB.S9S_MB_2U(SCH_1):PAGE561_I38@PURE_QUANTA.TS3A24157RSER(CHIPS)':
 C_PATH='@s9s_mb_2u_lib.s9s_mb_2u(sch_1):page561_i38@pure_quanta.ts3a24157rser(chi~
ps)';

PART_NAME
 U96 'TS3A24157RSER-TS3A24157RSER,SMA':;

SECTION_NUMBER 1
 '@S9S_MB_2U_LIB.S9S_MB_2U(SCH_1):PAGE561_I68@PURE_QUANTA.TS3A24157RSER(CHIPS)':
 C_PATH='@s9s_mb_2u_lib.s9s_mb_2u(sch_1):page561_i68@pure_quanta.ts3a24157rser(chi~
ps)';

PART_NAME
 U84 'GTL2014PW-GTL2014PW,SMLF,IC,ALA':;

SECTION_NUMBER 1
 '@S9S_MB_2U_LIB.S9S_MB_2U(SCH_1):PAGE561_I18@PURE_QUANTA.GTL2014PW(CHIPS)':
 C_PATH='@s9s_mb_2u_lib.s9s_mb_2u(sch_1):page561_i18@pure_quanta.gtl2014pw(chips)';

PART_NAME
 U83 'GTL2014PW-GTL2014PW,SMLF,IC,ALA':;

SECTION_NUMBER 1
 '@S9S_MB_2U_LIB.S9S_MB_2U(SCH_1):PAGE561_I45@PURE_QUANTA.GTL2014PW(CHIPS)':
 C_PATH='@s9s_mb_2u_lib.s9s_mb_2u(sch_1):page561_i45@pure_quanta.gtl2014pw(chips)';

PART_NAME
 R1832 'Q_RES_0402LF-0,5%,1/16W,EMPTY,A':;

SECTION_NUMBER 1
 '@S9S_MB_2U_LIB.S9S_MB_2U(SCH_1):PAGE561_I80@PURE_QUANTA.Q_RES(CHIPS)':
 C_PATH='@s9s_mb_2u_lib.s9s_mb_2u(sch_1):page561_i80@pure_quanta.q_res(chips)';

PART_NAME
 R1831 'Q_RES_0402LF-0,5%,1/16W,EMPTY,A':;

SECTION_NUMBER 1
 '@S9S_MB_2U_LIB.S9S_MB_2U(SCH_1):PAGE561_I82@PURE_QUANTA.Q_RES(CHIPS)':
 C_PATH='@s9s_mb_2u_lib.s9s_mb_2u(sch_1):page561_i82@pure_quanta.q_res(chips)';

PART_NAME
 R1814 'Q_RES_0402LF-1K,1%,1/16W,CHIP,A':;

SECTION_NUMBER 1
 '@S9S_MB_2U_LIB.S9S_MB_2U(SCH_1):PAGE561_I77@PURE_QUANTA.Q_RES(CHIPS)':
 C_PATH='@s9s_mb_2u_lib.s9s_mb_2u(sch_1):page561_i77@pure_quanta.q_res(chips)';

PART_NAME
 R1813 'Q_RES_0402LF-10K,1%,1/16W,EMPTA':;

SECTION_NUMBER 1
 '@S9S_MB_2U_LIB.S9S_MB_2U(SCH_1):PAGE561_I79@PURE_QUANTA.Q_RES(CHIPS)':
 C_PATH='@s9s_mb_2u_lib.s9s_mb_2u(sch_1):page561_i79@pure_quanta.q_res(chips)';

PART_NAME
 R1383 'Q_RES_0402LF-1K,1%,1/16W,CHIP,A':;

SECTION_NUMBER 1
 '@S9S_MB_2U_LIB.S9S_MB_2U(SCH_1):PAGE561_I1@PURE_QUANTA.Q_RES(CHIPS)':
 C_PATH='@s9s_mb_2u_lib.s9s_mb_2u(sch_1):page561_i1@pure_quanta.q_res(chips)';

PART_NAME
 R1382 'Q_RES_0402LF-1K,1%,1/16W,CHIP,A':;

SECTION_NUMBER 1
 '@S9S_MB_2U_LIB.S9S_MB_2U(SCH_1):PAGE561_I20@PURE_QUANTA.Q_RES(CHIPS)':
 C_PATH='@s9s_mb_2u_lib.s9s_mb_2u(sch_1):page561_i20@pure_quanta.q_res(chips)';

PART_NAME
 R1381 'Q_RES_0402LF-1K,1%,1/16W,CHIP,A':;

SECTION_NUMBER 1
 '@S9S_MB_2U_LIB.S9S_MB_2U(SCH_1):PAGE561_I7@PURE_QUANTA.Q_RES(CHIPS)':
 C_PATH='@s9s_mb_2u_lib.s9s_mb_2u(sch_1):page561_i7@pure_quanta.q_res(chips)';

PART_NAME
 R1380 'Q_RES_0402LF-1K,1%,1/16W,CHIP,A':;

SECTION_NUMBER 1
 '@S9S_MB_2U_LIB.S9S_MB_2U(SCH_1):PAGE561_I31@PURE_QUANTA.Q_RES(CHIPS)':
 C_PATH='@s9s_mb_2u_lib.s9s_mb_2u(sch_1):page561_i31@pure_quanta.q_res(chips)';

PART_NAME
 R1379 'Q_RES_0402LF-33.2,1%,1/16W,CHIA':;

SECTION_NUMBER 1
 '@S9S_MB_2U_LIB.S9S_MB_2U(SCH_1):PAGE561_I12@PURE_QUANTA.Q_RES(CHIPS)':
 C_PATH='@s9s_mb_2u_lib.s9s_mb_2u(sch_1):page561_i12@pure_quanta.q_res(chips)';

PART_NAME
 R1378 'Q_RES_0402LF-33.2,1%,1/16W,CHIA':;

SECTION_NUMBER 1
 '@S9S_MB_2U_LIB.S9S_MB_2U(SCH_1):PAGE561_I36@PURE_QUANTA.Q_RES(CHIPS)':
 C_PATH='@s9s_mb_2u_lib.s9s_mb_2u(sch_1):page561_i36@pure_quanta.q_res(chips)';

PART_NAME
 R1377 'Q_RES_0402LF-1K,1%,1/16W,CHIP,A':;

SECTION_NUMBER 1
 '@S9S_MB_2U_LIB.S9S_MB_2U(SCH_1):PAGE561_I11@PURE_QUANTA.Q_RES(CHIPS)':
 C_PATH='@s9s_mb_2u_lib.s9s_mb_2u(sch_1):page561_i11@pure_quanta.q_res(chips)';

PART_NAME
 R1376 'Q_RES_0402LF-1K,1%,1/16W,CHIP,A':;

SECTION_NUMBER 1
 '@S9S_MB_2U_LIB.S9S_MB_2U(SCH_1):PAGE561_I35@PURE_QUANTA.Q_RES(CHIPS)':
 C_PATH='@s9s_mb_2u_lib.s9s_mb_2u(sch_1):page561_i35@pure_quanta.q_res(chips)';

PART_NAME
 R1369 'Q_RES_0402LF-1K,1%,1/16W,CHIP,A':;

SECTION_NUMBER 1
 '@S9S_MB_2U_LIB.S9S_MB_2U(SCH_1):PAGE561_I47@PURE_QUANTA.Q_RES(CHIPS)':
 C_PATH='@s9s_mb_2u_lib.s9s_mb_2u(sch_1):page561_i47@pure_quanta.q_res(chips)';

PART_NAME
 R1368 'Q_RES_0402LF-1K,1%,1/16W,CHIP,A':;

SECTION_NUMBER 1
 '@S9S_MB_2U_LIB.S9S_MB_2U(SCH_1):PAGE561_I48@PURE_QUANTA.Q_RES(CHIPS)':
 C_PATH='@s9s_mb_2u_lib.s9s_mb_2u(sch_1):page561_i48@pure_quanta.q_res(chips)';

PART_NAME
 R1367 'Q_RES_0402LF-100,1%,1/16W,CHIPB':;

SECTION_NUMBER 1
 '@S9S_MB_2U_LIB.S9S_MB_2U(SCH_1):PAGE561_I65@PURE_QUANTA.Q_RES(CHIPS)':
 C_PATH='@s9s_mb_2u_lib.s9s_mb_2u(sch_1):page561_i65@pure_quanta.q_res(chips)';

PART_NAME
 R1366 'Q_RES_0402LF-100,1%,1/16W,CHIPB':;

SECTION_NUMBER 1
 '@S9S_MB_2U_LIB.S9S_MB_2U(SCH_1):PAGE561_I64@PURE_QUANTA.Q_RES(CHIPS)':
 C_PATH='@s9s_mb_2u_lib.s9s_mb_2u(sch_1):page561_i64@pure_quanta.q_res(chips)';

PART_NAME
 R1347 'Q_RES_0402LF-1K,1%,1/16W,CHIP,A':;

SECTION_NUMBER 1
 '@S9S_MB_2U_LIB.S9S_MB_2U(SCH_1):PAGE561_I10@PURE_QUANTA.Q_RES(CHIPS)':
 C_PATH='@s9s_mb_2u_lib.s9s_mb_2u(sch_1):page561_i10@pure_quanta.q_res(chips)';

PART_NAME
 R1346 'Q_RES_0402LF-1K,1%,1/16W,CHIP,A':;

SECTION_NUMBER 1
 '@S9S_MB_2U_LIB.S9S_MB_2U(SCH_1):PAGE561_I34@PURE_QUANTA.Q_RES(CHIPS)':
 C_PATH='@s9s_mb_2u_lib.s9s_mb_2u(sch_1):page561_i34@pure_quanta.q_res(chips)';

PART_NAME
 R1345 'Q_RES_0402LF-0,5%,1/16W,CHIP,CA':;

SECTION_NUMBER 1
 '@S9S_MB_2U_LIB.S9S_MB_2U(SCH_1):PAGE561_I13@PURE_QUANTA.Q_RES(CHIPS)':
 C_PATH='@s9s_mb_2u_lib.s9s_mb_2u(sch_1):page561_i13@pure_quanta.q_res(chips)';

PART_NAME
 R1184 'Q_RES_0402LF-0,5%,1/16W,CHIP,CA':;

SECTION_NUMBER 1
 '@S9S_MB_2U_LIB.S9S_MB_2U(SCH_1):PAGE561_I14@PURE_QUANTA.Q_RES(CHIPS)':
 C_PATH='@s9s_mb_2u_lib.s9s_mb_2u(sch_1):page561_i14@pure_quanta.q_res(chips)';

PART_NAME
 R483 'Q_RES_0402LF-0,5%,1/16W,CHIP,CA':;

SECTION_NUMBER 1
 '@S9S_MB_2U_LIB.S9S_MB_2U(SCH_1):PAGE561_I37@PURE_QUANTA.Q_RES(CHIPS)':
 C_PATH='@s9s_mb_2u_lib.s9s_mb_2u(sch_1):page561_i37@pure_quanta.q_res(chips)';

PART_NAME
 R482 'Q_RES_0402LF-0,5%,1/16W,CHIP,CA':;

SECTION_NUMBER 1
 '@S9S_MB_2U_LIB.S9S_MB_2U(SCH_1):PAGE561_I57@PURE_QUANTA.Q_RES(CHIPS)':
 C_PATH='@s9s_mb_2u_lib.s9s_mb_2u(sch_1):page561_i57@pure_quanta.q_res(chips)';

PART_NAME
 R481 'Q_RES_0402LF-0,5%,1/16W,CHIP,CA':;

SECTION_NUMBER 1
 '@S9S_MB_2U_LIB.S9S_MB_2U(SCH_1):PAGE561_I58@PURE_QUANTA.Q_RES(CHIPS)':
 C_PATH='@s9s_mb_2u_lib.s9s_mb_2u(sch_1):page561_i58@pure_quanta.q_res(chips)';

PART_NAME
 R480 'Q_RES_0402LF-0,5%,1/16W,CHIP,CA':;

SECTION_NUMBER 1
 '@S9S_MB_2U_LIB.S9S_MB_2U(SCH_1):PAGE561_I59@PURE_QUANTA.Q_RES(CHIPS)':
 C_PATH='@s9s_mb_2u_lib.s9s_mb_2u(sch_1):page561_i59@pure_quanta.q_res(chips)';

PART_NAME
 C1322 'Q_CAP_0402-0.1UF,25V,10%,X7R,CA':;

SECTION_NUMBER 1
 '@S9S_MB_2U_LIB.S9S_MB_2U(SCH_1):PAGE561_I27@PURE_QUANTA.Q_CAP(CHIPS)':
 C_PATH='@s9s_mb_2u_lib.s9s_mb_2u(sch_1):page561_i27@pure_quanta.q_cap(chips)';

PART_NAME
 C1321 'Q_CAP_0402-0.1UF,25V,10%,X7R,CA':;

SECTION_NUMBER 1
 '@S9S_MB_2U_LIB.S9S_MB_2U(SCH_1):PAGE561_I55@PURE_QUANTA.Q_CAP(CHIPS)':
 C_PATH='@s9s_mb_2u_lib.s9s_mb_2u(sch_1):page561_i55@pure_quanta.q_cap(chips)';

PART_NAME
 C1291 'Q_CAP_C0402-1UF,25V,10%,X6S,CHA':;

SECTION_NUMBER 1
 '@S9S_MB_2U_LIB.S9S_MB_2U(SCH_1):PAGE561_I16@PURE_QUANTA.Q_CAP(CHIPS)':
 C_PATH='@s9s_mb_2u_lib.s9s_mb_2u(sch_1):page561_i16@pure_quanta.q_cap(chips)';

PART_NAME
 C1290 'Q_CAP_C0402-1UF,25V,10%,X6S,CHA':;

SECTION_NUMBER 1
 '@S9S_MB_2U_LIB.S9S_MB_2U(SCH_1):PAGE561_I43@PURE_QUANTA.Q_CAP(CHIPS)':
 C_PATH='@s9s_mb_2u_lib.s9s_mb_2u(sch_1):page561_i43@pure_quanta.q_cap(chips)';

PART_NAME
 U87 'MOSFET_N_SMLF-BSS138K,BSS138K,A':;

SECTION_NUMBER 1
 '@S9S_MB_2U_LIB.S9S_MB_2U(SCH_1):PAGE492_I96@PURE_QUANTA.MOSFET_N(CHIPS)':
 C_PATH='@s9s_mb_2u_lib.s9s_mb_2u(sch_1):page492_i96@pure_quanta.mosfet_n(chips)';

PART_NAME
 U86 '74CBTLV3126PW-74CBTLV3126PW,SMA':;

SECTION_NUMBER 1
 '@S9S_MB_2U_LIB.S9S_MB_2U(SCH_1):PAGE492_I84@PURE_QUANTA.74CBTLV3126PW(CHIPS)':
 C_PATH='@s9s_mb_2u_lib.s9s_mb_2u(sch_1):page492_i84@pure_quanta.\74cbtlv3126pw\(c~
hips)';

PART_NAME
 U85 'NC7SB3157_SMLF-NC7SB3157P6X,NCA':;

SECTION_NUMBER 1
 '@S9S_MB_2U_LIB.S9S_MB_2U(SCH_1):PAGE492_I109@PURE_QUANTA.NC7SB3157(CHIPS)':
 C_PATH='@s9s_mb_a_lib.s9s_mb_a(sch_1):page492_i109@pure_quanta.nc7sb3157(chips)~
';

PART_NAME
 R1375 'Q_RES_0402LF-10K,1%,1/16W,CHIPA':;

SECTION_NUMBER 1
 '@S9S_MB_2U_LIB.S9S_MB_2U(SCH_1):PAGE492_I97@PURE_QUANTA.Q_RES(CHIPS)':
 C_PATH='@s9s_mb_2u_lib.s9s_mb_2u(sch_1):page492_i97@pure_quanta.q_res(chips)';

PART_NAME
 R1374 'Q_RES_0402LF-1K,1%,1/16W,CHIP,A':;

SECTION_NUMBER 1
 '@S9S_MB_2U_LIB.S9S_MB_2U(SCH_1):PAGE492_I103@PURE_QUANTA.Q_RES(CHIPS)':
 C_PATH='@s9s_mb_2u_lib.s9s_mb_2u(sch_1):page492_i103@pure_quanta.q_res(chips)';

PART_NAME
 R1373 'Q_RES_0402LF-1K,1%,1/16W,CHIP,A':;

SECTION_NUMBER 1
 '@S9S_MB_2U_LIB.S9S_MB_2U(SCH_1):PAGE492_I105@PURE_QUANTA.Q_RES(CHIPS)':
 C_PATH='@s9s_mb_2u_lib.s9s_mb_2u(sch_1):page492_i105@pure_quanta.q_res(chips)';

PART_NAME
 R1372 'Q_RES_0402LF-1K,1%,1/16W,CHIP,A':;

SECTION_NUMBER 1
 '@S9S_MB_2U_LIB.S9S_MB_2U(SCH_1):PAGE492_I102@PURE_QUANTA.Q_RES(CHIPS)':
 C_PATH='@s9s_mb_2u_lib.s9s_mb_2u(sch_1):page492_i102@pure_quanta.q_res(chips)';

PART_NAME
 R1371 'Q_RES_0402LF-1K,1%,1/16W,CHIP,A':;

SECTION_NUMBER 1
 '@S9S_MB_2U_LIB.S9S_MB_2U(SCH_1):PAGE492_I106@PURE_QUANTA.Q_RES(CHIPS)':
 C_PATH='@s9s_mb_2u_lib.s9s_mb_2u(sch_1):page492_i106@pure_quanta.q_res(chips)';

PART_NAME
 R1370 'Q_RES_0402LF-100,1%,1/16W,CHIPA':;

SECTION_NUMBER 1
 '@S9S_MB_2U_LIB.S9S_MB_2U(SCH_1):PAGE492_I98@PURE_QUANTA.Q_RES(CHIPS)':
 C_PATH='@s9s_mb_2u_lib.s9s_mb_2u(sch_1):page492_i98@pure_quanta.q_res(chips)';

PART_NAME
 R1365 'Q_RES_0402LF-1K,1%,1/16W,CHIP,A':;

SECTION_NUMBER 1
 '@S9S_MB_2U_LIB.S9S_MB_2U(SCH_1):PAGE492_I116@PURE_QUANTA.Q_RES(CHIPS)':
 C_PATH='@s9s_mb_2u_lib.s9s_mb_2u(sch_1):page492_i116@pure_quanta.q_res(chips)';

PART_NAME
 R1349 'Q_RES_0402LF-0,5%,1/16W,CHIP,CA':;

SECTION_NUMBER 1
 '@S9S_MB_2U_LIB.S9S_MB_2U(SCH_1):PAGE492_I87@PURE_QUANTA.Q_RES(CHIPS)':
 C_PATH='@s9s_mb_2u_lib.s9s_mb_2u(sch_1):page492_i87@pure_quanta.q_res(chips)';

PART_NAME
 R1348 'Q_RES_0402LF-0,5%,1/16W,CHIP,CA':;

SECTION_NUMBER 1
 '@S9S_MB_2U_LIB.S9S_MB_2U(SCH_1):PAGE492_I88@PURE_QUANTA.Q_RES(CHIPS)':
 C_PATH='@s9s_mb_2u_lib.s9s_mb_2u(sch_1):page492_i88@pure_quanta.q_res(chips)';

PART_NAME
 JP6 'CONN3_210HP1030BR1-CONN3_210-HA':;

SECTION_NUMBER 1
 '@S9S_MB_2U_LIB.S9S_MB_2U(SCH_1):PAGE492_I108@PURE_QUANTA.CONN3_210HP1030BR1(CHIPS)':
 C_PATH='@s9s_mb_2u_lib.s9s_mb_2u(sch_1):page492_i108@pure_quanta.conn3_210hp1030b~
r1(chips)';

PART_NAME
 C1293 'Q_CAP_C0402-1UF,25V,10%,X6S,CHA':;

SECTION_NUMBER 1
 '@S9S_MB_2U_LIB.S9S_MB_2U(SCH_1):PAGE492_I95@PURE_QUANTA.Q_CAP(CHIPS)':
 C_PATH='@s9s_mb_2u_lib.s9s_mb_2u(sch_1):page492_i95@pure_quanta.q_cap(chips)';

PART_NAME
 C1292 'Q_CAP_0402-0.1UF,25V,10%,X7R,CA':;

SECTION_NUMBER 1
 '@S9S_MB_2U_LIB.S9S_MB_2U(SCH_1):PAGE492_I90@PURE_QUANTA.Q_CAP(CHIPS)':
 C_PATH='@s9s_mb_2u_lib.s9s_mb_2u(sch_1):page492_i90@pure_quanta.q_cap(chips)';

PART_NAME
 C1289 'Q_CAP_C0402-1UF,25V,10%,X6S,CHA':;

SECTION_NUMBER 1
 '@S9S_MB_2U_LIB.S9S_MB_2U(SCH_1):PAGE492_I110@PURE_QUANTA.Q_CAP(CHIPS)':
 C_PATH='@s9s_mb_2u_lib.s9s_mb_2u(sch_1):page492_i110@pure_quanta.q_cap(chips)';

PART_NAME
 C1288 'Q_CAP_0402-0.1UF,25V,10%,X7R,CA':;

SECTION_NUMBER 1
 '@S9S_MB_2U_LIB.S9S_MB_2U(SCH_1):PAGE492_I112@PURE_QUANTA.Q_CAP(CHIPS)':
 C_PATH='@s9s_mb_2u_lib.s9s_mb_2u(sch_1):page492_i112@pure_quanta.q_cap(chips)';

PART_NAME
 R1649 'Q_RES_0402LF-2K,1%,1/16W,CHIP,A':;

SECTION_NUMBER 1
 '@S9S_MB_2U_LIB.S9S_MB_2U(SCH_1):PAGE578_I52@PURE_QUANTA.Q_RES(CHIPS)':
 C_PATH='@s9s_mb_2u_lib.s9s_mb_2u(sch_1):page578_i52@pure_quanta.q_res(chips)';

PART_NAME
 PU73 'MPQ8633BGLEC838Z-MPQ8633BGLE-CA':;

SECTION_NUMBER 1
 '@S9S_MB_2U_LIB.S9S_MB_2U(SCH_1):PAGE578_I32@PURE_QUANTA.MPQ8633BGLEC838Z(CHIPS)':
 C_PATH='@s9s_mb_2u_lib.s9s_mb_2u(sch_1):page578_i32@pure_quanta.mpq8633bglec838z(~
chips)';

PART_NAME
 PR2390 'Q_RES_0402LF-0,5%,1/16W,CHIP,CA':;

SECTION_NUMBER 1
 '@S9S_MB_2U_LIB.S9S_MB_2U(SCH_1):PAGE578_I4@PURE_QUANTA.Q_RES(CHIPS)':
 C_PATH='@s9s_mb_2u_lib.s9s_mb_2u(sch_1):page578_i4@pure_quanta.q_res(chips)';

PART_NAME
 PR1650 'Q_RES_0402LF-0,5%,1/16W,CHIP,CA':;

SECTION_NUMBER 1
 '@S9S_MB_2U_LIB.S9S_MB_2U(SCH_1):PAGE578_I49@PURE_QUANTA.Q_RES(CHIPS)':
 C_PATH='@s9s_mb_2u_lib.s9s_mb_2u(sch_1):page578_i49@pure_quanta.q_res(chips)';

PART_NAME
 PR1647 'Q_RES_0402LF-10K,1%,1/16W,EMPTA':;

SECTION_NUMBER 1
 '@S9S_MB_2U_LIB.S9S_MB_2U(SCH_1):PAGE578_I50@PURE_QUANTA.Q_RES(CHIPS)':
 C_PATH='@s9s_mb_2u_lib.s9s_mb_2u(sch_1):page578_i50@pure_quanta.q_res(chips)';

PART_NAME
 PR1389 'Q_RES_0402LF-0,5%,1/16W,CHIP,CA':;

SECTION_NUMBER 1
 '@S9S_MB_2U_LIB.S9S_MB_2U(SCH_1):PAGE578_I28@PURE_QUANTA.Q_RES(CHIPS)':
 C_PATH='@s9s_mb_2u_lib.s9s_mb_2u(sch_1):page578_i28@pure_quanta.q_res(chips)';

PART_NAME
 PR1388 'Q_RES_0402LF-0,5%,1/16W,EMPTY,A':;

SECTION_NUMBER 1
 '@S9S_MB_2U_LIB.S9S_MB_2U(SCH_1):PAGE578_I27@PURE_QUANTA.Q_RES(CHIPS)':
 C_PATH='@s9s_mb_2u_lib.s9s_mb_2u(sch_1):page578_i27@pure_quanta.q_res(chips)';

PART_NAME
 PR1328 'Q_RES_0402LF-7.32K,1%,1/16W,CHA':;

SECTION_NUMBER 1
 '@S9S_MB_2U_LIB.S9S_MB_2U(SCH_1):PAGE578_I17@PURE_QUANTA.Q_RES(CHIPS)':
 C_PATH='@s9s_mb_2u_lib.s9s_mb_2u(sch_1):page578_i17@pure_quanta.q_res(chips)';

PART_NAME
 PR1327 'Q_RES_0402LF-7.32K,1%,1/16W,CHB':;

SECTION_NUMBER 1
 '@S9S_MB_2U_LIB.S9S_MB_2U(SCH_1):PAGE578_I33@PURE_QUANTA.Q_RES(CHIPS)':
 C_PATH='@s9s_mb_2u_lib.s9s_mb_2u(sch_1):page578_i33@pure_quanta.q_res(chips)';

PART_NAME
 PR1326 'Q_RES_0402LF-0,5%,1/16W,CHIP,CA':;

SECTION_NUMBER 1
 '@S9S_MB_2U_LIB.S9S_MB_2U(SCH_1):PAGE578_I36@PURE_QUANTA.Q_RES(CHIPS)':
 C_PATH='@s9s_mb_2u_lib.s9s_mb_2u(sch_1):page578_i36@pure_quanta.q_res(chips)';

PART_NAME
 PR187 'Q_RES_0402LF-10K,1%,1/16W,CHIPA':;

SECTION_NUMBER 1
 '@S9S_MB_2U_LIB.S9S_MB_2U(SCH_1):PAGE578_I19@PURE_QUANTA.Q_RES(CHIPS)':
 C_PATH='@s9s_mb_2u_lib.s9s_mb_2u(sch_1):page578_i19@pure_quanta.q_res(chips)';

PART_NAME
 PR186 'Q_RES_0402LF-10K,1%,1/16W,CHIPA':;

SECTION_NUMBER 1
 '@S9S_MB_2U_LIB.S9S_MB_2U(SCH_1):PAGE578_I22@PURE_QUANTA.Q_RES(CHIPS)':
 C_PATH='@s9s_mb_2u_lib.s9s_mb_2u(sch_1):page578_i22@pure_quanta.q_res(chips)';

PART_NAME
 PL150 'Q_INDUCTOR_SMLF-300NH/33A,IND,A':;

SECTION_NUMBER 1
 '@S9S_MB_2U_LIB.S9S_MB_2U(SCH_1):PAGE578_I5@PURE_QUANTA.Q_INDUCTOR(CHIPS)':
 C_PATH='@s9s_mb_2u_lib.s9s_mb_2u(sch_1):page578_i5@pure_quanta.q_inductor(chips)';

PART_NAME
 PL110 'Q_INDUCTOR_SMLF-100NH/16A,IND,A':;

SECTION_NUMBER 1
 '@S9S_MB_2U_LIB.S9S_MB_2U(SCH_1):PAGE578_I40@PURE_QUANTA.Q_INDUCTOR(CHIPS)':
 C_PATH='@s9s_mb_a_lib.s9s_mb_a(sch_1):page578_i40@pure_quanta.q_inductor(chips)~
';

PART_NAME
 PJ62 'Q_SHORT_SM-EMPTY,SHORT6':;

SECTION_NUMBER 1
 '@S9S_MB_2U_LIB.S9S_MB_2U(SCH_1):PAGE578_I13@PURE_QUANTA.Q_SHORT(CHIPS)':
 C_PATH='@s9s_mb_2u_lib.s9s_mb_2u(sch_1):page578_i13@pure_quanta.q_short(chips)';

PART_NAME
 PC1230 'Q_CAPP_RDLF-560UF,2.5V,20%,ALUA':;

SECTION_NUMBER 1
 '@S9S_MB_2U_LIB.S9S_MB_2U(SCH_1):PAGE578_I8@PURE_QUANTA.Q_CAPP(CHIPS)':
 C_PATH='@s9s_mb_2u_lib.s9s_mb_2u(sch_1):page578_i8@pure_quanta.q_capp(chips)';

PART_NAME
 PC1229 'Q_CAPP_RDLLF-470UF,2V,20%,C_POA':;

SECTION_NUMBER 1
 '@S9S_MB_2U_LIB.S9S_MB_2U(SCH_1):PAGE578_I6@PURE_QUANTA.Q_CAPP(CHIPS)':
 C_PATH='@s9s_mb_2u_lib.s9s_mb_2u(sch_1):page578_i6@pure_quanta.q_capp(chips)';

PART_NAME
 PC1227 'Q_CAPP_RDLF-560UF,2.5V,20%,ALUA':;

SECTION_NUMBER 1
 '@S9S_MB_2U_LIB.S9S_MB_2U(SCH_1):PAGE578_I14@PURE_QUANTA.Q_CAPP(CHIPS)':
 C_PATH='@s9s_mb_2u_lib.s9s_mb_2u(sch_1):page578_i14@pure_quanta.q_capp(chips)';

PART_NAME
 PC1226 'Q_CAP_0805-47UF,4V,20%,X6S,CH6A':;

SECTION_NUMBER 1
 '@S9S_MB_2U_LIB.S9S_MB_2U(SCH_1):PAGE578_I11@PURE_QUANTA.Q_CAP(CHIPS)':
 C_PATH='@s9s_mb_2u_lib.s9s_mb_2u(sch_1):page578_i11@pure_quanta.q_cap(chips)';

PART_NAME
 PC1225 'Q_CAP_0805-47UF,4V,20%,X6S,CH6A':;

SECTION_NUMBER 1
 '@S9S_MB_2U_LIB.S9S_MB_2U(SCH_1):PAGE578_I12@PURE_QUANTA.Q_CAP(CHIPS)':
 C_PATH='@s9s_mb_2u_lib.s9s_mb_2u(sch_1):page578_i12@pure_quanta.q_cap(chips)';

PART_NAME
 PC1224 'Q_CAP_0402-0.1UF,25V,10%,X7R,CA':;

SECTION_NUMBER 1
 '@S9S_MB_2U_LIB.S9S_MB_2U(SCH_1):PAGE578_I16@PURE_QUANTA.Q_CAP(CHIPS)':
 C_PATH='@s9s_mb_2u_lib.s9s_mb_2u(sch_1):page578_i16@pure_quanta.q_cap(chips)';

PART_NAME
 PC1223 'Q_CAP_C0402-470PF,50V,5%,NPO,CA':;

SECTION_NUMBER 1
 '@S9S_MB_2U_LIB.S9S_MB_2U(SCH_1):PAGE578_I18@PURE_QUANTA.Q_CAP(CHIPS)':
 C_PATH='@s9s_mb_2u_lib.s9s_mb_2u(sch_1):page578_i18@pure_quanta.q_cap(chips)';

PART_NAME
 PC1222 'Q_CAP_0402-0.22UF,16V,10%,X7R,A':;

SECTION_NUMBER 1
 '@S9S_MB_2U_LIB.S9S_MB_2U(SCH_1):PAGE578_I23@PURE_QUANTA.Q_CAP(CHIPS)':
 C_PATH='@s9s_mb_2u_lib.s9s_mb_2u(sch_1):page578_i23@pure_quanta.q_cap(chips)';

PART_NAME
 PC1221 'Q_CAP_0402-0.1UF,25V,10%,X7R,CA':;

SECTION_NUMBER 1
 '@S9S_MB_2U_LIB.S9S_MB_2U(SCH_1):PAGE578_I30@PURE_QUANTA.Q_CAP(CHIPS)':
 C_PATH='@s9s_mb_2u_lib.s9s_mb_2u(sch_1):page578_i30@pure_quanta.q_cap(chips)';

PART_NAME
 PC1219 'Q_CAP_0402-0.1UF,25V,10%,X7R,CA':;

SECTION_NUMBER 1
 '@S9S_MB_2U_LIB.S9S_MB_2U(SCH_1):PAGE578_I25@PURE_QUANTA.Q_CAP(CHIPS)':
 C_PATH='@s9s_mb_2u_lib.s9s_mb_2u(sch_1):page578_i25@pure_quanta.q_cap(chips)';

PART_NAME
 PC1218 'Q_CAP_C0805-22UF,16V,20%,X6S,CA':;

SECTION_NUMBER 1
 '@S9S_MB_2U_LIB.S9S_MB_2U(SCH_1):PAGE578_I26@PURE_QUANTA.Q_CAP(CHIPS)':
 C_PATH='@s9s_mb_2u_lib.s9s_mb_2u(sch_1):page578_i26@pure_quanta.q_cap(chips)';

PART_NAME
 PC1217 'Q_CAP_C0805-22UF,16V,20%,X6S,CA':;

SECTION_NUMBER 1
 '@S9S_MB_2U_LIB.S9S_MB_2U(SCH_1):PAGE578_I29@PURE_QUANTA.Q_CAP(CHIPS)':
 C_PATH='@s9s_mb_2u_lib.s9s_mb_2u(sch_1):page578_i29@pure_quanta.q_cap(chips)';

PART_NAME
 PC1216 'Q_CAP_C0805-22UF,16V,20%,X6S,CA':;

SECTION_NUMBER 1
 '@S9S_MB_2U_LIB.S9S_MB_2U(SCH_1):PAGE578_I39@PURE_QUANTA.Q_CAP(CHIPS)':
 C_PATH='@s9s_mb_2u_lib.s9s_mb_2u(sch_1):page578_i39@pure_quanta.q_cap(chips)';

PART_NAME
 PC1215 'Q_CAPP_SMLF-100UF,16V,20%,ALUMA':;

SECTION_NUMBER 1
 '@S9S_MB_2U_LIB.S9S_MB_2U(SCH_1):PAGE578_I43@PURE_QUANTA.Q_CAPP(CHIPS)':
 C_PATH='@s9s_mb_2u_lib.s9s_mb_2u(sch_1):page578_i43@pure_quanta.q_capp(chips)';

PART_NAME
 PC117 'Q_CAPP_RDLLF-470UF,2V,20%,C_POA':;

SECTION_NUMBER 1
 '@S9S_MB_2U_LIB.S9S_MB_2U(SCH_1):PAGE578_I15@PURE_QUANTA.Q_CAPP(CHIPS)':
 C_PATH='@s9s_mb_2u_lib.s9s_mb_2u(sch_1):page578_i15@pure_quanta.q_capp(chips)';

PART_NAME
 PC113 'Q_CAP_C0402-1UF,25V,10%,X6S,CHA':;

SECTION_NUMBER 1
 '@S9S_MB_2U_LIB.S9S_MB_2U(SCH_1):PAGE578_I37@PURE_QUANTA.Q_CAP(CHIPS)':
 C_PATH='@s9s_mb_2u_lib.s9s_mb_2u(sch_1):page578_i37@pure_quanta.q_cap(chips)';

PART_NAME
 C1286 'Q_CAP_0402-1000PF,50V,5%,EMPTYA':;

SECTION_NUMBER 1
 '@S9S_MB_2U_LIB.S9S_MB_2U(SCH_1):PAGE578_I53@PURE_QUANTA.Q_CAP(CHIPS)':
 C_PATH='@s9s_mb_2u_lib.s9s_mb_2u(sch_1):page578_i53@pure_quanta.q_cap(chips)';

PART_NAME
 R1673 'Q_RES_0402LF-10K,1%,1/16W,EMPTA':;

SECTION_NUMBER 1
 '@S9S_MB_2U_LIB.S9S_MB_2U(SCH_1):PAGE503_I183@PURE_QUANTA.Q_RES(CHIPS)':
 C_PATH='@s9s_mb_2u_lib.s9s_mb_2u(sch_1):page503_i183@pure_quanta.q_res(chips)';

PART_NAME
 R1672 'Q_RES_0402LF-0,5%,1/16W,CHIP,CA':;

SECTION_NUMBER 1
 '@S9S_MB_2U_LIB.S9S_MB_2U(SCH_1):PAGE503_I180@PURE_QUANTA.Q_RES(CHIPS)':
 C_PATH='@s9s_mb_2u_lib.s9s_mb_2u(sch_1):page503_i180@pure_quanta.q_res(chips)';

PART_NAME
 R1102 'Q_RES_0402LF-0,5%,1/16W,CHIP,CA':;

SECTION_NUMBER 1
 '@S9S_MB_2U_LIB.S9S_MB_2U(SCH_1):PAGE503_I203@PURE_QUANTA.Q_RES(CHIPS)':
 C_PATH='@s9s_mb_2u_lib.s9s_mb_2u(sch_1):page503_i203@pure_quanta.q_res(chips)';

PART_NAME
 R926 'Q_RES_0402LF-0,5%,1/16W,CHIP,CA':;

SECTION_NUMBER 1
 '@S9S_MB_2U_LIB.S9S_MB_2U(SCH_1):PAGE503_I200@PURE_QUANTA.Q_RES(CHIPS)':
 C_PATH='@s9s_mb_2u_lib.s9s_mb_2u(sch_1):page503_i200@pure_quanta.q_res(chips)';

PART_NAME
 R925 'Q_RES_0402LF-0,5%,1/16W,CHIP,CA':;

SECTION_NUMBER 1
 '@S9S_MB_2U_LIB.S9S_MB_2U(SCH_1):PAGE503_I194@PURE_QUANTA.Q_RES(CHIPS)':
 C_PATH='@s9s_mb_2u_lib.s9s_mb_2u(sch_1):page503_i194@pure_quanta.q_res(chips)';

PART_NAME
 R458 'Q_RES_0402LF-33.2,1%,1/16W,CHIA':;

SECTION_NUMBER 1
 '@S9S_MB_2U_LIB.S9S_MB_2U(SCH_1):PAGE503_I24@PURE_QUANTA.Q_RES(CHIPS)':
 C_PATH='@s9s_mb_2u_lib.s9s_mb_2u(sch_1):page503_i24@pure_quanta.q_res(chips)';

PART_NAME
 R457 'Q_RES_0402LF-33.2,1%,1/16W,CHIA':;

SECTION_NUMBER 1
 '@S9S_MB_2U_LIB.S9S_MB_2U(SCH_1):PAGE503_I23@PURE_QUANTA.Q_RES(CHIPS)':
 C_PATH='@s9s_mb_2u_lib.s9s_mb_2u(sch_1):page503_i23@pure_quanta.q_res(chips)';

PART_NAME
 R452 'Q_RES_0402LF-0,5%,1/16W,CHIP,CA':;

SECTION_NUMBER 1
 '@S9S_MB_2U_LIB.S9S_MB_2U(SCH_1):PAGE503_I95@PURE_QUANTA.Q_RES(CHIPS)':
 C_PATH='@s9s_mb_2u_lib.s9s_mb_2u(sch_1):page503_i95@pure_quanta.q_res(chips)';

PART_NAME
 R451 'Q_RES_0402LF-0,5%,1/16W,CHIP,CA':;

SECTION_NUMBER 1
 '@S9S_MB_2U_LIB.S9S_MB_2U(SCH_1):PAGE503_I96@PURE_QUANTA.Q_RES(CHIPS)':
 C_PATH='@s9s_mb_2u_lib.s9s_mb_2u(sch_1):page503_i96@pure_quanta.q_res(chips)';

PART_NAME
 R450 'Q_RES_0402LF-0,5%,1/16W,CHIP,CA':;

SECTION_NUMBER 1
 '@S9S_MB_2U_LIB.S9S_MB_2U(SCH_1):PAGE503_I93@PURE_QUANTA.Q_RES(CHIPS)':
 C_PATH='@s9s_mb_2u_lib.s9s_mb_2u(sch_1):page503_i93@pure_quanta.q_res(chips)';

PART_NAME
 R449 'Q_RES_0402LF-0,5%,1/16W,CHIP,CA':;

SECTION_NUMBER 1
 '@S9S_MB_2U_LIB.S9S_MB_2U(SCH_1):PAGE503_I94@PURE_QUANTA.Q_RES(CHIPS)':
 C_PATH='@s9s_mb_2u_lib.s9s_mb_2u(sch_1):page503_i94@pure_quanta.q_res(chips)';

PART_NAME
 R446 'Q_RES_0402LF-100K,1%,1/16W,CHIA':;

SECTION_NUMBER 1
 '@S9S_MB_2U_LIB.S9S_MB_2U(SCH_1):PAGE503_I207@PURE_QUANTA.Q_RES(CHIPS)':
 C_PATH='@s9s_mb_2u_lib.s9s_mb_2u(sch_1):page503_i207@pure_quanta.q_res(chips)';

PART_NAME
 R439 'Q_RES_0402LF-0,5%,1/16W,EMPTY,A':;

SECTION_NUMBER 1
 '@S9S_MB_2U_LIB.S9S_MB_2U(SCH_1):PAGE503_I161@PURE_QUANTA.Q_RES(CHIPS)':
 C_PATH='@s9s_mb_2u_lib.s9s_mb_2u(sch_1):page503_i161@pure_quanta.q_res(chips)';

PART_NAME
 R438 'Q_RES_0402LF-1K,1%,1/16W,EMPTYA':;

SECTION_NUMBER 1
 '@S9S_MB_2U_LIB.S9S_MB_2U(SCH_1):PAGE503_I205@PURE_QUANTA.Q_RES(CHIPS)':
 C_PATH='@s9s_mb_2u_lib.s9s_mb_2u(sch_1):page503_i205@pure_quanta.q_res(chips)';

PART_NAME
 R437 'Q_RES_0402LF-4.7K,5%,1/16W,CHIA':;

SECTION_NUMBER 1
 '@S9S_MB_2U_LIB.S9S_MB_2U(SCH_1):PAGE503_I159@PURE_QUANTA.Q_RES(CHIPS)':
 C_PATH='@s9s_mb_2u_lib.s9s_mb_2u(sch_1):page503_i159@pure_quanta.q_res(chips)';

PART_NAME
 R436 'Q_RES_0402LF-1K,1%,1/16W,EMPTYA':;

SECTION_NUMBER 1
 '@S9S_MB_2U_LIB.S9S_MB_2U(SCH_1):PAGE503_I204@PURE_QUANTA.Q_RES(CHIPS)':
 C_PATH='@s9s_mb_2u_lib.s9s_mb_2u(sch_1):page503_i204@pure_quanta.q_res(chips)';

PART_NAME
 R431 'Q_RES_0402LF-4.7K,1%,1/16W,CHIA':;

SECTION_NUMBER 1
 '@S9S_MB_2U_LIB.S9S_MB_2U(SCH_1):PAGE503_I187@PURE_QUANTA.Q_RES(CHIPS)':
 C_PATH='@s9s_mb_2u_lib.s9s_mb_2u(sch_1):page503_i187@pure_quanta.q_res(chips)';

PART_NAME
 R430 'Q_RES_0402LF-4.7K,1%,1/16W,EMPA':;

SECTION_NUMBER 1
 '@S9S_MB_2U_LIB.S9S_MB_2U(SCH_1):PAGE503_I186@PURE_QUANTA.Q_RES(CHIPS)':
 C_PATH='@s9s_mb_2u_lib.s9s_mb_2u(sch_1):page503_i186@pure_quanta.q_res(chips)';

PART_NAME
 R427 'Q_RES_0402LF-4.7K,1%,1/16W,CHIA':;

SECTION_NUMBER 1
 '@S9S_MB_2U_LIB.S9S_MB_2U(SCH_1):PAGE503_I190@PURE_QUANTA.Q_RES(CHIPS)':
 C_PATH='@s9s_mb_2u_lib.s9s_mb_2u(sch_1):page503_i190@pure_quanta.q_res(chips)';

PART_NAME
 R426 'Q_RES_0402LF-4.7K,1%,1/16W,EMPA':;

SECTION_NUMBER 1
 '@S9S_MB_2U_LIB.S9S_MB_2U(SCH_1):PAGE503_I189@PURE_QUANTA.Q_RES(CHIPS)':
 C_PATH='@s9s_mb_2u_lib.s9s_mb_2u(sch_1):page503_i189@pure_quanta.q_res(chips)';

PART_NAME
 R405 'Q_RES_0402LF-100,1%,1/16W,CHIPA':;

SECTION_NUMBER 1
 '@S9S_MB_2U_LIB.S9S_MB_2U(SCH_1):PAGE503_I154@PURE_QUANTA.Q_RES(CHIPS)':
 C_PATH='@s9s_mb_2u_lib.s9s_mb_2u(sch_1):page503_i154@pure_quanta.q_res(chips)';

PART_NAME
 J38 'SCONN168_623403212-SCONN168_6-A':;

SECTION_NUMBER 1
 '@S9S_MB_2U_LIB.S9S_MB_2U(SCH_1):PAGE503_I107@PURE_QUANTA.SCONN168_623403212(CHIPS)':
 C_PATH='@s9s_mb_2u_lib.s9s_mb_2u(sch_1):page503_i107@pure_quanta.sconn168_6234032~
12(chips)';

PART_NAME
 C1285 'Q_CAP_0402-0.1UF,25V,10%,X7R,CA':;

SECTION_NUMBER 1
 '@S9S_MB_2U_LIB.S9S_MB_2U(SCH_1):PAGE503_I179@PURE_QUANTA.Q_CAP(CHIPS)':
 C_PATH='@s9s_mb_2u_lib.s9s_mb_2u(sch_1):page503_i179@pure_quanta.q_cap(chips)';

PART_NAME
 C1284 'Q_CAP_0402-0.1UF,25V,10%,X7R,CA':;

SECTION_NUMBER 1
 '@S9S_MB_2U_LIB.S9S_MB_2U(SCH_1):PAGE503_I176@PURE_QUANTA.Q_CAP(CHIPS)':
 C_PATH='@s9s_mb_2u_lib.s9s_mb_2u(sch_1):page503_i176@pure_quanta.q_cap(chips)';

PART_NAME
 C1283 'Q_CAP_0402-0.1UF,25V,10%,X7R,CA':;

SECTION_NUMBER 1
 '@S9S_MB_2U_LIB.S9S_MB_2U(SCH_1):PAGE503_I175@PURE_QUANTA.Q_CAP(CHIPS)':
 C_PATH='@s9s_mb_2u_lib.s9s_mb_2u(sch_1):page503_i175@pure_quanta.q_cap(chips)';

PART_NAME
 C1282 'Q_CAP_0402-0.1UF,25V,10%,X7R,CA':;

SECTION_NUMBER 1
 '@S9S_MB_2U_LIB.S9S_MB_2U(SCH_1):PAGE503_I174@PURE_QUANTA.Q_CAP(CHIPS)':
 C_PATH='@s9s_mb_2u_lib.s9s_mb_2u(sch_1):page503_i174@pure_quanta.q_cap(chips)';

PART_NAME
 C1281 'Q_CAP_0402-0.1UF,25V,10%,X7R,CA':;

SECTION_NUMBER 1
 '@S9S_MB_2U_LIB.S9S_MB_2U(SCH_1):PAGE503_I173@PURE_QUANTA.Q_CAP(CHIPS)':
 C_PATH='@s9s_mb_2u_lib.s9s_mb_2u(sch_1):page503_i173@pure_quanta.q_cap(chips)';

PART_NAME
 C1280 'Q_CAP_0402-0.1UF,25V,10%,X7R,CA':;

SECTION_NUMBER 1
 '@S9S_MB_2U_LIB.S9S_MB_2U(SCH_1):PAGE503_I171@PURE_QUANTA.Q_CAP(CHIPS)':
 C_PATH='@s9s_mb_2u_lib.s9s_mb_2u(sch_1):page503_i171@pure_quanta.q_cap(chips)';

PART_NAME
 C1279 'Q_CAP_0402-0.1UF,25V,10%,X7R,CA':;

SECTION_NUMBER 1
 '@S9S_MB_2U_LIB.S9S_MB_2U(SCH_1):PAGE503_I170@PURE_QUANTA.Q_CAP(CHIPS)':
 C_PATH='@s9s_mb_2u_lib.s9s_mb_2u(sch_1):page503_i170@pure_quanta.q_cap(chips)';

PART_NAME
 C1278 'Q_CAP_0402-0.1UF,25V,10%,X7R,CA':;

SECTION_NUMBER 1
 '@S9S_MB_2U_LIB.S9S_MB_2U(SCH_1):PAGE503_I168@PURE_QUANTA.Q_CAP(CHIPS)':
 C_PATH='@s9s_mb_2u_lib.s9s_mb_2u(sch_1):page503_i168@pure_quanta.q_cap(chips)';

PART_NAME
 C1277 'Q_CAP_C0805-22UF,16V,20%,X6S,CA':;

SECTION_NUMBER 1
 '@S9S_MB_2U_LIB.S9S_MB_2U(SCH_1):PAGE503_I167@PURE_QUANTA.Q_CAP(CHIPS)':
 C_PATH='@s9s_mb_2u_lib.s9s_mb_2u(sch_1):page503_i167@pure_quanta.q_cap(chips)';

PART_NAME
 C1276 'Q_CAP_C0805-22UF,16V,20%,X6S,CA':;

SECTION_NUMBER 1
 '@S9S_MB_2U_LIB.S9S_MB_2U(SCH_1):PAGE503_I166@PURE_QUANTA.Q_CAP(CHIPS)':
 C_PATH='@s9s_mb_2u_lib.s9s_mb_2u(sch_1):page503_i166@pure_quanta.q_cap(chips)';

PART_NAME
 U101 'SN74LVC1G17DCKR-SN74LVC1G17DCKA':;

SECTION_NUMBER 1
 '@S9S_MB_2U_LIB.S9S_MB_2U(SCH_1):PAGE519_I205@PURE_QUANTA.SN74LVC1G17DCKR(CHIPS)':
 C_PATH='@s9s_mb_2u_lib.s9s_mb_2u(sch_1):page519_i205@pure_quanta.sn74lvc1g17dckr(~
chips)';

PART_NAME
 U55 '74LVC1G07GV-74LVC1G07GV,SMLF,IA':;

SECTION_NUMBER 1
 '@S9S_MB_2U_LIB.S9S_MB_2U(SCH_1):PAGE519_I158@PURE_QUANTA.74LVC1G07GV(CHIPS)':
 C_PATH='@s9s_mb_2u_lib.s9s_mb_2u(sch_1):page519_i158@pure_quanta.\74lvc1g07gv\(ch~
ips)';

PART_NAME
 U54 '74LVC1G07GV-74LVC1G07GV,SMLF,IA':;

SECTION_NUMBER 1
 '@S9S_MB_2U_LIB.S9S_MB_2U(SCH_1):PAGE519_I165@PURE_QUANTA.74LVC1G07GV(CHIPS)':
 C_PATH='@s9s_mb_2u_lib.s9s_mb_2u(sch_1):page519_i165@pure_quanta.\74lvc1g07gv\(ch~
ips)';

PART_NAME
 R1828 'Q_RES_0402LF-10K,1%,1/16W,CHIPA':;

SECTION_NUMBER 1
 '@S9S_MB_2U_LIB.S9S_MB_2U(SCH_1):PAGE519_I188@PURE_QUANTA.Q_RES(CHIPS)':
 C_PATH='@s9s_mb_2u_lib.s9s_mb_2u(sch_1):page519_i188@pure_quanta.q_res(chips)';

PART_NAME
 R1827 'Q_RES_0402LF-33,5%,1/16W,CHIP,A':;

SECTION_NUMBER 1
 '@S9S_MB_2U_LIB.S9S_MB_2U(SCH_1):PAGE519_I193@PURE_QUANTA.Q_RES(CHIPS)':
 C_PATH='@s9s_mb_2u_lib.s9s_mb_2u(sch_1):page519_i193@pure_quanta.q_res(chips)';

PART_NAME
 R1778 'Q_RES_0402LF-0,5%,1/16W,EMPTY,A':;

SECTION_NUMBER 1
 '@S9S_MB_2U_LIB.S9S_MB_2U(SCH_1):PAGE519_I244@PURE_QUANTA.Q_RES(CHIPS)':
 C_PATH='@s9s_mb_2u_lib.s9s_mb_2u(sch_1):page519_i244@pure_quanta.q_res(chips)';

PART_NAME
 R1777 'Q_RES_0402LF-0,5%,1/16W,EMPTY,A':;

SECTION_NUMBER 1
 '@S9S_MB_2U_LIB.S9S_MB_2U(SCH_1):PAGE519_I243@PURE_QUANTA.Q_RES(CHIPS)':
 C_PATH='@s9s_mb_2u_lib.s9s_mb_2u(sch_1):page519_i243@pure_quanta.q_res(chips)';

PART_NAME
 R1697 'Q_RES_0402LF-10K,1%,1/16W,CHIPA':;

SECTION_NUMBER 1
 '@S9S_MB_2U_LIB.S9S_MB_2U(SCH_1):PAGE519_I186@PURE_QUANTA.Q_RES(CHIPS)':
 C_PATH='@s9s_mb_2u_lib.s9s_mb_2u(sch_1):page519_i186@pure_quanta.q_res(chips)';

PART_NAME
 R1696 'Q_RES_0402LF-10K,1%,1/16W,CHIPA':;

SECTION_NUMBER 1
 '@S9S_MB_2U_LIB.S9S_MB_2U(SCH_1):PAGE519_I184@PURE_QUANTA.Q_RES(CHIPS)':
 C_PATH='@s9s_mb_2u_lib.s9s_mb_2u(sch_1):page519_i184@pure_quanta.q_res(chips)';

PART_NAME
 R1659 'Q_RES_0402LF-10K,1%,1/16W,CHIPA':;

SECTION_NUMBER 1
 '@S9S_MB_2U_LIB.S9S_MB_2U(SCH_1):PAGE519_I181@PURE_QUANTA.Q_RES(CHIPS)':
 C_PATH='@s9s_mb_2u_lib.s9s_mb_2u(sch_1):page519_i181@pure_quanta.q_res(chips)';

PART_NAME
 R1658 'Q_RES_0402LF-10K,1%,1/16W,CHIPA':;

SECTION_NUMBER 1
 '@S9S_MB_2U_LIB.S9S_MB_2U(SCH_1):PAGE519_I174@PURE_QUANTA.Q_RES(CHIPS)':
 C_PATH='@s9s_mb_2u_lib.s9s_mb_2u(sch_1):page519_i174@pure_quanta.q_res(chips)';

PART_NAME
 R1657 'Q_RES_0402LF-33,5%,1/16W,CHIP,A':;

SECTION_NUMBER 1
 '@S9S_MB_2U_LIB.S9S_MB_2U(SCH_1):PAGE519_I180@PURE_QUANTA.Q_RES(CHIPS)':
 C_PATH='@s9s_mb_2u_lib.s9s_mb_2u(sch_1):page519_i180@pure_quanta.q_res(chips)';

PART_NAME
 R1656 'Q_RES_0402LF-33,5%,1/16W,CHIP,A':;

SECTION_NUMBER 1
 '@S9S_MB_2U_LIB.S9S_MB_2U(SCH_1):PAGE519_I178@PURE_QUANTA.Q_RES(CHIPS)':
 C_PATH='@s9s_mb_2u_lib.s9s_mb_2u(sch_1):page519_i178@pure_quanta.q_res(chips)';

PART_NAME
 R1601 'Q_RES_0402LF-10K,1%,1/16W,CHIPA':;

SECTION_NUMBER 1
 '@S9S_MB_2U_LIB.S9S_MB_2U(SCH_1):PAGE519_I151@PURE_QUANTA.Q_RES(CHIPS)':
 C_PATH='@s9s_mb_2u_lib.s9s_mb_2u(sch_1):page519_i151@pure_quanta.q_res(chips)';

PART_NAME
 R1600 'Q_RES_0402LF-33,5%,1/16W,CHIP,A':;

SECTION_NUMBER 1
 '@S9S_MB_2U_LIB.S9S_MB_2U(SCH_1):PAGE519_I148@PURE_QUANTA.Q_RES(CHIPS)':
 C_PATH='@s9s_mb_2u_lib.s9s_mb_2u(sch_1):page519_i148@pure_quanta.q_res(chips)';

PART_NAME
 R1583 'Q_RES_0402LF-10K,1%,1/16W,CHIPA':;

SECTION_NUMBER 1
 '@S9S_MB_2U_LIB.S9S_MB_2U(SCH_1):PAGE519_I144@PURE_QUANTA.Q_RES(CHIPS)':
 C_PATH='@s9s_mb_2u_lib.s9s_mb_2u(sch_1):page519_i144@pure_quanta.q_res(chips)';

PART_NAME
 R1582 'Q_RES_0402LF-2K,1%,1/16W,CHIP,A':;

SECTION_NUMBER 1
 '@S9S_MB_2U_LIB.S9S_MB_2U(SCH_1):PAGE519_I141@PURE_QUANTA.Q_RES(CHIPS)':
 C_PATH='@s9s_mb_2u_lib.s9s_mb_2u(sch_1):page519_i141@pure_quanta.q_res(chips)';

PART_NAME
 R1581 'Q_RES_0402LF-2K,1%,1/16W,CHIP,A':;

SECTION_NUMBER 1
 '@S9S_MB_2U_LIB.S9S_MB_2U(SCH_1):PAGE519_I142@PURE_QUANTA.Q_RES(CHIPS)':
 C_PATH='@s9s_mb_2u_lib.s9s_mb_2u(sch_1):page519_i142@pure_quanta.q_res(chips)';

PART_NAME
 R1546 'Q_RES_0402LF-2K,1%,1/16W,CHIP,A':;

SECTION_NUMBER 1
 '@S9S_MB_2U_LIB.S9S_MB_2U(SCH_1):PAGE519_I138@PURE_QUANTA.Q_RES(CHIPS)':
 C_PATH='@s9s_mb_2u_lib.s9s_mb_2u(sch_1):page519_i138@pure_quanta.q_res(chips)';

PART_NAME
 R1545 'Q_RES_0402LF-2K,1%,1/16W,CHIP,A':;

SECTION_NUMBER 1
 '@S9S_MB_2U_LIB.S9S_MB_2U(SCH_1):PAGE519_I137@PURE_QUANTA.Q_RES(CHIPS)':
 C_PATH='@s9s_mb_2u_lib.s9s_mb_2u(sch_1):page519_i137@pure_quanta.q_res(chips)';

PART_NAME
 R1487 'Q_RES_0402LF-100,1%,1/16W,CHIPA':;

SECTION_NUMBER 1
 '@S9S_MB_2U_LIB.S9S_MB_2U(SCH_1):PAGE519_I125@PURE_QUANTA.Q_RES(CHIPS)':
 C_PATH='@s9s_mb_2u_lib.s9s_mb_2u(sch_1):page519_i125@pure_quanta.q_res(chips)';

PART_NAME
 R1454 'Q_RES_0402LF-2K,1%,1/16W,CHIP,A':;

SECTION_NUMBER 1
 '@S9S_MB_2U_LIB.S9S_MB_2U(SCH_1):PAGE519_I121@PURE_QUANTA.Q_RES(CHIPS)':
 C_PATH='@s9s_mb_2u_lib.s9s_mb_2u(sch_1):page519_i121@pure_quanta.q_res(chips)';

PART_NAME
 R1453 'Q_RES_0402LF-2K,1%,1/16W,CHIP,A':;

SECTION_NUMBER 1
 '@S9S_MB_2U_LIB.S9S_MB_2U(SCH_1):PAGE519_I120@PURE_QUANTA.Q_RES(CHIPS)':
 C_PATH='@s9s_mb_2u_lib.s9s_mb_2u(sch_1):page519_i120@pure_quanta.q_res(chips)';

PART_NAME
 R1452 'Q_RES_0402LF-2K,1%,1/16W,CHIP,A':;

SECTION_NUMBER 1
 '@S9S_MB_2U_LIB.S9S_MB_2U(SCH_1):PAGE519_I112@PURE_QUANTA.Q_RES(CHIPS)':
 C_PATH='@s9s_mb_2u_lib.s9s_mb_2u(sch_1):page519_i112@pure_quanta.q_res(chips)';

PART_NAME
 R1451 'Q_RES_0402LF-2K,1%,1/16W,CHIP,A':;

SECTION_NUMBER 1
 '@S9S_MB_2U_LIB.S9S_MB_2U(SCH_1):PAGE519_I109@PURE_QUANTA.Q_RES(CHIPS)':
 C_PATH='@s9s_mb_2u_lib.s9s_mb_2u(sch_1):page519_i109@pure_quanta.q_res(chips)';

PART_NAME
 R1269 'Q_RES_0402LF-4.75K,1%,1/16W,CHA':;

SECTION_NUMBER 1
 '@S9S_MB_2U_LIB.S9S_MB_2U(SCH_1):PAGE519_I225@PURE_QUANTA.Q_RES(CHIPS)':
 C_PATH='@s9s_mb_2u_lib.s9s_mb_2u(sch_1):page519_i225@pure_quanta.q_res(chips)';

PART_NAME
 R1268 'Q_RES_0402LF-33,5%,1/16W,CHIP,A':;

SECTION_NUMBER 1
 '@S9S_MB_2U_LIB.S9S_MB_2U(SCH_1):PAGE519_I222@PURE_QUANTA.Q_RES(CHIPS)':
 C_PATH='@s9s_mb_2u_lib.s9s_mb_2u(sch_1):page519_i222@pure_quanta.q_res(chips)';

PART_NAME
 R913 'Q_RES_0402LF-10K,1%,1/16W,CHIPA':;

SECTION_NUMBER 1
 '@S9S_MB_2U_LIB.S9S_MB_2U(SCH_1):PAGE519_I241@PURE_QUANTA.Q_RES(CHIPS)':
 C_PATH='@s9s_mb_2u_lib.s9s_mb_2u(sch_1):page519_i241@pure_quanta.q_res(chips)';

PART_NAME
 R770 'Q_RES_0402LF-10K,1%,1/16W,CHIPA':;

SECTION_NUMBER 1
 '@S9S_MB_2U_LIB.S9S_MB_2U(SCH_1):PAGE519_I239@PURE_QUANTA.Q_RES(CHIPS)':
 C_PATH='@s9s_mb_2u_lib.s9s_mb_2u(sch_1):page519_i239@pure_quanta.q_res(chips)';

PART_NAME
 R727 'Q_RES_0402LF-10K,1%,1/16W,CHIPA':;

SECTION_NUMBER 1
 '@S9S_MB_2U_LIB.S9S_MB_2U(SCH_1):PAGE519_I236@PURE_QUANTA.Q_RES(CHIPS)':
 C_PATH='@s9s_mb_2u_lib.s9s_mb_2u(sch_1):page519_i236@pure_quanta.q_res(chips)';

PART_NAME
 R699 'Q_RES_0402LF-33,5%,1/16W,CHIP,A':;

SECTION_NUMBER 1
 '@S9S_MB_2U_LIB.S9S_MB_2U(SCH_1):PAGE519_I102@PURE_QUANTA.Q_RES(CHIPS)':
 C_PATH='@s9s_mb_2u_lib.s9s_mb_2u(sch_1):page519_i102@pure_quanta.q_res(chips)';

PART_NAME
 R635 'Q_RES_0402LF-10K,1%,1/16W,CHIPA':;

SECTION_NUMBER 1
 '@S9S_MB_2U_LIB.S9S_MB_2U(SCH_1):PAGE519_I234@PURE_QUANTA.Q_RES(CHIPS)':
 C_PATH='@s9s_mb_2u_lib.s9s_mb_2u(sch_1):page519_i234@pure_quanta.q_res(chips)';

PART_NAME
 R634 'Q_RES_0402LF-10K,1%,1/16W,CHIPA':;

SECTION_NUMBER 1
 '@S9S_MB_2U_LIB.S9S_MB_2U(SCH_1):PAGE519_I233@PURE_QUANTA.Q_RES(CHIPS)':
 C_PATH='@s9s_mb_2u_lib.s9s_mb_2u(sch_1):page519_i233@pure_quanta.q_res(chips)';

PART_NAME
 R633 'Q_RES_0402LF-0,5%,1/16W,EMPTY,A':;

SECTION_NUMBER 1
 '@S9S_MB_2U_LIB.S9S_MB_2U(SCH_1):PAGE519_I215@PURE_QUANTA.Q_RES(CHIPS)':
 C_PATH='@s9s_mb_2u_lib.s9s_mb_2u(sch_1):page519_i215@pure_quanta.q_res(chips)';

PART_NAME
 R632 'Q_RES_0402LF-0,5%,1/16W,EMPTY,A':;

SECTION_NUMBER 1
 '@S9S_MB_2U_LIB.S9S_MB_2U(SCH_1):PAGE519_I214@PURE_QUANTA.Q_RES(CHIPS)':
 C_PATH='@s9s_mb_2u_lib.s9s_mb_2u(sch_1):page519_i214@pure_quanta.q_res(chips)';

PART_NAME
 R631 'Q_RES_0402LF-0,5%,1/16W,EMPTY,A':;

SECTION_NUMBER 1
 '@S9S_MB_2U_LIB.S9S_MB_2U(SCH_1):PAGE519_I226@PURE_QUANTA.Q_RES(CHIPS)':
 C_PATH='@s9s_mb_2u_lib.s9s_mb_2u(sch_1):page519_i226@pure_quanta.q_res(chips)';

PART_NAME
 R474 'Q_RES_0402LF-33,5%,1/16W,CHIP,A':;

SECTION_NUMBER 1
 '@S9S_MB_2U_LIB.S9S_MB_2U(SCH_1):PAGE519_I213@PURE_QUANTA.Q_RES(CHIPS)':
 C_PATH='@s9s_mb_2u_lib.s9s_mb_2u(sch_1):page519_i213@pure_quanta.q_res(chips)';

PART_NAME
 C1408 'Q_CAP_0402-0.1UF,25V,10%,X7R,CA':;

SECTION_NUMBER 1
 '@S9S_MB_2U_LIB.S9S_MB_2U(SCH_1):PAGE519_I206@PURE_QUANTA.Q_CAP(CHIPS)':
 C_PATH='@s9s_mb_2u_lib.s9s_mb_2u(sch_1):page519_i206@pure_quanta.q_cap(chips)';

PART_NAME
 C1230 'Q_CAP_0402-0.1UF,25V,10%,X7R,CA':;

SECTION_NUMBER 1
 '@S9S_MB_2U_LIB.S9S_MB_2U(SCH_1):PAGE519_I163@PURE_QUANTA.Q_CAP(CHIPS)':
 C_PATH='@s9s_mb_2u_lib.s9s_mb_2u(sch_1):page519_i163@pure_quanta.q_cap(chips)';

PART_NAME
 C1229 'Q_CAP_0402-0.1UF,25V,10%,X7R,CA':;

SECTION_NUMBER 1
 '@S9S_MB_2U_LIB.S9S_MB_2U(SCH_1):PAGE519_I168@PURE_QUANTA.Q_CAP(CHIPS)':
 C_PATH='@s9s_mb_2u_lib.s9s_mb_2u(sch_1):page519_i168@pure_quanta.q_cap(chips)';

PART_NAME
 R1930 'Q_RES_0402LF-10K,5%,1/16W,CHIPA':;

SECTION_NUMBER 1
 '@S9S_MB_2U_LIB.S9S_MB_2U(SCH_1):PAGE500_I359@PURE_QUANTA.Q_RES(CHIPS)':
 C_PATH='@s9s_mb_2u_lib.s9s_mb_2u(sch_1):page500_i359@pure_quanta.q_res(chips)';

PART_NAME
 R1929 'Q_RES_0402LF-10K,5%,1/16W,CHIPA':;

SECTION_NUMBER 1
 '@S9S_MB_2U_LIB.S9S_MB_2U(SCH_1):PAGE500_I360@PURE_QUANTA.Q_RES(CHIPS)':
 C_PATH='@s9s_mb_2u_lib.s9s_mb_2u(sch_1):page500_i360@pure_quanta.q_res(chips)';

PART_NAME
 R1895 'Q_RES_0402LF-100,1%,1/16W,CHIPA':;

SECTION_NUMBER 1
 '@S9S_MB_2U_LIB.S9S_MB_2U(SCH_1):PAGE500_I353@PURE_QUANTA.Q_RES(CHIPS)':
 C_PATH='@s9s_mb_2u_lib.s9s_mb_2u(sch_1):page500_i353@pure_quanta.q_res(chips)';

PART_NAME
 R1671 'Q_RES_0402LF-0,5%,1/16W,CHIP,CA':;

SECTION_NUMBER 1
 '@S9S_MB_2U_LIB.S9S_MB_2U(SCH_1):PAGE500_I340@PURE_QUANTA.Q_RES(CHIPS)':
 C_PATH='@s9s_mb_2u_lib.s9s_mb_2u(sch_1):page500_i340@pure_quanta.q_res(chips)';

PART_NAME
 R454 'Q_RES_0402LF-10K,1%,1/16W,EMPTA':;

SECTION_NUMBER 1
 '@S9S_MB_2U_LIB.S9S_MB_2U(SCH_1):PAGE500_I314@PURE_QUANTA.Q_RES(CHIPS)':
 C_PATH='@s9s_mb_2u_lib.s9s_mb_2u(sch_1):page500_i314@pure_quanta.q_res(chips)';

PART_NAME
 R445 'Q_RES_0402LF-0,5%,1/16W,CHIP,CA':;

SECTION_NUMBER 1
 '@S9S_MB_2U_LIB.S9S_MB_2U(SCH_1):PAGE500_I349@PURE_QUANTA.Q_RES(CHIPS)':
 C_PATH='@s9s_mb_2u_lib.s9s_mb_2u(sch_1):page500_i349@pure_quanta.q_res(chips)';

PART_NAME
 R444 'Q_RES_0402LF-0,5%,1/16W,CHIP,CA':;

SECTION_NUMBER 1
 '@S9S_MB_2U_LIB.S9S_MB_2U(SCH_1):PAGE500_I350@PURE_QUANTA.Q_RES(CHIPS)':
 C_PATH='@s9s_mb_2u_lib.s9s_mb_2u(sch_1):page500_i350@pure_quanta.q_res(chips)';

PART_NAME
 R429 'Q_RES_0402LF-0,5%,1/16W,CHIP,CA':;

SECTION_NUMBER 1
 '@S9S_MB_2U_LIB.S9S_MB_2U(SCH_1):PAGE500_I344@PURE_QUANTA.Q_RES(CHIPS)':
 C_PATH='@s9s_mb_2u_lib.s9s_mb_2u(sch_1):page500_i344@pure_quanta.q_res(chips)';

PART_NAME
 R425 'Q_RES_0402LF-33.2,1%,1/16W,CHIA':;

SECTION_NUMBER 1
 '@S9S_MB_2U_LIB.S9S_MB_2U(SCH_1):PAGE500_I174@PURE_QUANTA.Q_RES(CHIPS)':
 C_PATH='@s9s_mb_2u_lib.s9s_mb_2u(sch_1):page500_i174@pure_quanta.q_res(chips)';

PART_NAME
 R424 'Q_RES_0402LF-33.2,1%,1/16W,CHIA':;

SECTION_NUMBER 1
 '@S9S_MB_2U_LIB.S9S_MB_2U(SCH_1):PAGE500_I173@PURE_QUANTA.Q_RES(CHIPS)':
 C_PATH='@s9s_mb_2u_lib.s9s_mb_2u(sch_1):page500_i173@pure_quanta.q_res(chips)';

PART_NAME
 R423 'Q_RES_0402LF-0,5%,1/16W,EMPTY,A':;

SECTION_NUMBER 1
 '@S9S_MB_2U_LIB.S9S_MB_2U(SCH_1):PAGE500_I13@PURE_QUANTA.Q_RES(CHIPS)':
 C_PATH='@s9s_mb_2u_lib.s9s_mb_2u(sch_1):page500_i13@pure_quanta.q_res(chips)';

PART_NAME
 R422 'Q_RES_0402LF-1K,1%,1/16W,EMPTYA':;

SECTION_NUMBER 1
 '@S9S_MB_2U_LIB.S9S_MB_2U(SCH_1):PAGE500_I12@PURE_QUANTA.Q_RES(CHIPS)':
 C_PATH='@s9s_mb_2u_lib.s9s_mb_2u(sch_1):page500_i12@pure_quanta.q_res(chips)';

PART_NAME
 R421 'Q_RES_0402LF-4.7K,5%,1/16W,CHIA':;

SECTION_NUMBER 1
 '@S9S_MB_2U_LIB.S9S_MB_2U(SCH_1):PAGE500_I11@PURE_QUANTA.Q_RES(CHIPS)':
 C_PATH='@s9s_mb_2u_lib.s9s_mb_2u(sch_1):page500_i11@pure_quanta.q_res(chips)';

PART_NAME
 R420 'Q_RES_0402LF-1K,1%,1/16W,EMPTYA':;

SECTION_NUMBER 1
 '@S9S_MB_2U_LIB.S9S_MB_2U(SCH_1):PAGE500_I10@PURE_QUANTA.Q_RES(CHIPS)':
 C_PATH='@s9s_mb_2u_lib.s9s_mb_2u(sch_1):page500_i10@pure_quanta.q_res(chips)';

PART_NAME
 R418 'Q_RES_0402LF-0,5%,1/16W,CHIP,CA':;

SECTION_NUMBER 1
 '@S9S_MB_2U_LIB.S9S_MB_2U(SCH_1):PAGE500_I258@PURE_QUANTA.Q_RES(CHIPS)':
 C_PATH='@s9s_mb_2u_lib.s9s_mb_2u(sch_1):page500_i258@pure_quanta.q_res(chips)';

PART_NAME
 R417 'Q_RES_0402LF-0,5%,1/16W,CHIP,CA':;

SECTION_NUMBER 1
 '@S9S_MB_2U_LIB.S9S_MB_2U(SCH_1):PAGE500_I255@PURE_QUANTA.Q_RES(CHIPS)':
 C_PATH='@s9s_mb_2u_lib.s9s_mb_2u(sch_1):page500_i255@pure_quanta.q_res(chips)';

PART_NAME
 R416 'Q_RES_0402LF-0,5%,1/16W,CHIP,CA':;

SECTION_NUMBER 1
 '@S9S_MB_2U_LIB.S9S_MB_2U(SCH_1):PAGE500_I253@PURE_QUANTA.Q_RES(CHIPS)':
 C_PATH='@s9s_mb_2u_lib.s9s_mb_2u(sch_1):page500_i253@pure_quanta.q_res(chips)';

PART_NAME
 R415 'Q_RES_0402LF-4.7K,1%,1/16W,CHIA':;

SECTION_NUMBER 1
 '@S9S_MB_2U_LIB.S9S_MB_2U(SCH_1):PAGE500_I145@PURE_QUANTA.Q_RES(CHIPS)':
 C_PATH='@s9s_mb_2u_lib.s9s_mb_2u(sch_1):page500_i145@pure_quanta.q_res(chips)';

PART_NAME
 R414 'Q_RES_0402LF-4.7K,1%,1/16W,EMPA':;

SECTION_NUMBER 1
 '@S9S_MB_2U_LIB.S9S_MB_2U(SCH_1):PAGE500_I144@PURE_QUANTA.Q_RES(CHIPS)':
 C_PATH='@s9s_mb_2u_lib.s9s_mb_2u(sch_1):page500_i144@pure_quanta.q_res(chips)';

PART_NAME
 R413 'Q_RES_0402LF-100K,1%,1/16W,CHIA':;

SECTION_NUMBER 1
 '@S9S_MB_2U_LIB.S9S_MB_2U(SCH_1):PAGE500_I362@PURE_QUANTA.Q_RES(CHIPS)':
 C_PATH='@s9s_mb_2u_lib.s9s_mb_2u(sch_1):page500_i362@pure_quanta.q_res(chips)';

PART_NAME
 R410 'Q_RES_0402LF-4.7K,1%,1/16W,CHIA':;

SECTION_NUMBER 1
 '@S9S_MB_2U_LIB.S9S_MB_2U(SCH_1):PAGE500_I148@PURE_QUANTA.Q_RES(CHIPS)':
 C_PATH='@s9s_mb_2u_lib.s9s_mb_2u(sch_1):page500_i148@pure_quanta.q_res(chips)';

PART_NAME
 R409 'Q_RES_0402LF-4.7K,1%,1/16W,EMPA':;

SECTION_NUMBER 1
 '@S9S_MB_2U_LIB.S9S_MB_2U(SCH_1):PAGE500_I147@PURE_QUANTA.Q_RES(CHIPS)':
 C_PATH='@s9s_mb_2u_lib.s9s_mb_2u(sch_1):page500_i147@pure_quanta.q_res(chips)';

PART_NAME
 J37 'SCONN168_623403212-SCONN168_6-A':;

SECTION_NUMBER 1
 '@S9S_MB_2U_LIB.S9S_MB_2U(SCH_1):PAGE500_I86@PURE_QUANTA.SCONN168_623403212(CHIPS)':
 C_PATH='@s9s_mb_2u_lib.s9s_mb_2u(sch_1):page500_i86@pure_quanta.sconn168_62340321~
2(chips)';

PART_NAME
 C1240 'Q_CAP_0402-0.1UF,25V,10%,X7R,CA':;

SECTION_NUMBER 1
 '@S9S_MB_2U_LIB.S9S_MB_2U(SCH_1):PAGE500_I335@PURE_QUANTA.Q_CAP(CHIPS)':
 C_PATH='@s9s_mb_2u_lib.s9s_mb_2u(sch_1):page500_i335@pure_quanta.q_cap(chips)';

PART_NAME
 C1239 'Q_CAP_0402-0.1UF,25V,10%,X7R,CA':;

SECTION_NUMBER 1
 '@S9S_MB_2U_LIB.S9S_MB_2U(SCH_1):PAGE500_I337@PURE_QUANTA.Q_CAP(CHIPS)':
 C_PATH='@s9s_mb_2u_lib.s9s_mb_2u(sch_1):page500_i337@pure_quanta.q_cap(chips)';

PART_NAME
 C1238 'Q_CAP_0402-0.1UF,25V,10%,X7R,CA':;

SECTION_NUMBER 1
 '@S9S_MB_2U_LIB.S9S_MB_2U(SCH_1):PAGE500_I338@PURE_QUANTA.Q_CAP(CHIPS)':
 C_PATH='@s9s_mb_2u_lib.s9s_mb_2u(sch_1):page500_i338@pure_quanta.q_cap(chips)';

PART_NAME
 C1237 'Q_CAP_0402-0.1UF,25V,10%,X7R,CA':;

SECTION_NUMBER 1
 '@S9S_MB_2U_LIB.S9S_MB_2U(SCH_1):PAGE500_I334@PURE_QUANTA.Q_CAP(CHIPS)':
 C_PATH='@s9s_mb_2u_lib.s9s_mb_2u(sch_1):page500_i334@pure_quanta.q_cap(chips)';

PART_NAME
 C1236 'Q_CAP_0402-0.1UF,25V,10%,X7R,CA':;

SECTION_NUMBER 1
 '@S9S_MB_2U_LIB.S9S_MB_2U(SCH_1):PAGE500_I322@PURE_QUANTA.Q_CAP(CHIPS)':
 C_PATH='@s9s_mb_2u_lib.s9s_mb_2u(sch_1):page500_i322@pure_quanta.q_cap(chips)';

PART_NAME
 C1235 'Q_CAP_0402-0.1UF,25V,10%,X7R,CA':;

SECTION_NUMBER 1
 '@S9S_MB_2U_LIB.S9S_MB_2U(SCH_1):PAGE500_I333@PURE_QUANTA.Q_CAP(CHIPS)':
 C_PATH='@s9s_mb_2u_lib.s9s_mb_2u(sch_1):page500_i333@pure_quanta.q_cap(chips)';

PART_NAME
 C1234 'Q_CAP_0402-0.1UF,25V,10%,X7R,CA':;

SECTION_NUMBER 1
 '@S9S_MB_2U_LIB.S9S_MB_2U(SCH_1):PAGE500_I332@PURE_QUANTA.Q_CAP(CHIPS)':
 C_PATH='@s9s_mb_2u_lib.s9s_mb_2u(sch_1):page500_i332@pure_quanta.q_cap(chips)';

PART_NAME
 C1233 'Q_CAP_0402-0.1UF,25V,10%,X7R,CA':;

SECTION_NUMBER 1
 '@S9S_MB_2U_LIB.S9S_MB_2U(SCH_1):PAGE500_I319@PURE_QUANTA.Q_CAP(CHIPS)':
 C_PATH='@s9s_mb_2u_lib.s9s_mb_2u(sch_1):page500_i319@pure_quanta.q_cap(chips)';

PART_NAME
 C1232 'Q_CAP_C0805-22UF,16V,20%,X6S,CA':;

SECTION_NUMBER 1
 '@S9S_MB_2U_LIB.S9S_MB_2U(SCH_1):PAGE500_I331@PURE_QUANTA.Q_CAP(CHIPS)':
 C_PATH='@s9s_mb_2u_lib.s9s_mb_2u(sch_1):page500_i331@pure_quanta.q_cap(chips)';

PART_NAME
 C1213 'Q_CAP_C0805-22UF,16V,20%,X6S,CA':;

SECTION_NUMBER 1
 '@S9S_MB_2U_LIB.S9S_MB_2U(SCH_1):PAGE500_I316@PURE_QUANTA.Q_CAP(CHIPS)':
 C_PATH='@s9s_mb_2u_lib.s9s_mb_2u(sch_1):page500_i316@pure_quanta.q_cap(chips)';

PART_NAME
 R1742 'Q_RES_0402LF-10K,1%,1/16W,EMPTA':;

SECTION_NUMBER 1
 '@S9S_MB_2U_LIB.S9S_MB_2U(SCH_1):PAGE547_I329@PURE_QUANTA.Q_RES(CHIPS)':
 C_PATH='@s9s_mb_2u_lib.s9s_mb_2u(sch_1):page547_i329@pure_quanta.q_res(chips)';

PART_NAME
 R1741 'Q_RES_0402LF-1K,1%,1/16W,CHIP,A':;

SECTION_NUMBER 1
 '@S9S_MB_2U_LIB.S9S_MB_2U(SCH_1):PAGE547_I330@PURE_QUANTA.Q_RES(CHIPS)':
 C_PATH='@s9s_mb_2u_lib.s9s_mb_2u(sch_1):page547_i330@pure_quanta.q_res(chips)';

PART_NAME
 R1660 'Q_RES_0402LF-10K,1%,1/16W,CHIPA':;

SECTION_NUMBER 1
 '@S9S_MB_2U_LIB.S9S_MB_2U(SCH_1):PAGE547_I328@PURE_QUANTA.Q_RES(CHIPS)':
 C_PATH='@s9s_mb_2u_lib.s9s_mb_2u(sch_1):page547_i328@pure_quanta.q_res(chips)';

PART_NAME
 R1639 'Q_RES_0402LF-10K,1%,1/16W,CHIPA':;

SECTION_NUMBER 1
 '@S9S_MB_2U_LIB.S9S_MB_2U(SCH_1):PAGE547_I322@PURE_QUANTA.Q_RES(CHIPS)':
 C_PATH='@s9s_mb_2u_lib.s9s_mb_2u(sch_1):page547_i322@pure_quanta.q_res(chips)';

PART_NAME
 R1558 'Q_RES_0402LF-10K,1%,1/16W,CHIPA':;

SECTION_NUMBER 1
 '@S9S_MB_2U_LIB.S9S_MB_2U(SCH_1):PAGE547_I318@PURE_QUANTA.Q_RES(CHIPS)':
 C_PATH='@s9s_mb_2u_lib.s9s_mb_2u(sch_1):page547_i318@pure_quanta.q_res(chips)';

PART_NAME
 R1557 'Q_RES_0402LF-10K,1%,1/16W,CHIPA':;

SECTION_NUMBER 1
 '@S9S_MB_2U_LIB.S9S_MB_2U(SCH_1):PAGE547_I316@PURE_QUANTA.Q_RES(CHIPS)':
 C_PATH='@s9s_mb_2u_lib.s9s_mb_2u(sch_1):page547_i316@pure_quanta.q_res(chips)';

PART_NAME
 R1552 'Q_RES_0402LF-10K,1%,1/16W,CHIPA':;

SECTION_NUMBER 1
 '@S9S_MB_2U_LIB.S9S_MB_2U(SCH_1):PAGE547_I317@PURE_QUANTA.Q_RES(CHIPS)':
 C_PATH='@s9s_mb_2u_lib.s9s_mb_2u(sch_1):page547_i317@pure_quanta.q_res(chips)';

PART_NAME
 R1495 'Q_RES_0402LF-10K,1%,1/16W,CHIPA':;

SECTION_NUMBER 1
 '@S9S_MB_2U_LIB.S9S_MB_2U(SCH_1):PAGE547_I286@PURE_QUANTA.Q_RES(CHIPS)':
 C_PATH='@s9s_mb_2u_lib.s9s_mb_2u(sch_1):page547_i286@pure_quanta.q_res(chips)';

PART_NAME
 R1494 'Q_RES_0402LF-1K,1%,1/16W,CHIP,A':;

SECTION_NUMBER 1
 '@S9S_MB_2U_LIB.S9S_MB_2U(SCH_1):PAGE547_I275@PURE_QUANTA.Q_RES(CHIPS)':
 C_PATH='@s9s_mb_2u_lib.s9s_mb_2u(sch_1):page547_i275@pure_quanta.q_res(chips)';

PART_NAME
 R1493 'Q_RES_0402LF-1K,1%,1/16W,EMPTYA':;

SECTION_NUMBER 1
 '@S9S_MB_2U_LIB.S9S_MB_2U(SCH_1):PAGE547_I287@PURE_QUANTA.Q_RES(CHIPS)':
 C_PATH='@s9s_mb_2u_lib.s9s_mb_2u(sch_1):page547_i287@pure_quanta.q_res(chips)';

PART_NAME
 R1492 'Q_RES_0402LF-10K,1%,1/16W,EMPTA':;

SECTION_NUMBER 1
 '@S9S_MB_2U_LIB.S9S_MB_2U(SCH_1):PAGE547_I272@PURE_QUANTA.Q_RES(CHIPS)':
 C_PATH='@s9s_mb_2u_lib.s9s_mb_2u(sch_1):page547_i272@pure_quanta.q_res(chips)';

PART_NAME
 R1491 'Q_RES_0402LF-1K,1%,1/16W,CHIP,A':;

SECTION_NUMBER 1
 '@S9S_MB_2U_LIB.S9S_MB_2U(SCH_1):PAGE547_I282@PURE_QUANTA.Q_RES(CHIPS)':
 C_PATH='@s9s_mb_2u_lib.s9s_mb_2u(sch_1):page547_i282@pure_quanta.q_res(chips)';

PART_NAME
 R1490 'Q_RES_0402LF-10K,1%,1/16W,CHIPA':;

SECTION_NUMBER 1
 '@S9S_MB_2U_LIB.S9S_MB_2U(SCH_1):PAGE547_I291@PURE_QUANTA.Q_RES(CHIPS)':
 C_PATH='@s9s_mb_2u_lib.s9s_mb_2u(sch_1):page547_i291@pure_quanta.q_res(chips)';

PART_NAME
 R1489 'Q_RES_0402LF-10K,1%,1/16W,CHIPA':;

SECTION_NUMBER 1
 '@S9S_MB_2U_LIB.S9S_MB_2U(SCH_1):PAGE547_I290@PURE_QUANTA.Q_RES(CHIPS)':
 C_PATH='@s9s_mb_2u_lib.s9s_mb_2u(sch_1):page547_i290@pure_quanta.q_res(chips)';

PART_NAME
 R1488 'Q_RES_0402LF-10K,1%,1/16W,CHIPA':;

SECTION_NUMBER 1
 '@S9S_MB_2U_LIB.S9S_MB_2U(SCH_1):PAGE547_I279@PURE_QUANTA.Q_RES(CHIPS)':
 C_PATH='@s9s_mb_2u_lib.s9s_mb_2u(sch_1):page547_i279@pure_quanta.q_res(chips)';

PART_NAME
 R1474 'Q_RES_0402LF-1K,1%,1/16W,EMPTYA':;

SECTION_NUMBER 1
 '@S9S_MB_2U_LIB.S9S_MB_2U(SCH_1):PAGE547_I262@PURE_QUANTA.Q_RES(CHIPS)':
 C_PATH='@s9s_mb_2u_lib.s9s_mb_2u(sch_1):page547_i262@pure_quanta.q_res(chips)';

PART_NAME
 R1473 'Q_RES_0402LF-1K,1%,1/16W,EMPTYA':;

SECTION_NUMBER 1
 '@S9S_MB_2U_LIB.S9S_MB_2U(SCH_1):PAGE547_I261@PURE_QUANTA.Q_RES(CHIPS)':
 C_PATH='@s9s_mb_2u_lib.s9s_mb_2u(sch_1):page547_i261@pure_quanta.q_res(chips)';

PART_NAME
 R1441 'Q_RES_0402LF-1K,1%,1/16W,CHIP,A':;

SECTION_NUMBER 1
 '@S9S_MB_2U_LIB.S9S_MB_2U(SCH_1):PAGE547_I235@PURE_QUANTA.Q_RES(CHIPS)':
 C_PATH='@s9s_mb_2u_lib.s9s_mb_2u(sch_1):page547_i235@pure_quanta.q_res(chips)';

PART_NAME
 R1440 'Q_RES_0402LF-10K,1%,1/16W,EMPTA':;

SECTION_NUMBER 1
 '@S9S_MB_2U_LIB.S9S_MB_2U(SCH_1):PAGE547_I231@PURE_QUANTA.Q_RES(CHIPS)':
 C_PATH='@s9s_mb_2u_lib.s9s_mb_2u(sch_1):page547_i231@pure_quanta.q_res(chips)';

PART_NAME
 R1439 'Q_RES_0402LF-10K,1%,1/16W,CHIPA':;

SECTION_NUMBER 1
 '@S9S_MB_2U_LIB.S9S_MB_2U(SCH_1):PAGE547_I229@PURE_QUANTA.Q_RES(CHIPS)':
 C_PATH='@s9s_mb_2u_lib.s9s_mb_2u(sch_1):page547_i229@pure_quanta.q_res(chips)';

PART_NAME
 R1438 'Q_RES_0402LF-10K,1%,1/16W,CHIPA':;

SECTION_NUMBER 1
 '@S9S_MB_2U_LIB.S9S_MB_2U(SCH_1):PAGE547_I226@PURE_QUANTA.Q_RES(CHIPS)':
 C_PATH='@s9s_mb_2u_lib.s9s_mb_2u(sch_1):page547_i226@pure_quanta.q_res(chips)';

PART_NAME
 R1437 'Q_RES_0402LF-10K,1%,1/16W,CHIPA':;

SECTION_NUMBER 1
 '@S9S_MB_2U_LIB.S9S_MB_2U(SCH_1):PAGE547_I224@PURE_QUANTA.Q_RES(CHIPS)':
 C_PATH='@s9s_mb_2u_lib.s9s_mb_2u(sch_1):page547_i224@pure_quanta.q_res(chips)';

PART_NAME
 R1436 'Q_RES_0402LF-10K,1%,1/16W,CHIPA':;

SECTION_NUMBER 1
 '@S9S_MB_2U_LIB.S9S_MB_2U(SCH_1):PAGE547_I278@PURE_QUANTA.Q_RES(CHIPS)':
 C_PATH='@s9s_mb_2u_lib.s9s_mb_2u(sch_1):page547_i278@pure_quanta.q_res(chips)';

PART_NAME
 R1435 'Q_RES_0402LF-10K,1%,1/16W,CHIPA':;

SECTION_NUMBER 1
 '@S9S_MB_2U_LIB.S9S_MB_2U(SCH_1):PAGE547_I221@PURE_QUANTA.Q_RES(CHIPS)':
 C_PATH='@s9s_mb_2u_lib.s9s_mb_2u(sch_1):page547_i221@pure_quanta.q_res(chips)';

PART_NAME
 R1434 'Q_RES_0402LF-10K,1%,1/16W,CHIPA':;

SECTION_NUMBER 1
 '@S9S_MB_2U_LIB.S9S_MB_2U(SCH_1):PAGE547_I216@PURE_QUANTA.Q_RES(CHIPS)':
 C_PATH='@s9s_mb_2u_lib.s9s_mb_2u(sch_1):page547_i216@pure_quanta.q_res(chips)';

PART_NAME
 R1433 'Q_RES_0402LF-150,1%,1/16W,CHIPA':;

SECTION_NUMBER 1
 '@S9S_MB_2U_LIB.S9S_MB_2U(SCH_1):PAGE547_I215@PURE_QUANTA.Q_RES(CHIPS)':
 C_PATH='@s9s_mb_2u_lib.s9s_mb_2u(sch_1):page547_i215@pure_quanta.q_res(chips)';

PART_NAME
 R1432 'Q_RES_0402LF-150,1%,1/16W,CHIPA':;

SECTION_NUMBER 1
 '@S9S_MB_2U_LIB.S9S_MB_2U(SCH_1):PAGE547_I214@PURE_QUANTA.Q_RES(CHIPS)':
 C_PATH='@s9s_mb_2u_lib.s9s_mb_2u(sch_1):page547_i214@pure_quanta.q_res(chips)';

PART_NAME
 R1431 'Q_RES_0402LF-150,1%,1/16W,CHIPA':;

SECTION_NUMBER 1
 '@S9S_MB_2U_LIB.S9S_MB_2U(SCH_1):PAGE547_I213@PURE_QUANTA.Q_RES(CHIPS)':
 C_PATH='@s9s_mb_2u_lib.s9s_mb_2u(sch_1):page547_i213@pure_quanta.q_res(chips)';

PART_NAME
 R1430 'Q_RES_0402LF-100,1%,1/16W,CHIPA':;

SECTION_NUMBER 1
 '@S9S_MB_2U_LIB.S9S_MB_2U(SCH_1):PAGE547_I203@PURE_QUANTA.Q_RES(CHIPS)':
 C_PATH='@s9s_mb_2u_lib.s9s_mb_2u(sch_1):page547_i203@pure_quanta.q_res(chips)';

PART_NAME
 R1429 'Q_RES_0402LF-100,1%,1/16W,CHIPA':;

SECTION_NUMBER 1
 '@S9S_MB_2U_LIB.S9S_MB_2U(SCH_1):PAGE547_I205@PURE_QUANTA.Q_RES(CHIPS)':
 C_PATH='@s9s_mb_2u_lib.s9s_mb_2u(sch_1):page547_i205@pure_quanta.q_res(chips)';

PART_NAME
 R1428 'Q_RES_0402LF-100,1%,1/16W,CHIPA':;

SECTION_NUMBER 1
 '@S9S_MB_2U_LIB.S9S_MB_2U(SCH_1):PAGE547_I202@PURE_QUANTA.Q_RES(CHIPS)':
 C_PATH='@s9s_mb_2u_lib.s9s_mb_2u(sch_1):page547_i202@pure_quanta.q_res(chips)';

PART_NAME
 R1427 'Q_RES_0402LF-100,1%,1/16W,CHIPA':;

SECTION_NUMBER 1
 '@S9S_MB_2U_LIB.S9S_MB_2U(SCH_1):PAGE547_I199@PURE_QUANTA.Q_RES(CHIPS)':
 C_PATH='@s9s_mb_2u_lib.s9s_mb_2u(sch_1):page547_i199@pure_quanta.q_res(chips)';

PART_NAME
 R1426 'Q_RES_0402LF-100,1%,1/16W,CHIPA':;

SECTION_NUMBER 1
 '@S9S_MB_2U_LIB.S9S_MB_2U(SCH_1):PAGE547_I198@PURE_QUANTA.Q_RES(CHIPS)':
 C_PATH='@s9s_mb_2u_lib.s9s_mb_2u(sch_1):page547_i198@pure_quanta.q_res(chips)';

PART_NAME
 R1425 'Q_RES_0402LF-100,1%,1/16W,CHIPA':;

SECTION_NUMBER 1
 '@S9S_MB_2U_LIB.S9S_MB_2U(SCH_1):PAGE547_I197@PURE_QUANTA.Q_RES(CHIPS)':
 C_PATH='@s9s_mb_2u_lib.s9s_mb_2u(sch_1):page547_i197@pure_quanta.q_res(chips)';

PART_NAME
 R1421 'Q_RES_0402LF-2K,1%,1/16W,CHIP,A':;

SECTION_NUMBER 1
 '@S9S_MB_2U_LIB.S9S_MB_2U(SCH_1):PAGE547_I155@PURE_QUANTA.Q_RES(CHIPS)':
 C_PATH='@s9s_mb_2u_lib.s9s_mb_2u(sch_1):page547_i155@pure_quanta.q_res(chips)';

PART_NAME
 R1420 'Q_RES_0402LF-2K,1%,1/16W,CHIP,A':;

SECTION_NUMBER 1
 '@S9S_MB_2U_LIB.S9S_MB_2U(SCH_1):PAGE547_I152@PURE_QUANTA.Q_RES(CHIPS)':
 C_PATH='@s9s_mb_2u_lib.s9s_mb_2u(sch_1):page547_i152@pure_quanta.q_res(chips)';

PART_NAME
 R1419 'Q_RES_0402LF-2K,1%,1/16W,CHIP,A':;

SECTION_NUMBER 1
 '@S9S_MB_2U_LIB.S9S_MB_2U(SCH_1):PAGE547_I153@PURE_QUANTA.Q_RES(CHIPS)':
 C_PATH='@s9s_mb_2u_lib.s9s_mb_2u(sch_1):page547_i153@pure_quanta.q_res(chips)';

PART_NAME
 R1418 'Q_RES_0402LF-2K,1%,1/16W,CHIP,A':;

SECTION_NUMBER 1
 '@S9S_MB_2U_LIB.S9S_MB_2U(SCH_1):PAGE547_I151@PURE_QUANTA.Q_RES(CHIPS)':
 C_PATH='@s9s_mb_2u_lib.s9s_mb_2u(sch_1):page547_i151@pure_quanta.q_res(chips)';

PART_NAME
 R1417 'Q_RES_0402LF-2K,1%,1/16W,CHIP,A':;

SECTION_NUMBER 1
 '@S9S_MB_2U_LIB.S9S_MB_2U(SCH_1):PAGE547_I150@PURE_QUANTA.Q_RES(CHIPS)':
 C_PATH='@s9s_mb_2u_lib.s9s_mb_2u(sch_1):page547_i150@pure_quanta.q_res(chips)';

PART_NAME
 R1416 'Q_RES_0402LF-2K,1%,1/16W,CHIP,A':;

SECTION_NUMBER 1
 '@S9S_MB_2U_LIB.S9S_MB_2U(SCH_1):PAGE547_I149@PURE_QUANTA.Q_RES(CHIPS)':
 C_PATH='@s9s_mb_2u_lib.s9s_mb_2u(sch_1):page547_i149@pure_quanta.q_res(chips)';

PART_NAME
 R1415 'Q_RES_0402LF-2K,1%,1/16W,CHIP,A':;

SECTION_NUMBER 1
 '@S9S_MB_2U_LIB.S9S_MB_2U(SCH_1):PAGE547_I148@PURE_QUANTA.Q_RES(CHIPS)':
 C_PATH='@s9s_mb_2u_lib.s9s_mb_2u(sch_1):page547_i148@pure_quanta.q_res(chips)';

PART_NAME
 R1414 'Q_RES_0402LF-2K,1%,1/16W,CHIP,A':;

SECTION_NUMBER 1
 '@S9S_MB_2U_LIB.S9S_MB_2U(SCH_1):PAGE547_I186@PURE_QUANTA.Q_RES(CHIPS)':
 C_PATH='@s9s_mb_2u_lib.s9s_mb_2u(sch_1):page547_i186@pure_quanta.q_res(chips)';

PART_NAME
 R1413 'Q_RES_0402LF-2K,1%,1/16W,CHIP,A':;

SECTION_NUMBER 1
 '@S9S_MB_2U_LIB.S9S_MB_2U(SCH_1):PAGE547_I188@PURE_QUANTA.Q_RES(CHIPS)':
 C_PATH='@s9s_mb_2u_lib.s9s_mb_2u(sch_1):page547_i188@pure_quanta.q_res(chips)';

PART_NAME
 R1412 'Q_RES_0402LF-2K,1%,1/16W,CHIP,A':;

SECTION_NUMBER 1
 '@S9S_MB_2U_LIB.S9S_MB_2U(SCH_1):PAGE547_I183@PURE_QUANTA.Q_RES(CHIPS)':
 C_PATH='@s9s_mb_2u_lib.s9s_mb_2u(sch_1):page547_i183@pure_quanta.q_res(chips)';

PART_NAME
 R1411 'Q_RES_0402LF-2K,1%,1/16W,CHIP,A':;

SECTION_NUMBER 1
 '@S9S_MB_2U_LIB.S9S_MB_2U(SCH_1):PAGE547_I184@PURE_QUANTA.Q_RES(CHIPS)':
 C_PATH='@s9s_mb_2u_lib.s9s_mb_2u(sch_1):page547_i184@pure_quanta.q_res(chips)';

PART_NAME
 R1410 'Q_RES_0402LF-2K,1%,1/16W,CHIP,A':;

SECTION_NUMBER 1
 '@S9S_MB_2U_LIB.S9S_MB_2U(SCH_1):PAGE547_I180@PURE_QUANTA.Q_RES(CHIPS)':
 C_PATH='@s9s_mb_2u_lib.s9s_mb_2u(sch_1):page547_i180@pure_quanta.q_res(chips)';

PART_NAME
 R1409 'Q_RES_0402LF-2K,1%,1/16W,CHIP,A':;

SECTION_NUMBER 1
 '@S9S_MB_2U_LIB.S9S_MB_2U(SCH_1):PAGE547_I179@PURE_QUANTA.Q_RES(CHIPS)':
 C_PATH='@s9s_mb_2u_lib.s9s_mb_2u(sch_1):page547_i179@pure_quanta.q_res(chips)';

PART_NAME
 R1408 'Q_RES_0402LF-2K,1%,1/16W,CHIP,A':;

SECTION_NUMBER 1
 '@S9S_MB_2U_LIB.S9S_MB_2U(SCH_1):PAGE547_I176@PURE_QUANTA.Q_RES(CHIPS)':
 C_PATH='@s9s_mb_2u_lib.s9s_mb_2u(sch_1):page547_i176@pure_quanta.q_res(chips)';

PART_NAME
 R1407 'Q_RES_0402LF-2K,1%,1/16W,CHIP,A':;

SECTION_NUMBER 1
 '@S9S_MB_2U_LIB.S9S_MB_2U(SCH_1):PAGE547_I175@PURE_QUANTA.Q_RES(CHIPS)':
 C_PATH='@s9s_mb_2u_lib.s9s_mb_2u(sch_1):page547_i175@pure_quanta.q_res(chips)';

PART_NAME
 R1406 'Q_RES_0402LF-2K,1%,1/16W,CHIP,A':;

SECTION_NUMBER 1
 '@S9S_MB_2U_LIB.S9S_MB_2U(SCH_1):PAGE547_I173@PURE_QUANTA.Q_RES(CHIPS)':
 C_PATH='@s9s_mb_2u_lib.s9s_mb_2u(sch_1):page547_i173@pure_quanta.q_res(chips)';

PART_NAME
 R1405 'Q_RES_0402LF-2K,1%,1/16W,CHIP,A':;

SECTION_NUMBER 1
 '@S9S_MB_2U_LIB.S9S_MB_2U(SCH_1):PAGE547_I170@PURE_QUANTA.Q_RES(CHIPS)':
 C_PATH='@s9s_mb_2u_lib.s9s_mb_2u(sch_1):page547_i170@pure_quanta.q_res(chips)';

PART_NAME
 R1404 'Q_RES_0402LF-2K,1%,1/16W,CHIP,A':;

SECTION_NUMBER 1
 '@S9S_MB_2U_LIB.S9S_MB_2U(SCH_1):PAGE547_I169@PURE_QUANTA.Q_RES(CHIPS)':
 C_PATH='@s9s_mb_2u_lib.s9s_mb_2u(sch_1):page547_i169@pure_quanta.q_res(chips)';

PART_NAME
 R1403 'Q_RES_0402LF-2K,1%,1/16W,CHIP,A':;

SECTION_NUMBER 1
 '@S9S_MB_2U_LIB.S9S_MB_2U(SCH_1):PAGE547_I127@PURE_QUANTA.Q_RES(CHIPS)':
 C_PATH='@s9s_mb_2u_lib.s9s_mb_2u(sch_1):page547_i127@pure_quanta.q_res(chips)';

PART_NAME
 R1402 'Q_RES_0402LF-2K,1%,1/16W,CHIP,A':;

SECTION_NUMBER 1
 '@S9S_MB_2U_LIB.S9S_MB_2U(SCH_1):PAGE547_I132@PURE_QUANTA.Q_RES(CHIPS)':
 C_PATH='@s9s_mb_2u_lib.s9s_mb_2u(sch_1):page547_i132@pure_quanta.q_res(chips)';

PART_NAME
 R1401 'Q_RES_0402LF-10K,1%,1/16W,CHIPA':;

SECTION_NUMBER 1
 '@S9S_MB_2U_LIB.S9S_MB_2U(SCH_1):PAGE547_I277@PURE_QUANTA.Q_RES(CHIPS)':
 C_PATH='@s9s_mb_2u_lib.s9s_mb_2u(sch_1):page547_i277@pure_quanta.q_res(chips)';

PART_NAME
 R1400 'Q_RES_0402LF-10K,1%,1/16W,CHIPA':;

SECTION_NUMBER 1
 '@S9S_MB_2U_LIB.S9S_MB_2U(SCH_1):PAGE547_I270@PURE_QUANTA.Q_RES(CHIPS)':
 C_PATH='@s9s_mb_2u_lib.s9s_mb_2u(sch_1):page547_i270@pure_quanta.q_res(chips)';

PART_NAME
 R1399 'Q_RES_0402LF-10K,1%,1/16W,CHIPA':;

SECTION_NUMBER 1
 '@S9S_MB_2U_LIB.S9S_MB_2U(SCH_1):PAGE547_I269@PURE_QUANTA.Q_RES(CHIPS)':
 C_PATH='@s9s_mb_2u_lib.s9s_mb_2u(sch_1):page547_i269@pure_quanta.q_res(chips)';

PART_NAME
 R1398 'Q_RES_0402LF-2K,1%,1/16W,CHIP,A':;

SECTION_NUMBER 1
 '@S9S_MB_2U_LIB.S9S_MB_2U(SCH_1):PAGE547_I139@PURE_QUANTA.Q_RES(CHIPS)':
 C_PATH='@s9s_mb_2u_lib.s9s_mb_2u(sch_1):page547_i139@pure_quanta.q_res(chips)';

PART_NAME
 R1389 'Q_RES_0402LF-2K,1%,1/16W,CHIP,A':;

SECTION_NUMBER 1
 '@S9S_MB_2U_LIB.S9S_MB_2U(SCH_1):PAGE547_I307@PURE_QUANTA.Q_RES(CHIPS)':
 C_PATH='@s9s_mb_2u_lib.s9s_mb_2u(sch_1):page547_i307@pure_quanta.q_res(chips)';

PART_NAME
 R1388 'Q_RES_0402LF-2K,1%,1/16W,CHIP,A':;

SECTION_NUMBER 1
 '@S9S_MB_2U_LIB.S9S_MB_2U(SCH_1):PAGE547_I305@PURE_QUANTA.Q_RES(CHIPS)':
 C_PATH='@s9s_mb_2u_lib.s9s_mb_2u(sch_1):page547_i305@pure_quanta.q_res(chips)';

PART_NAME
 R1330 'Q_RES_0402LF-2K,1%,1/16W,CHIP,A':;

SECTION_NUMBER 1
 '@S9S_MB_2U_LIB.S9S_MB_2U(SCH_1):PAGE547_I303@PURE_QUANTA.Q_RES(CHIPS)':
 C_PATH='@s9s_mb_2u_lib.s9s_mb_2u(sch_1):page547_i303@pure_quanta.q_res(chips)';

PART_NAME
 R1329 'Q_RES_0402LF-2K,1%,1/16W,CHIP,A':;

SECTION_NUMBER 1
 '@S9S_MB_2U_LIB.S9S_MB_2U(SCH_1):PAGE547_I301@PURE_QUANTA.Q_RES(CHIPS)':
 C_PATH='@s9s_mb_2u_lib.s9s_mb_2u(sch_1):page547_i301@pure_quanta.q_res(chips)';

PART_NAME
 R1328 'Q_RES_0402LF-2K,1%,1/16W,CHIP,A':;

SECTION_NUMBER 1
 '@S9S_MB_2U_LIB.S9S_MB_2U(SCH_1):PAGE547_I299@PURE_QUANTA.Q_RES(CHIPS)':
 C_PATH='@s9s_mb_2u_lib.s9s_mb_2u(sch_1):page547_i299@pure_quanta.q_res(chips)';

PART_NAME
 R1327 'Q_RES_0402LF-2K,1%,1/16W,CHIP,A':;

SECTION_NUMBER 1
 '@S9S_MB_2U_LIB.S9S_MB_2U(SCH_1):PAGE547_I298@PURE_QUANTA.Q_RES(CHIPS)':
 C_PATH='@s9s_mb_2u_lib.s9s_mb_2u(sch_1):page547_i298@pure_quanta.q_res(chips)';

PART_NAME
 R1326 'Q_RES_0402LF-2K,1%,1/16W,CHIP,A':;

SECTION_NUMBER 1
 '@S9S_MB_2U_LIB.S9S_MB_2U(SCH_1):PAGE547_I295@PURE_QUANTA.Q_RES(CHIPS)':
 C_PATH='@s9s_mb_2u_lib.s9s_mb_2u(sch_1):page547_i295@pure_quanta.q_res(chips)';

PART_NAME
 R1312 'Q_RES_0402LF-10K,1%,1/16W,CHIPA':;

SECTION_NUMBER 1
 '@S9S_MB_2U_LIB.S9S_MB_2U(SCH_1):PAGE547_I260@PURE_QUANTA.Q_RES(CHIPS)':
 C_PATH='@s9s_mb_2u_lib.s9s_mb_2u(sch_1):page547_i260@pure_quanta.q_res(chips)';

PART_NAME
 R1308 'Q_RES_0402LF-10K,1%,1/16W,CHIPA':;

SECTION_NUMBER 1
 '@S9S_MB_2U_LIB.S9S_MB_2U(SCH_1):PAGE547_I252@PURE_QUANTA.Q_RES(CHIPS)':
 C_PATH='@s9s_mb_2u_lib.s9s_mb_2u(sch_1):page547_i252@pure_quanta.q_res(chips)';

PART_NAME
 R1304 'Q_RES_0402LF-10K,1%,1/16W,EMPTA':;

SECTION_NUMBER 1
 '@S9S_MB_2U_LIB.S9S_MB_2U(SCH_1):PAGE547_I321@PURE_QUANTA.Q_RES(CHIPS)':
 C_PATH='@s9s_mb_2u_lib.s9s_mb_2u(sch_1):page547_i321@pure_quanta.q_res(chips)';

PART_NAME
 R1302 'Q_RES_0402LF-2K,1%,1/16W,CHIP,A':;

SECTION_NUMBER 1
 '@S9S_MB_2U_LIB.S9S_MB_2U(SCH_1):PAGE547_I294@PURE_QUANTA.Q_RES(CHIPS)':
 C_PATH='@s9s_mb_2u_lib.s9s_mb_2u(sch_1):page547_i294@pure_quanta.q_res(chips)';

PART_NAME
 R992 'Q_RES_0402LF-2K,1%,1/16W,CHIP,A':;

SECTION_NUMBER 1
 '@S9S_MB_2U_LIB.S9S_MB_2U(SCH_1):PAGE547_I141@PURE_QUANTA.Q_RES(CHIPS)':
 C_PATH='@s9s_mb_2u_lib.s9s_mb_2u(sch_1):page547_i141@pure_quanta.q_res(chips)';

PART_NAME
 R991 'Q_RES_0402LF-2K,1%,1/16W,CHIP,A':;

SECTION_NUMBER 1
 '@S9S_MB_2U_LIB.S9S_MB_2U(SCH_1):PAGE547_I144@PURE_QUANTA.Q_RES(CHIPS)':
 C_PATH='@s9s_mb_2u_lib.s9s_mb_2u(sch_1):page547_i144@pure_quanta.q_res(chips)';

PART_NAME
 R990 'Q_RES_0402LF-2K,1%,1/16W,CHIP,A':;

SECTION_NUMBER 1
 '@S9S_MB_2U_LIB.S9S_MB_2U(SCH_1):PAGE547_I131@PURE_QUANTA.Q_RES(CHIPS)':
 C_PATH='@s9s_mb_2u_lib.s9s_mb_2u(sch_1):page547_i131@pure_quanta.q_res(chips)';

PART_NAME
 R922 'Q_RES_0402LF-10K,1%,1/16W,CHIPA':;

SECTION_NUMBER 1
 '@S9S_MB_2U_LIB.S9S_MB_2U(SCH_1):PAGE547_I266@PURE_QUANTA.Q_RES(CHIPS)':
 C_PATH='@s9s_mb_2u_lib.s9s_mb_2u(sch_1):page547_i266@pure_quanta.q_res(chips)';

PART_NAME
 R921 'Q_RES_0402LF-10K,1%,1/16W,CHIPA':;

SECTION_NUMBER 1
 '@S9S_MB_2U_LIB.S9S_MB_2U(SCH_1):PAGE547_I265@PURE_QUANTA.Q_RES(CHIPS)':
 C_PATH='@s9s_mb_2u_lib.s9s_mb_2u(sch_1):page547_i265@pure_quanta.q_res(chips)';

PART_NAME
 R736 'Q_RES_0402LF-1K,1%,1/16W,EMPTYA':;

SECTION_NUMBER 1
 '@S9S_MB_2U_LIB.S9S_MB_2U(SCH_1):PAGE547_I125@PURE_QUANTA.Q_RES(CHIPS)':
 C_PATH='@s9s_mb_2u_lib.s9s_mb_2u(sch_1):page547_i125@pure_quanta.q_res(chips)';

PART_NAME
 R735 'Q_RES_0402LF-10K,1%,1/16W,CHIPA':;

SECTION_NUMBER 1
 '@S9S_MB_2U_LIB.S9S_MB_2U(SCH_1):PAGE547_I123@PURE_QUANTA.Q_RES(CHIPS)':
 C_PATH='@s9s_mb_2u_lib.s9s_mb_2u(sch_1):page547_i123@pure_quanta.q_res(chips)';

PART_NAME
 R547 'Q_RES_0402LF-1K,1%,1/16W,CHIP,A':;

SECTION_NUMBER 1
 '@S9S_MB_2U_LIB.S9S_MB_2U(SCH_1):PAGE547_I313@PURE_QUANTA.Q_RES(CHIPS)':
 C_PATH='@s9s_mb_2u_lib.s9s_mb_2u(sch_1):page547_i313@pure_quanta.q_res(chips)';

PART_NAME
 R546 'Q_RES_0402LF-1K,1%,1/16W,CHIP,A':;

SECTION_NUMBER 1
 '@S9S_MB_2U_LIB.S9S_MB_2U(SCH_1):PAGE547_I311@PURE_QUANTA.Q_RES(CHIPS)':
 C_PATH='@s9s_mb_2u_lib.s9s_mb_2u(sch_1):page547_i311@pure_quanta.q_res(chips)';

PART_NAME
 R397 'Q_RES_0402LF-10K,1%,1/16W,CHIPA':;

SECTION_NUMBER 1
 '@S9S_MB_2U_LIB.S9S_MB_2U(SCH_1):PAGE547_I324@PURE_QUANTA.Q_RES(CHIPS)':
 C_PATH='@s9s_mb_2u_lib.s9s_mb_2u(sch_1):page547_i324@pure_quanta.q_res(chips)';

PART_NAME
 R393 'Q_RES_0402LF-1K,1%,1/16W,EMPTYA':;

SECTION_NUMBER 1
 '@S9S_MB_2U_LIB.S9S_MB_2U(SCH_1):PAGE547_I325@PURE_QUANTA.Q_RES(CHIPS)':
 C_PATH='@s9s_mb_2u_lib.s9s_mb_2u(sch_1):page547_i325@pure_quanta.q_res(chips)';

PART_NAME
 R141 'Q_RES_0402LF-10K,1%,1/16W,EMPTA':;

SECTION_NUMBER 1
 '@S9S_MB_2U_LIB.S9S_MB_2U(SCH_1):PAGE547_I255@PURE_QUANTA.Q_RES(CHIPS)':
 C_PATH='@s9s_mb_2u_lib.s9s_mb_2u(sch_1):page547_i255@pure_quanta.q_res(chips)';

PART_NAME
 R140 'Q_RES_0402LF-10K,1%,1/16W,EMPTA':;

SECTION_NUMBER 1
 '@S9S_MB_2U_LIB.S9S_MB_2U(SCH_1):PAGE547_I254@PURE_QUANTA.Q_RES(CHIPS)':
 C_PATH='@s9s_mb_2u_lib.s9s_mb_2u(sch_1):page547_i254@pure_quanta.q_res(chips)';

PART_NAME
 R139 'Q_RES_0402LF-10K,1%,1/16W,CHIPA':;

SECTION_NUMBER 1
 '@S9S_MB_2U_LIB.S9S_MB_2U(SCH_1):PAGE547_I249@PURE_QUANTA.Q_RES(CHIPS)':
 C_PATH='@s9s_mb_2u_lib.s9s_mb_2u(sch_1):page547_i249@pure_quanta.q_res(chips)';

PART_NAME
 C1211 'Q_CAP_0402-100PF,50V,5%,X7R,CHA':;

SECTION_NUMBER 1
 '@S9S_MB_2U_LIB.S9S_MB_2U(SCH_1):PAGE547_I240@PURE_QUANTA.Q_CAP(CHIPS)':
 C_PATH='@s9s_mb_2u_lib.s9s_mb_2u(sch_1):page547_i240@pure_quanta.q_cap(chips)';

PART_NAME
 C1209 'Q_CAP_0402-100PF,50V,5%,X7R,CHA':;

SECTION_NUMBER 1
 '@S9S_MB_2U_LIB.S9S_MB_2U(SCH_1):PAGE547_I236@PURE_QUANTA.Q_CAP(CHIPS)':
 C_PATH='@s9s_mb_2u_lib.s9s_mb_2u(sch_1):page547_i236@pure_quanta.q_cap(chips)';

PART_NAME
 R1852 'Q_RES_0402LF-0,5%,1/16W,CHIP,CA':;

SECTION_NUMBER 1
 '@S9S_MB_2U_LIB.S9S_MB_2U(SCH_1):PAGE512_I318@PURE_QUANTA.Q_RES(CHIPS)':
 C_PATH='@s9s_mb_2u_lib.s9s_mb_2u(sch_1):page512_i318@pure_quanta.q_res(chips)';

PART_NAME
 R1638 'Q_RES_0402LF-4.7K,5%,1/16W,EMPA':;

SECTION_NUMBER 1
 '@S9S_MB_2U_LIB.S9S_MB_2U(SCH_1):PAGE512_I280@PURE_QUANTA.Q_RES(CHIPS)':
 C_PATH='@s9s_mb_2u_lib.s9s_mb_2u(sch_1):page512_i280@pure_quanta.q_res(chips)';

PART_NAME
 R1637 'Q_RES_0402LF-4.7K,5%,1/16W,EMPA':;

SECTION_NUMBER 1
 '@S9S_MB_2U_LIB.S9S_MB_2U(SCH_1):PAGE512_I281@PURE_QUANTA.Q_RES(CHIPS)':
 C_PATH='@s9s_mb_2u_lib.s9s_mb_2u(sch_1):page512_i281@pure_quanta.q_res(chips)';

PART_NAME
 R1636 'Q_RES_0402LF-4.7K,5%,1/16W,EMPA':;

SECTION_NUMBER 1
 '@S9S_MB_2U_LIB.S9S_MB_2U(SCH_1):PAGE512_I282@PURE_QUANTA.Q_RES(CHIPS)':
 C_PATH='@s9s_mb_2u_lib.s9s_mb_2u(sch_1):page512_i282@pure_quanta.q_res(chips)';

PART_NAME
 R1635 'Q_RES_0402LF-4.7K,5%,1/16W,EMPA':;

SECTION_NUMBER 1
 '@S9S_MB_2U_LIB.S9S_MB_2U(SCH_1):PAGE512_I283@PURE_QUANTA.Q_RES(CHIPS)':
 C_PATH='@s9s_mb_2u_lib.s9s_mb_2u(sch_1):page512_i283@pure_quanta.q_res(chips)';

PART_NAME
 R1634 'Q_RES_0402LF-4.7K,5%,1/16W,EMPA':;

SECTION_NUMBER 1
 '@S9S_MB_2U_LIB.S9S_MB_2U(SCH_1):PAGE512_I284@PURE_QUANTA.Q_RES(CHIPS)':
 C_PATH='@s9s_mb_2u_lib.s9s_mb_2u(sch_1):page512_i284@pure_quanta.q_res(chips)';

PART_NAME
 R1633 'Q_RES_0402LF-100,1%,1/16W,CHIPA':;

SECTION_NUMBER 1
 '@S9S_MB_2U_LIB.S9S_MB_2U(SCH_1):PAGE512_I294@PURE_QUANTA.Q_RES(CHIPS)':
 C_PATH='@s9s_mb_2u_lib.s9s_mb_2u(sch_1):page512_i294@pure_quanta.q_res(chips)';

PART_NAME
 R1632 'Q_RES_0402LF-10K,5%,1/16W,CHIPA':;

SECTION_NUMBER 1
 '@S9S_MB_2U_LIB.S9S_MB_2U(SCH_1):PAGE512_I297@PURE_QUANTA.Q_RES(CHIPS)':
 C_PATH='@s9s_mb_2u_lib.s9s_mb_2u(sch_1):page512_i297@pure_quanta.q_res(chips)';

PART_NAME
 R1631 'Q_RES_0402LF-0,5%,1/16W,CHIP,CA':;

SECTION_NUMBER 1
 '@S9S_MB_2U_LIB.S9S_MB_2U(SCH_1):PAGE512_I303@PURE_QUANTA.Q_RES(CHIPS)':
 C_PATH='@s9s_mb_2u_lib.s9s_mb_2u(sch_1):page512_i303@pure_quanta.q_res(chips)';

PART_NAME
 R1630 'Q_RES_0402LF-10K,5%,1/16W,EMPTA':;

SECTION_NUMBER 1
 '@S9S_MB_2U_LIB.S9S_MB_2U(SCH_1):PAGE512_I301@PURE_QUANTA.Q_RES(CHIPS)':
 C_PATH='@s9s_mb_2u_lib.s9s_mb_2u(sch_1):page512_i301@pure_quanta.q_res(chips)';

PART_NAME
 R1517 'Q_RES_0402LF-10K,1%,1/16W,CHIPA':;

SECTION_NUMBER 1
 '@S9S_MB_2U_LIB.S9S_MB_2U(SCH_1):PAGE512_I332@PURE_QUANTA.Q_RES(CHIPS)':
 C_PATH='@s9s_mb_2u_lib.s9s_mb_2u(sch_1):page512_i332@pure_quanta.q_res(chips)';

PART_NAME
 R959 'Q_RES_0402LF-33.2,1%,1/16W,CHIA':;

SECTION_NUMBER 1
 '@S9S_MB_2U_LIB.S9S_MB_2U(SCH_1):PAGE512_I326@PURE_QUANTA.Q_RES(CHIPS)':
 C_PATH='@s9s_mb_2u_lib.s9s_mb_2u(sch_1):page512_i326@pure_quanta.q_res(chips)';

PART_NAME
 R958 'Q_RES_0402LF-33.2,1%,1/16W,CHIA':;

SECTION_NUMBER 1
 '@S9S_MB_2U_LIB.S9S_MB_2U(SCH_1):PAGE512_I322@PURE_QUANTA.Q_RES(CHIPS)':
 C_PATH='@s9s_mb_2u_lib.s9s_mb_2u(sch_1):page512_i322@pure_quanta.q_res(chips)';

PART_NAME
 R505 'Q_RES_0402LF-4.7K,1%,1/16W,CHIA':;

SECTION_NUMBER 1
 '@S9S_MB_2U_LIB.S9S_MB_2U(SCH_1):PAGE512_I329@PURE_QUANTA.Q_RES(CHIPS)':
 C_PATH='@s9s_mb_2u_lib.s9s_mb_2u(sch_1):page512_i329@pure_quanta.q_res(chips)';

PART_NAME
 J52 'CONN4_G87MP042502THR-CONN4_G87A':;

SECTION_NUMBER 1
 '@S9S_MB_2U_LIB.S9S_MB_2U(SCH_1):PAGE512_I314@PURE_QUANTA.CONN4_G87MP042502THR(CHIPS)':
 C_PATH='@s9s_mb_2u_lib.s9s_mb_2u(sch_1):page512_i314@pure_quanta.conn4_g87mp04250~
2thr(chips)';

PART_NAME
 J40 'SCONN140_123322056-SCONN140_1-A':;

SECTION_NUMBER 1
 '@S9S_MB_2U_LIB.S9S_MB_2U(SCH_1):PAGE512_I25@PURE_QUANTA.SCONN140_123322056(CHIPS)':
 C_PATH='@s9s_mb_2u_lib.s9s_mb_2u(sch_1):page512_i25@pure_quanta.sconn140_12332205~
6(chips)';

PART_NAME
 C1225 'Q_CAP_0402-0.1UF,25V,10%,X7R,CA':;

SECTION_NUMBER 1
 '@S9S_MB_2U_LIB.S9S_MB_2U(SCH_1):PAGE512_I306@PURE_QUANTA.Q_CAP(CHIPS)':
 C_PATH='@s9s_mb_2u_lib.s9s_mb_2u(sch_1):page512_i306@pure_quanta.q_cap(chips)';

PART_NAME
 C1224 'Q_CAP_0402-0.1UF,25V,10%,X7R,CA':;

SECTION_NUMBER 1
 '@S9S_MB_2U_LIB.S9S_MB_2U(SCH_1):PAGE512_I309@PURE_QUANTA.Q_CAP(CHIPS)':
 C_PATH='@s9s_mb_2u_lib.s9s_mb_2u(sch_1):page512_i309@pure_quanta.q_cap(chips)';

PART_NAME
 C1199 'Q_CAP_0402-0.1UF,25V,10%,X7R,CA':;

SECTION_NUMBER 1
 '@S9S_MB_2U_LIB.S9S_MB_2U(SCH_1):PAGE512_I270@PURE_QUANTA.Q_CAP(CHIPS)':
 C_PATH='@s9s_mb_2u_lib.s9s_mb_2u(sch_1):page512_i270@pure_quanta.q_cap(chips)';

PART_NAME
 C1196 'Q_CAPP_RDLLF-100UF,16V,20%,OSCA':;

SECTION_NUMBER 1
 '@S9S_MB_2U_LIB.S9S_MB_2U(SCH_1):PAGE512_I269@PURE_QUANTA.Q_CAPP(CHIPS)':
 C_PATH='@s9s_mb_2u_lib.s9s_mb_2u(sch_1):page512_i269@pure_quanta.q_capp(chips)';

PART_NAME
 C1195 'Q_CAP_0402-0.1UF,25V,10%,X7R,CA':;

SECTION_NUMBER 1
 '@S9S_MB_2U_LIB.S9S_MB_2U(SCH_1):PAGE512_I273@PURE_QUANTA.Q_CAP(CHIPS)':
 C_PATH='@s9s_mb_2u_lib.s9s_mb_2u(sch_1):page512_i273@pure_quanta.q_cap(chips)';

PART_NAME
 C1194 'Q_CAPP_SMLF-220UF,6.3V,20%,OSCA':;

SECTION_NUMBER 1
 '@S9S_MB_2U_LIB.S9S_MB_2U(SCH_1):PAGE512_I268@PURE_QUANTA.Q_CAPP(CHIPS)':
 C_PATH='@s9s_mb_2u_lib.s9s_mb_2u(sch_1):page512_i268@pure_quanta.q_capp(chips)';

PART_NAME
 R1851 'Q_RES_0402LF-0,5%,1/16W,CHIP,CA':;

SECTION_NUMBER 1
 '@S9S_MB_2U_LIB.S9S_MB_2U(SCH_1):PAGE511_I318@PURE_QUANTA.Q_RES(CHIPS)':
 C_PATH='@s9s_mb_2u_lib.s9s_mb_2u(sch_1):page511_i318@pure_quanta.q_res(chips)';

PART_NAME
 R1629 'Q_RES_0402LF-4.7K,5%,1/16W,EMPA':;

SECTION_NUMBER 1
 '@S9S_MB_2U_LIB.S9S_MB_2U(SCH_1):PAGE511_I278@PURE_QUANTA.Q_RES(CHIPS)':
 C_PATH='@s9s_mb_2u_lib.s9s_mb_2u(sch_1):page511_i278@pure_quanta.q_res(chips)';

PART_NAME
 R1628 'Q_RES_0402LF-4.7K,5%,1/16W,EMPA':;

SECTION_NUMBER 1
 '@S9S_MB_2U_LIB.S9S_MB_2U(SCH_1):PAGE511_I277@PURE_QUANTA.Q_RES(CHIPS)':
 C_PATH='@s9s_mb_2u_lib.s9s_mb_2u(sch_1):page511_i277@pure_quanta.q_res(chips)';

PART_NAME
 R1627 'Q_RES_0402LF-4.7K,5%,1/16W,EMPA':;

SECTION_NUMBER 1
 '@S9S_MB_2U_LIB.S9S_MB_2U(SCH_1):PAGE511_I276@PURE_QUANTA.Q_RES(CHIPS)':
 C_PATH='@s9s_mb_2u_lib.s9s_mb_2u(sch_1):page511_i276@pure_quanta.q_res(chips)';

PART_NAME
 R1626 'Q_RES_0402LF-4.7K,5%,1/16W,EMPA':;

SECTION_NUMBER 1
 '@S9S_MB_2U_LIB.S9S_MB_2U(SCH_1):PAGE511_I275@PURE_QUANTA.Q_RES(CHIPS)':
 C_PATH='@s9s_mb_2u_lib.s9s_mb_2u(sch_1):page511_i275@pure_quanta.q_res(chips)';

PART_NAME
 R1625 'Q_RES_0402LF-4.7K,5%,1/16W,EMPA':;

SECTION_NUMBER 1
 '@S9S_MB_2U_LIB.S9S_MB_2U(SCH_1):PAGE511_I274@PURE_QUANTA.Q_RES(CHIPS)':
 C_PATH='@s9s_mb_2u_lib.s9s_mb_2u(sch_1):page511_i274@pure_quanta.q_res(chips)';

PART_NAME
 R1624 'Q_RES_0402LF-100,1%,1/16W,CHIPA':;

SECTION_NUMBER 1
 '@S9S_MB_2U_LIB.S9S_MB_2U(SCH_1):PAGE511_I281@PURE_QUANTA.Q_RES(CHIPS)':
 C_PATH='@s9s_mb_2u_lib.s9s_mb_2u(sch_1):page511_i281@pure_quanta.q_res(chips)';

PART_NAME
 R1623 'Q_RES_0402LF-10K,5%,1/16W,CHIPA':;

SECTION_NUMBER 1
 '@S9S_MB_2U_LIB.S9S_MB_2U(SCH_1):PAGE511_I284@PURE_QUANTA.Q_RES(CHIPS)':
 C_PATH='@s9s_mb_2u_lib.s9s_mb_2u(sch_1):page511_i284@pure_quanta.q_res(chips)';

PART_NAME
 R1622 'Q_RES_0402LF-0,5%,1/16W,CHIP,CA':;

SECTION_NUMBER 1
 '@S9S_MB_2U_LIB.S9S_MB_2U(SCH_1):PAGE511_I291@PURE_QUANTA.Q_RES(CHIPS)':
 C_PATH='@s9s_mb_2u_lib.s9s_mb_2u(sch_1):page511_i291@pure_quanta.q_res(chips)';

PART_NAME
 R1621 'Q_RES_0402LF-10K,5%,1/16W,CHIPA':;

SECTION_NUMBER 1
 '@S9S_MB_2U_LIB.S9S_MB_2U(SCH_1):PAGE511_I292@PURE_QUANTA.Q_RES(CHIPS)':
 C_PATH='@s9s_mb_2u_lib.s9s_mb_2u(sch_1):page511_i292@pure_quanta.q_res(chips)';

PART_NAME
 R957 'Q_RES_0402LF-33.2,1%,1/16W,CHIA':;

SECTION_NUMBER 1
 '@S9S_MB_2U_LIB.S9S_MB_2U(SCH_1):PAGE511_I326@PURE_QUANTA.Q_RES(CHIPS)':
 C_PATH='@s9s_mb_2u_lib.s9s_mb_2u(sch_1):page511_i326@pure_quanta.q_res(chips)';

PART_NAME
 R956 'Q_RES_0402LF-33.2,1%,1/16W,CHIA':;

SECTION_NUMBER 1
 '@S9S_MB_2U_LIB.S9S_MB_2U(SCH_1):PAGE511_I319@PURE_QUANTA.Q_RES(CHIPS)':
 C_PATH='@s9s_mb_2u_lib.s9s_mb_2u(sch_1):page511_i319@pure_quanta.q_res(chips)';

PART_NAME
 R493 'Q_RES_0402LF-4.7K,1%,1/16W,CHIA':;

SECTION_NUMBER 1
 '@S9S_MB_2U_LIB.S9S_MB_2U(SCH_1):PAGE511_I328@PURE_QUANTA.Q_RES(CHIPS)':
 C_PATH='@s9s_mb_2u_lib.s9s_mb_2u(sch_1):page511_i328@pure_quanta.q_res(chips)';

PART_NAME
 R443 'Q_RES_0402LF-10K,1%,1/16W,CHIPA':;

SECTION_NUMBER 1
 '@S9S_MB_2U_LIB.S9S_MB_2U(SCH_1):PAGE511_I332@PURE_QUANTA.Q_RES(CHIPS)':
 C_PATH='@s9s_mb_2u_lib.s9s_mb_2u(sch_1):page511_i332@pure_quanta.q_res(chips)';

PART_NAME
 J51 'CONN4_G87MP042502THR-CONN4_G87A':;

SECTION_NUMBER 1
 '@S9S_MB_2U_LIB.S9S_MB_2U(SCH_1):PAGE511_I315@PURE_QUANTA.CONN4_G87MP042502THR(CHIPS)':
 C_PATH='@s9s_mb_2u_lib.s9s_mb_2u(sch_1):page511_i315@pure_quanta.conn4_g87mp04250~
2thr(chips)';

PART_NAME
 J39 'SCONN140_123322056-SCONN140_1-A':;

SECTION_NUMBER 1
 '@S9S_MB_2U_LIB.S9S_MB_2U(SCH_1):PAGE511_I148@PURE_QUANTA.SCONN140_123322056(CHIPS)':
 C_PATH='@s9s_mb_2u_lib.s9s_mb_2u(sch_1):page511_i148@pure_quanta.sconn140_1233220~
56(chips)';

PART_NAME
 C1223 'Q_CAP_0402-0.1UF,25V,10%,X7R,CA':;

SECTION_NUMBER 1
 '@S9S_MB_2U_LIB.S9S_MB_2U(SCH_1):PAGE511_I298@PURE_QUANTA.Q_CAP(CHIPS)':
 C_PATH='@s9s_mb_2u_lib.s9s_mb_2u(sch_1):page511_i298@pure_quanta.q_cap(chips)';

PART_NAME
 C1222 'Q_CAP_0402-0.1UF,25V,10%,X7R,CA':;

SECTION_NUMBER 1
 '@S9S_MB_2U_LIB.S9S_MB_2U(SCH_1):PAGE511_I297@PURE_QUANTA.Q_CAP(CHIPS)':
 C_PATH='@s9s_mb_2u_lib.s9s_mb_2u(sch_1):page511_i297@pure_quanta.q_cap(chips)';

PART_NAME
 C1193 'Q_CAP_0402-0.1UF,25V,10%,X7R,CA':;

SECTION_NUMBER 1
 '@S9S_MB_2U_LIB.S9S_MB_2U(SCH_1):PAGE511_I251@PURE_QUANTA.Q_CAP(CHIPS)':
 C_PATH='@s9s_mb_2u_lib.s9s_mb_2u(sch_1):page511_i251@pure_quanta.q_cap(chips)';

PART_NAME
 C1188 'Q_CAPP_RDLLF-100UF,16V,20%,OSCA':;

SECTION_NUMBER 1
 '@S9S_MB_2U_LIB.S9S_MB_2U(SCH_1):PAGE511_I249@PURE_QUANTA.Q_CAPP(CHIPS)':
 C_PATH='@s9s_mb_2u_lib.s9s_mb_2u(sch_1):page511_i249@pure_quanta.q_capp(chips)';

PART_NAME
 C1180 'Q_CAP_0402-0.1UF,25V,10%,X7R,CA':;

SECTION_NUMBER 1
 '@S9S_MB_2U_LIB.S9S_MB_2U(SCH_1):PAGE511_I248@PURE_QUANTA.Q_CAP(CHIPS)':
 C_PATH='@s9s_mb_2u_lib.s9s_mb_2u(sch_1):page511_i248@pure_quanta.q_cap(chips)';

PART_NAME
 C1179 'Q_CAPP_SMLF-220UF,6.3V,20%,OSCA':;

SECTION_NUMBER 1
 '@S9S_MB_2U_LIB.S9S_MB_2U(SCH_1):PAGE511_I245@PURE_QUANTA.Q_CAPP(CHIPS)':
 C_PATH='@s9s_mb_2u_lib.s9s_mb_2u(sch_1):page511_i245@pure_quanta.q_capp(chips)';

PART_NAME
 R1464 'Q_RES_0402LF-0,5%,1/16W,CHIP,CA':;

SECTION_NUMBER 1
 '@S9S_MB_2U_LIB.S9S_MB_2U(SCH_1):PAGE525_I144@PURE_QUANTA.Q_RES(CHIPS)':
 C_PATH='@s9s_mb_2u_lib.s9s_mb_2u(sch_1):page525_i144@pure_quanta.q_res(chips)';

PART_NAME
 R1463 'Q_RES_0402LF-0,5%,1/16W,CHIP,CA':;

SECTION_NUMBER 1
 '@S9S_MB_2U_LIB.S9S_MB_2U(SCH_1):PAGE525_I129@PURE_QUANTA.Q_RES(CHIPS)':
 C_PATH='@s9s_mb_2u_lib.s9s_mb_2u(sch_1):page525_i129@pure_quanta.q_res(chips)';

PART_NAME
 L10 'Q_INDUCTOR_SMLF-BLM18PG121SN1DA':;

SECTION_NUMBER 1
 '@S9S_MB_2U_LIB.S9S_MB_2U(SCH_1):PAGE525_I145@PURE_QUANTA.Q_INDUCTOR(CHIPS)':
 C_PATH='@s9s_mb_2u_lib.s9s_mb_2u(sch_1):page525_i145@pure_quanta.q_inductor(chips~
)';

PART_NAME
 L2 'Q_INDUCTOR_SMLF-BLM18PG121SN1DA':;

SECTION_NUMBER 1
 '@S9S_MB_2U_LIB.S9S_MB_2U(SCH_1):PAGE525_I135@PURE_QUANTA.Q_INDUCTOR(CHIPS)':
 C_PATH='@s9s_mb_2u_lib.s9s_mb_2u(sch_1):page525_i135@pure_quanta.q_inductor(chips~
)';

PART_NAME
 C1273 'Q_CAP_0805-47UF,4V,20%,X6S,CH6A':;

SECTION_NUMBER 1
 '@S9S_MB_2U_LIB.S9S_MB_2U(SCH_1):PAGE525_I116@PURE_QUANTA.Q_CAP(CHIPS)':
 C_PATH='@s9s_mb_2u_lib.s9s_mb_2u(sch_1):page525_i116@pure_quanta.q_cap(chips)';

PART_NAME
 C1272 'Q_CAP_0805-47UF,4V,20%,X6S,CH6A':;

SECTION_NUMBER 1
 '@S9S_MB_2U_LIB.S9S_MB_2U(SCH_1):PAGE525_I100@PURE_QUANTA.Q_CAP(CHIPS)':
 C_PATH='@s9s_mb_2u_lib.s9s_mb_2u(sch_1):page525_i100@pure_quanta.q_cap(chips)';

PART_NAME
 C1266 'Q_CAP_C0402-10UF,6.3V,20%,X6S,A':;

SECTION_NUMBER 1
 '@S9S_MB_2U_LIB.S9S_MB_2U(SCH_1):PAGE525_I127@PURE_QUANTA.Q_CAP(CHIPS)':
 C_PATH='@s9s_mb_2u_lib.s9s_mb_2u(sch_1):page525_i127@pure_quanta.q_cap(chips)';

PART_NAME
 C1265 'Q_CAP_0402-1UF,6.3V,10%,EMPTY,A':;

SECTION_NUMBER 1
 '@S9S_MB_2U_LIB.S9S_MB_2U(SCH_1):PAGE525_I140@PURE_QUANTA.Q_CAP(CHIPS)':
 C_PATH='@s9s_mb_2u_lib.s9s_mb_2u(sch_1):page525_i140@pure_quanta.q_cap(chips)';

PART_NAME
 C1264 'Q_CAP_0402-1UF,6.3V,10%,EMPTY,A':;

SECTION_NUMBER 1
 '@S9S_MB_2U_LIB.S9S_MB_2U(SCH_1):PAGE525_I133@PURE_QUANTA.Q_CAP(CHIPS)':
 C_PATH='@s9s_mb_2u_lib.s9s_mb_2u(sch_1):page525_i133@pure_quanta.q_cap(chips)';

PART_NAME
 C1263 'Q_CAP_C0402-10UF,6.3V,20%,X6S,A':;

SECTION_NUMBER 1
 '@S9S_MB_2U_LIB.S9S_MB_2U(SCH_1):PAGE525_I119@PURE_QUANTA.Q_CAP(CHIPS)':
 C_PATH='@s9s_mb_2u_lib.s9s_mb_2u(sch_1):page525_i119@pure_quanta.q_cap(chips)';

PART_NAME
 C1262 'Q_CAP_C0402-10UF,6.3V,20%,X6S,A':;

SECTION_NUMBER 1
 '@S9S_MB_2U_LIB.S9S_MB_2U(SCH_1):PAGE525_I104@PURE_QUANTA.Q_CAP(CHIPS)':
 C_PATH='@s9s_mb_2u_lib.s9s_mb_2u(sch_1):page525_i104@pure_quanta.q_cap(chips)';

PART_NAME
 C1261 'Q_CAP_C0603-10UF,6.3V,20%,X6S,A':;

SECTION_NUMBER 1
 '@S9S_MB_2U_LIB.S9S_MB_2U(SCH_1):PAGE525_I142@PURE_QUANTA.Q_CAP(CHIPS)':
 C_PATH='@s9s_mb_2u_lib.s9s_mb_2u(sch_1):page525_i142@pure_quanta.q_cap(chips)';

PART_NAME
 C1260 'Q_CAP_C0603-10UF,6.3V,20%,X6S,A':;

SECTION_NUMBER 1
 '@S9S_MB_2U_LIB.S9S_MB_2U(SCH_1):PAGE525_I131@PURE_QUANTA.Q_CAP(CHIPS)':
 C_PATH='@s9s_mb_2u_lib.s9s_mb_2u(sch_1):page525_i131@pure_quanta.q_cap(chips)';

PART_NAME
 C1259 'Q_CAP_0805-47UF,4V,20%,X6S,CH6A':;

SECTION_NUMBER 1
 '@S9S_MB_2U_LIB.S9S_MB_2U(SCH_1):PAGE525_I121@PURE_QUANTA.Q_CAP(CHIPS)':
 C_PATH='@s9s_mb_2u_lib.s9s_mb_2u(sch_1):page525_i121@pure_quanta.q_cap(chips)';

PART_NAME
 C1258 'Q_CAP_0805-47UF,4V,20%,X6S,CH6A':;

SECTION_NUMBER 1
 '@S9S_MB_2U_LIB.S9S_MB_2U(SCH_1):PAGE525_I112@PURE_QUANTA.Q_CAP(CHIPS)':
 C_PATH='@s9s_mb_2u_lib.s9s_mb_2u(sch_1):page525_i112@pure_quanta.q_cap(chips)';

PART_NAME
 C1257 'Q_CAP_0402-1UF,6.3V,10%,EMPTY,A':;

SECTION_NUMBER 1
 '@S9S_MB_2U_LIB.S9S_MB_2U(SCH_1):PAGE525_I146@PURE_QUANTA.Q_CAP(CHIPS)':
 C_PATH='@s9s_mb_2u_lib.s9s_mb_2u(sch_1):page525_i146@pure_quanta.q_cap(chips)';

PART_NAME
 C1256 'Q_CAP_0402-1UF,6.3V,10%,EMPTY,A':;

SECTION_NUMBER 1
 '@S9S_MB_2U_LIB.S9S_MB_2U(SCH_1):PAGE525_I136@PURE_QUANTA.Q_CAP(CHIPS)':
 C_PATH='@s9s_mb_2u_lib.s9s_mb_2u(sch_1):page525_i136@pure_quanta.q_cap(chips)';

PART_NAME
 C1255 'Q_CAP_C0603-10UF,6.3V,20%,X6S,A':;

SECTION_NUMBER 1
 '@S9S_MB_2U_LIB.S9S_MB_2U(SCH_1):PAGE525_I123@PURE_QUANTA.Q_CAP(CHIPS)':
 C_PATH='@s9s_mb_2u_lib.s9s_mb_2u(sch_1):page525_i123@pure_quanta.q_cap(chips)';

PART_NAME
 C1254 'Q_CAP_C0603-10UF,6.3V,20%,X6S,A':;

SECTION_NUMBER 1
 '@S9S_MB_2U_LIB.S9S_MB_2U(SCH_1):PAGE525_I111@PURE_QUANTA.Q_CAP(CHIPS)':
 C_PATH='@s9s_mb_2u_lib.s9s_mb_2u(sch_1):page525_i111@pure_quanta.q_cap(chips)';

PART_NAME
 C1253 'Q_CAP_0402-1UF,6.3V,10%,EMPTY,A':;

SECTION_NUMBER 1
 '@S9S_MB_2U_LIB.S9S_MB_2U(SCH_1):PAGE525_I147@PURE_QUANTA.Q_CAP(CHIPS)':
 C_PATH='@s9s_mb_2u_lib.s9s_mb_2u(sch_1):page525_i147@pure_quanta.q_cap(chips)';

PART_NAME
 C1252 'Q_CAP_C0603-10UF,6.3V,20%,X6S,A':;

SECTION_NUMBER 1
 '@S9S_MB_2U_LIB.S9S_MB_2U(SCH_1):PAGE525_I125@PURE_QUANTA.Q_CAP(CHIPS)':
 C_PATH='@s9s_mb_2u_lib.s9s_mb_2u(sch_1):page525_i125@pure_quanta.q_cap(chips)';

PART_NAME
 C1251 'Q_CAP_C0603-10UF,6.3V,20%,X6S,A':;

SECTION_NUMBER 1
 '@S9S_MB_2U_LIB.S9S_MB_2U(SCH_1):PAGE525_I110@PURE_QUANTA.Q_CAP(CHIPS)':
 C_PATH='@s9s_mb_2u_lib.s9s_mb_2u(sch_1):page525_i110@pure_quanta.q_cap(chips)';

PART_NAME
 C1250 'Q_CAP_0402-1UF,6.3V,10%,EMPTY,A':;

SECTION_NUMBER 1
 '@S9S_MB_2U_LIB.S9S_MB_2U(SCH_1):PAGE525_I137@PURE_QUANTA.Q_CAP(CHIPS)':
 C_PATH='@s9s_mb_2u_lib.s9s_mb_2u(sch_1):page525_i137@pure_quanta.q_cap(chips)';

PART_NAME
 C1249 'Q_CAP_0805-47UF,4V,20%,X6S,CH6A':;

SECTION_NUMBER 1
 '@S9S_MB_2U_LIB.S9S_MB_2U(SCH_1):PAGE525_I66@PURE_QUANTA.Q_CAP(CHIPS)':
 C_PATH='@s9s_mb_2u_lib.s9s_mb_2u(sch_1):page525_i66@pure_quanta.q_cap(chips)';

PART_NAME
 C1248 'Q_CAP_0805-47UF,4V,20%,X6S,CH6A':;

SECTION_NUMBER 1
 '@S9S_MB_2U_LIB.S9S_MB_2U(SCH_1):PAGE525_I22@PURE_QUANTA.Q_CAP(CHIPS)':
 C_PATH='@s9s_mb_2u_lib.s9s_mb_2u(sch_1):page525_i22@pure_quanta.q_cap(chips)';

PART_NAME
 C1247 'Q_CAP_0805-47UF,4V,20%,X6S,CH6A':;

SECTION_NUMBER 1
 '@S9S_MB_2U_LIB.S9S_MB_2U(SCH_1):PAGE525_I65@PURE_QUANTA.Q_CAP(CHIPS)':
 C_PATH='@s9s_mb_2u_lib.s9s_mb_2u(sch_1):page525_i65@pure_quanta.q_cap(chips)';

PART_NAME
 C1246 'Q_CAP_0805-47UF,4V,20%,X6S,CH6A':;

SECTION_NUMBER 1
 '@S9S_MB_2U_LIB.S9S_MB_2U(SCH_1):PAGE525_I21@PURE_QUANTA.Q_CAP(CHIPS)':
 C_PATH='@s9s_mb_2u_lib.s9s_mb_2u(sch_1):page525_i21@pure_quanta.q_cap(chips)';

PART_NAME
 C1245 'Q_CAP_0805-47UF,4V,20%,X6S,CH6A':;

SECTION_NUMBER 1
 '@S9S_MB_2U_LIB.S9S_MB_2U(SCH_1):PAGE525_I81@PURE_QUANTA.Q_CAP(CHIPS)':
 C_PATH='@s9s_mb_2u_lib.s9s_mb_2u(sch_1):page525_i81@pure_quanta.q_cap(chips)';

PART_NAME
 C1244 'Q_CAP_0805-47UF,4V,20%,X6S,CH6A':;

SECTION_NUMBER 1
 '@S9S_MB_2U_LIB.S9S_MB_2U(SCH_1):PAGE525_I15@PURE_QUANTA.Q_CAP(CHIPS)':
 C_PATH='@s9s_mb_2u_lib.s9s_mb_2u(sch_1):page525_i15@pure_quanta.q_cap(chips)';

PART_NAME
 C1243 'Q_CAP_0805-47UF,4V,20%,X6S,CH6A':;

SECTION_NUMBER 1
 '@S9S_MB_2U_LIB.S9S_MB_2U(SCH_1):PAGE525_I83@PURE_QUANTA.Q_CAP(CHIPS)':
 C_PATH='@s9s_mb_2u_lib.s9s_mb_2u(sch_1):page525_i83@pure_quanta.q_cap(chips)';

PART_NAME
 C1242 'Q_CAP_C0402-2.2UF,10V,10%,X6S,A':;

SECTION_NUMBER 1
 '@S9S_MB_2U_LIB.S9S_MB_2U(SCH_1):PAGE525_I63@PURE_QUANTA.Q_CAP(CHIPS)':
 C_PATH='@s9s_mb_2u_lib.s9s_mb_2u(sch_1):page525_i63@pure_quanta.q_cap(chips)';

PART_NAME
 C1231 'Q_CAP_C0402-10UF,6.3V,20%,X6S,A':;

SECTION_NUMBER 1
 '@S9S_MB_2U_LIB.S9S_MB_2U(SCH_1):PAGE525_I49@PURE_QUANTA.Q_CAP(CHIPS)':
 C_PATH='@s9s_mb_2u_lib.s9s_mb_2u(sch_1):page525_i49@pure_quanta.q_cap(chips)';

PART_NAME
 C1228 'Q_CAP_C0402-10UF,6.3V,20%,X6S,A':;

SECTION_NUMBER 1
 '@S9S_MB_2U_LIB.S9S_MB_2U(SCH_1):PAGE525_I13@PURE_QUANTA.Q_CAP(CHIPS)':
 C_PATH='@s9s_mb_2u_lib.s9s_mb_2u(sch_1):page525_i13@pure_quanta.q_cap(chips)';

PART_NAME
 C1214 'Q_CAP_C0402-2.2UF,10V,10%,X6S,A':;

SECTION_NUMBER 1
 '@S9S_MB_2U_LIB.S9S_MB_2U(SCH_1):PAGE525_I61@PURE_QUANTA.Q_CAP(CHIPS)':
 C_PATH='@s9s_mb_2u_lib.s9s_mb_2u(sch_1):page525_i61@pure_quanta.q_cap(chips)';

PART_NAME
 C1210 'Q_CAP_C0402-10UF,6.3V,20%,X6S,A':;

SECTION_NUMBER 1
 '@S9S_MB_2U_LIB.S9S_MB_2U(SCH_1):PAGE525_I45@PURE_QUANTA.Q_CAP(CHIPS)':
 C_PATH='@s9s_mb_2u_lib.s9s_mb_2u(sch_1):page525_i45@pure_quanta.q_cap(chips)';

PART_NAME
 C1207 'Q_CAP_C0402-10UF,6.3V,20%,X6S,A':;

SECTION_NUMBER 1
 '@S9S_MB_2U_LIB.S9S_MB_2U(SCH_1):PAGE525_I32@PURE_QUANTA.Q_CAP(CHIPS)':
 C_PATH='@s9s_mb_2u_lib.s9s_mb_2u(sch_1):page525_i32@pure_quanta.q_cap(chips)';

PART_NAME
 C1206 'Q_CAP_C0402-10UF,6.3V,20%,X6S,A':;

SECTION_NUMBER 1
 '@S9S_MB_2U_LIB.S9S_MB_2U(SCH_1):PAGE525_I78@PURE_QUANTA.Q_CAP(CHIPS)':
 C_PATH='@s9s_mb_2u_lib.s9s_mb_2u(sch_1):page525_i78@pure_quanta.q_cap(chips)';

PART_NAME
 C1205 'Q_CAP_C0402-10UF,6.3V,20%,X6S,A':;

SECTION_NUMBER 1
 '@S9S_MB_2U_LIB.S9S_MB_2U(SCH_1):PAGE525_I12@PURE_QUANTA.Q_CAP(CHIPS)':
 C_PATH='@s9s_mb_2u_lib.s9s_mb_2u(sch_1):page525_i12@pure_quanta.q_cap(chips)';

PART_NAME
 C1204 'Q_CAP_C0402-2.2UF,10V,10%,X6S,A':;

SECTION_NUMBER 1
 '@S9S_MB_2U_LIB.S9S_MB_2U(SCH_1):PAGE525_I60@PURE_QUANTA.Q_CAP(CHIPS)':
 C_PATH='@s9s_mb_2u_lib.s9s_mb_2u(sch_1):page525_i60@pure_quanta.q_cap(chips)';

PART_NAME
 C1203 'Q_CAP_C0402-10UF,6.3V,20%,X6S,A':;

SECTION_NUMBER 1
 '@S9S_MB_2U_LIB.S9S_MB_2U(SCH_1):PAGE525_I48@PURE_QUANTA.Q_CAP(CHIPS)':
 C_PATH='@s9s_mb_2u_lib.s9s_mb_2u(sch_1):page525_i48@pure_quanta.q_cap(chips)';

PART_NAME
 C1202 'Q_CAP_C0603-22UF,4V,20%,X6S,CHA':;

SECTION_NUMBER 1
 '@S9S_MB_2U_LIB.S9S_MB_2U(SCH_1):PAGE525_I29@PURE_QUANTA.Q_CAP(CHIPS)':
 C_PATH='@s9s_mb_2u_lib.s9s_mb_2u(sch_1):page525_i29@pure_quanta.q_cap(chips)';

PART_NAME
 C1201 'Q_CAP_C0603-22UF,4V,20%,X6S,CHA':;

SECTION_NUMBER 1
 '@S9S_MB_2U_LIB.S9S_MB_2U(SCH_1):PAGE525_I87@PURE_QUANTA.Q_CAP(CHIPS)':
 C_PATH='@s9s_mb_2u_lib.s9s_mb_2u(sch_1):page525_i87@pure_quanta.q_cap(chips)';

PART_NAME
 C1200 'Q_CAP_C0402-2.2UF,10V,10%,X6S,A':;

SECTION_NUMBER 1
 '@S9S_MB_2U_LIB.S9S_MB_2U(SCH_1):PAGE525_I59@PURE_QUANTA.Q_CAP(CHIPS)':
 C_PATH='@s9s_mb_2u_lib.s9s_mb_2u(sch_1):page525_i59@pure_quanta.q_cap(chips)';

PART_NAME
 C1198 'Q_CAP_C0603-22UF,4V,20%,X6S,CHA':;

SECTION_NUMBER 1
 '@S9S_MB_2U_LIB.S9S_MB_2U(SCH_1):PAGE525_I43@PURE_QUANTA.Q_CAP(CHIPS)':
 C_PATH='@s9s_mb_2u_lib.s9s_mb_2u(sch_1):page525_i43@pure_quanta.q_cap(chips)';

PART_NAME
 C1197 'Q_CAP_C0603-22UF,4V,20%,X6S,CHA':;

SECTION_NUMBER 1
 '@S9S_MB_2U_LIB.S9S_MB_2U(SCH_1):PAGE525_I30@PURE_QUANTA.Q_CAP(CHIPS)':
 C_PATH='@s9s_mb_2u_lib.s9s_mb_2u(sch_1):page525_i30@pure_quanta.q_cap(chips)';

PART_NAME
 C1192 'Q_CAP_C0603-22UF,4V,20%,X6S,CHA':;

SECTION_NUMBER 1
 '@S9S_MB_2U_LIB.S9S_MB_2U(SCH_1):PAGE525_I8@PURE_QUANTA.Q_CAP(CHIPS)':
 C_PATH='@s9s_mb_2u_lib.s9s_mb_2u(sch_1):page525_i8@pure_quanta.q_cap(chips)';

PART_NAME
 C1191 'Q_CAP_C0603-22UF,4V,20%,X6S,CHA':;

SECTION_NUMBER 1
 '@S9S_MB_2U_LIB.S9S_MB_2U(SCH_1):PAGE525_I89@PURE_QUANTA.Q_CAP(CHIPS)':
 C_PATH='@s9s_mb_2u_lib.s9s_mb_2u(sch_1):page525_i89@pure_quanta.q_cap(chips)';

PART_NAME
 C1189 'Q_CAP_C0402-2.2UF,10V,10%,X6S,A':;

SECTION_NUMBER 1
 '@S9S_MB_2U_LIB.S9S_MB_2U(SCH_1):PAGE525_I58@PURE_QUANTA.Q_CAP(CHIPS)':
 C_PATH='@s9s_mb_2u_lib.s9s_mb_2u(sch_1):page525_i58@pure_quanta.q_cap(chips)';

PART_NAME
 C1187 'Q_CAP_C0603-22UF,4V,20%,X6S,CHA':;

SECTION_NUMBER 1
 '@S9S_MB_2U_LIB.S9S_MB_2U(SCH_1):PAGE525_I40@PURE_QUANTA.Q_CAP(CHIPS)':
 C_PATH='@s9s_mb_2u_lib.s9s_mb_2u(sch_1):page525_i40@pure_quanta.q_cap(chips)';

PART_NAME
 C1186 'Q_CAP_C0603-22UF,4V,20%,X6S,CHA':;

SECTION_NUMBER 1
 '@S9S_MB_2U_LIB.S9S_MB_2U(SCH_1):PAGE525_I25@PURE_QUANTA.Q_CAP(CHIPS)':
 C_PATH='@s9s_mb_2u_lib.s9s_mb_2u(sch_1):page525_i25@pure_quanta.q_cap(chips)';

PART_NAME
 C1185 'Q_CAP_C0603-22UF,4V,20%,X6S,CHA':;

SECTION_NUMBER 1
 '@S9S_MB_2U_LIB.S9S_MB_2U(SCH_1):PAGE525_I7@PURE_QUANTA.Q_CAP(CHIPS)':
 C_PATH='@s9s_mb_2u_lib.s9s_mb_2u(sch_1):page525_i7@pure_quanta.q_cap(chips)';

PART_NAME
 C1184 'Q_CAP_C0603-22UF,4V,20%,X6S,CHA':;

SECTION_NUMBER 1
 '@S9S_MB_2U_LIB.S9S_MB_2U(SCH_1):PAGE525_I91@PURE_QUANTA.Q_CAP(CHIPS)':
 C_PATH='@s9s_mb_2u_lib.s9s_mb_2u(sch_1):page525_i91@pure_quanta.q_cap(chips)';

PART_NAME
 C1183 'Q_CAP_C0402-2.2UF,10V,10%,X6S,A':;

SECTION_NUMBER 1
 '@S9S_MB_2U_LIB.S9S_MB_2U(SCH_1):PAGE525_I51@PURE_QUANTA.Q_CAP(CHIPS)':
 C_PATH='@s9s_mb_2u_lib.s9s_mb_2u(sch_1):page525_i51@pure_quanta.q_cap(chips)';

PART_NAME
 C1182 'Q_CAP_C0603-22UF,4V,20%,X6S,CHA':;

SECTION_NUMBER 1
 '@S9S_MB_2U_LIB.S9S_MB_2U(SCH_1):PAGE525_I42@PURE_QUANTA.Q_CAP(CHIPS)':
 C_PATH='@s9s_mb_2u_lib.s9s_mb_2u(sch_1):page525_i42@pure_quanta.q_cap(chips)';

PART_NAME
 C1181 'Q_CAP_C0603-22UF,4V,20%,X6S,CHA':;

SECTION_NUMBER 1
 '@S9S_MB_2U_LIB.S9S_MB_2U(SCH_1):PAGE525_I27@PURE_QUANTA.Q_CAP(CHIPS)':
 C_PATH='@s9s_mb_2u_lib.s9s_mb_2u(sch_1):page525_i27@pure_quanta.q_cap(chips)';

PART_NAME
 C1178 'Q_CAP_C0603-22UF,4V,20%,X6S,CHA':;

SECTION_NUMBER 1
 '@S9S_MB_2U_LIB.S9S_MB_2U(SCH_1):PAGE525_I6@PURE_QUANTA.Q_CAP(CHIPS)':
 C_PATH='@s9s_mb_2u_lib.s9s_mb_2u(sch_1):page525_i6@pure_quanta.q_cap(chips)';

PART_NAME
 S2 'SW8S_DHNF04FTVTR-SW8S_DHNF04FTA':;

SECTION_NUMBER 1
 '@S9S_MB_2U_LIB.S9S_MB_2U(SCH_1):PAGE620_I35@PURE_QUANTA.SW8S_DHNF04FTVTR(CHIPS)':
 C_PATH='@s9s_mb_2u_lib.s9s_mb_2u(sch_1):page620_i35@pure_quanta.sw8s_dhnf04ftvtr(~
chips)';

PART_NAME
 S1 'SW8S_DHNF04FTVTR-SW8S_DHNF04FTA':;

SECTION_NUMBER 1
 '@S9S_MB_2U_LIB.S9S_MB_2U(SCH_1):PAGE620_I4@PURE_QUANTA.SW8S_DHNF04FTVTR(CHIPS)':
 C_PATH='@s9s_mb_2u_lib.s9s_mb_2u(sch_1):page620_i4@pure_quanta.sw8s_dhnf04ftvtr(c~
hips)';

PART_NAME
 R1343 'Q_RES_0402LF-10K,1%,1/16W,CHIPA':;

SECTION_NUMBER 1
 '@S9S_MB_2U_LIB.S9S_MB_2U(SCH_1):PAGE620_I44@PURE_QUANTA.Q_RES(CHIPS)':
 C_PATH='@s9s_mb_2u_lib.s9s_mb_2u(sch_1):page620_i44@pure_quanta.q_res(chips)';

PART_NAME
 R1342 'Q_RES_0402LF-10K,1%,1/16W,CHIPA':;

SECTION_NUMBER 1
 '@S9S_MB_2U_LIB.S9S_MB_2U(SCH_1):PAGE620_I45@PURE_QUANTA.Q_RES(CHIPS)':
 C_PATH='@s9s_mb_2u_lib.s9s_mb_2u(sch_1):page620_i45@pure_quanta.q_res(chips)';

PART_NAME
 R1341 'Q_RES_0402LF-10K,1%,1/16W,CHIPA':;

SECTION_NUMBER 1
 '@S9S_MB_2U_LIB.S9S_MB_2U(SCH_1):PAGE620_I69@PURE_QUANTA.Q_RES(CHIPS)':
 C_PATH='@s9s_mb_2u_lib.s9s_mb_2u(sch_1):page620_i69@pure_quanta.q_res(chips)';

PART_NAME
 R1340 'Q_RES_0402LF-20K,5%,1/16W,CHIPA':;

SECTION_NUMBER 1
 '@S9S_MB_2U_LIB.S9S_MB_2U(SCH_1):PAGE620_I57@PURE_QUANTA.Q_RES(CHIPS)':
 C_PATH='@s9s_mb_2u_lib.s9s_mb_2u(sch_1):page620_i57@pure_quanta.q_res(chips)';

PART_NAME
 R1339 'Q_RES_0402LF-10K,1%,1/16W,CHIPA':;

SECTION_NUMBER 1
 '@S9S_MB_2U_LIB.S9S_MB_2U(SCH_1):PAGE620_I13@PURE_QUANTA.Q_RES(CHIPS)':
 C_PATH='@s9s_mb_2u_lib.s9s_mb_2u(sch_1):page620_i13@pure_quanta.q_res(chips)';

PART_NAME
 R1338 'Q_RES_0402LF-10K,1%,1/16W,CHIPA':;

SECTION_NUMBER 1
 '@S9S_MB_2U_LIB.S9S_MB_2U(SCH_1):PAGE620_I29@PURE_QUANTA.Q_RES(CHIPS)':
 C_PATH='@s9s_mb_2u_lib.s9s_mb_2u(sch_1):page620_i29@pure_quanta.q_res(chips)';

PART_NAME
 R1337 'Q_RES_0402LF-10K,1%,1/16W,CHIPA':;

SECTION_NUMBER 1
 '@S9S_MB_2U_LIB.S9S_MB_2U(SCH_1):PAGE620_I77@PURE_QUANTA.Q_RES(CHIPS)':
 C_PATH='@s9s_mb_2u_lib.s9s_mb_2u(sch_1):page620_i77@pure_quanta.q_res(chips)';

PART_NAME
 R1335 'Q_RES_0402LF-1K,1%,1/16W,CHIP,A':;

SECTION_NUMBER 1
 '@S9S_MB_2U_LIB.S9S_MB_2U(SCH_1):PAGE620_I50@PURE_QUANTA.Q_RES(CHIPS)':
 C_PATH='@s9s_mb_2u_lib.s9s_mb_2u(sch_1):page620_i50@pure_quanta.q_res(chips)';

PART_NAME
 R1334 'Q_RES_0402LF-1K,1%,1/16W,CHIP,A':;

SECTION_NUMBER 1
 '@S9S_MB_2U_LIB.S9S_MB_2U(SCH_1):PAGE620_I54@PURE_QUANTA.Q_RES(CHIPS)':
 C_PATH='@s9s_mb_2u_lib.s9s_mb_2u(sch_1):page620_i54@pure_quanta.q_res(chips)';

PART_NAME
 R1333 'Q_RES_0402LF-1K,1%,1/16W,CHIP,A':;

SECTION_NUMBER 1
 '@S9S_MB_2U_LIB.S9S_MB_2U(SCH_1):PAGE620_I49@PURE_QUANTA.Q_RES(CHIPS)':
 C_PATH='@s9s_mb_2u_lib.s9s_mb_2u(sch_1):page620_i49@pure_quanta.q_res(chips)';

PART_NAME
 R1325 'Q_RES_0402LF-1K,1%,1/16W,CHIP,A':;

SECTION_NUMBER 1
 '@S9S_MB_2U_LIB.S9S_MB_2U(SCH_1):PAGE620_I75@PURE_QUANTA.Q_RES(CHIPS)':
 C_PATH='@s9s_mb_2u_lib.s9s_mb_2u(sch_1):page620_i75@pure_quanta.q_res(chips)';

PART_NAME
 R1324 'Q_RES_0402LF-1K,1%,1/16W,CHIP,A':;

SECTION_NUMBER 1
 '@S9S_MB_2U_LIB.S9S_MB_2U(SCH_1):PAGE620_I26@PURE_QUANTA.Q_RES(CHIPS)':
 C_PATH='@s9s_mb_2u_lib.s9s_mb_2u(sch_1):page620_i26@pure_quanta.q_res(chips)';

PART_NAME
 R1320 'Q_RES_0402LF-1K,1%,1/16W,CHIP,A':;

SECTION_NUMBER 1
 '@S9S_MB_2U_LIB.S9S_MB_2U(SCH_1):PAGE620_I68@PURE_QUANTA.Q_RES(CHIPS)':
 C_PATH='@s9s_mb_2u_lib.s9s_mb_2u(sch_1):page620_i68@pure_quanta.q_res(chips)';

PART_NAME
 R1317 'Q_RES_0402LF-1K,1%,1/16W,CHIP,A':;

SECTION_NUMBER 1
 '@S9S_MB_2U_LIB.S9S_MB_2U(SCH_1):PAGE620_I28@PURE_QUANTA.Q_RES(CHIPS)':
 C_PATH='@s9s_mb_2u_lib.s9s_mb_2u(sch_1):page620_i28@pure_quanta.q_res(chips)';

PART_NAME
 C1177 'Q_CAP_C0402-1UF,25V,10%,X6S,CHA':;

SECTION_NUMBER 1
 '@S9S_MB_2U_LIB.S9S_MB_2U(SCH_1):PAGE620_I67@PURE_QUANTA.Q_CAP(CHIPS)':
 C_PATH='@s9s_mb_2u_lib.s9s_mb_2u(sch_1):page620_i67@pure_quanta.q_cap(chips)';

PART_NAME
 U3 '10M25DAF484C7G-10M25DAF484C7G,A':;

SECTION_NUMBER 1
 '@S9S_MB_2U_LIB.S9S_MB_2U(SCH_1):PAGE541_I1@PURE_QUANTA.10M25DAF484C7G(CHIPS)':
 C_PATH='@s9s_mb_2u_lib.s9s_mb_2u(sch_1):page541_i1@pure_quanta.\10m25daf484c7g\(c~
hips)';

SECTION_NUMBER 2
 '@S9S_MB_2U_LIB.S9S_MB_2U(SCH_1):PAGE542_I33@PURE_QUANTA.10M25DAF484C7G(CHIPS)':
 C_PATH='@s9s_mb_2u_lib.s9s_mb_2u(sch_1):page542_i33@pure_quanta.\10m25daf484c7g\(~
chips)';

SECTION_NUMBER 3
 '@S9S_MB_2U_LIB.S9S_MB_2U(SCH_1):PAGE543_I28@PURE_QUANTA.10M25DAF484C7G(CHIPS)':
 C_PATH='@s9s_mb_2u_lib.s9s_mb_2u(sch_1):page543_i28@pure_quanta.\10m25daf484c7g\(~
chips)';

SECTION_NUMBER 4
 '@S9S_MB_2U_LIB.S9S_MB_2U(SCH_1):PAGE544_I28@PURE_QUANTA.10M25DAF484C7G(CHIPS)':
 C_PATH='@s9s_mb_2u_lib.s9s_mb_2u(sch_1):page544_i28@pure_quanta.\10m25daf484c7g\(~
chips)';

SECTION_NUMBER 5
 '@S9S_MB_2U_LIB.S9S_MB_2U(SCH_1):PAGE545_I28@PURE_QUANTA.10M25DAF484C7G(CHIPS)':
 C_PATH='@s9s_mb_2u_lib.s9s_mb_2u(sch_1):page545_i28@pure_quanta.\10m25daf484c7g\(~
chips)';

SECTION_NUMBER 6
 '@S9S_MB_2U_LIB.S9S_MB_2U(SCH_1):PAGE545_I29@PURE_QUANTA.10M25DAF484C7G(CHIPS)':
 C_PATH='@s9s_mb_2u_lib.s9s_mb_2u(sch_1):page545_i29@pure_quanta.\10m25daf484c7g\(~
chips)';

SECTION_NUMBER 7
 '@S9S_MB_2U_LIB.S9S_MB_2U(SCH_1):PAGE546_I1@PURE_QUANTA.10M25DAF484C7G(CHIPS)':
 C_PATH='@s9s_mb_2u_lib.s9s_mb_2u(sch_1):page546_i1@pure_quanta.\10m25daf484c7g\(c~
hips)';

PART_NAME
 R514 'Q_RES_1206LF-0,5%,1/4W,EMPTY,CA':;

SECTION_NUMBER 1
 '@S9S_MB_2U_LIB.S9S_MB_2U(SCH_1):PAGE546_I140@PURE_QUANTA.Q_RES(CHIPS)':
 C_PATH='@s9s_mb_2u_lib.s9s_mb_2u(sch_1):page546_i140@pure_quanta.q_res(chips)';

PART_NAME
 R513 'Q_RES_1206LF-0,5%,1/4W,CHIP,CSA':;

SECTION_NUMBER 1
 '@S9S_MB_2U_LIB.S9S_MB_2U(SCH_1):PAGE546_I141@PURE_QUANTA.Q_RES(CHIPS)':
 C_PATH='@s9s_mb_2u_lib.s9s_mb_2u(sch_1):page546_i141@pure_quanta.q_res(chips)';

PART_NAME
 R512 'Q_RES_1206LF-0,5%,1/4W,EMPTY,CA':;

SECTION_NUMBER 1
 '@S9S_MB_2U_LIB.S9S_MB_2U(SCH_1):PAGE546_I138@PURE_QUANTA.Q_RES(CHIPS)':
 C_PATH='@s9s_mb_2u_lib.s9s_mb_2u(sch_1):page546_i138@pure_quanta.q_res(chips)';

PART_NAME
 R511 'Q_RES_1206LF-0,5%,1/4W,CHIP,CSA':;

SECTION_NUMBER 1
 '@S9S_MB_2U_LIB.S9S_MB_2U(SCH_1):PAGE546_I137@PURE_QUANTA.Q_RES(CHIPS)':
 C_PATH='@s9s_mb_2u_lib.s9s_mb_2u(sch_1):page546_i137@pure_quanta.q_res(chips)';

PART_NAME
 R510 'Q_RES_0402LF-0,5%,1/16W,CHIP,CA':;

SECTION_NUMBER 1
 '@S9S_MB_2U_LIB.S9S_MB_2U(SCH_1):PAGE546_I14@PURE_QUANTA.Q_RES(CHIPS)':
 C_PATH='@s9s_mb_2u_lib.s9s_mb_2u(sch_1):page546_i14@pure_quanta.q_res(chips)';

PART_NAME
 R509 'Q_RES_0402LF-0,5%,1/16W,CHIP,CA':;

SECTION_NUMBER 1
 '@S9S_MB_2U_LIB.S9S_MB_2U(SCH_1):PAGE546_I13@PURE_QUANTA.Q_RES(CHIPS)':
 C_PATH='@s9s_mb_2u_lib.s9s_mb_2u(sch_1):page546_i13@pure_quanta.q_res(chips)';

PART_NAME
 R508 'Q_RES_0402LF-0,5%,1/16W,CHIP,CA':;

SECTION_NUMBER 1
 '@S9S_MB_2U_LIB.S9S_MB_2U(SCH_1):PAGE546_I8@PURE_QUANTA.Q_RES(CHIPS)':
 C_PATH='@s9s_mb_2u_lib.s9s_mb_2u(sch_1):page546_i8@pure_quanta.q_res(chips)';

PART_NAME
 R507 'Q_RES_0402LF-0,5%,1/16W,EMPTY,A':;

SECTION_NUMBER 1
 '@S9S_MB_2U_LIB.S9S_MB_2U(SCH_1):PAGE546_I7@PURE_QUANTA.Q_RES(CHIPS)':
 C_PATH='@s9s_mb_2u_lib.s9s_mb_2u(sch_1):page546_i7@pure_quanta.q_res(chips)';

PART_NAME
 L37 'Q_INDUCTOR_SMLF-BLM18PG121SN1DB':;

SECTION_NUMBER 1
 '@S9S_MB_2U_LIB.S9S_MB_2U(SCH_1):PAGE546_I145@PURE_QUANTA.Q_INDUCTOR(CHIPS)':
 C_PATH='@s9s_mb_2u_lib.s9s_mb_2u(sch_1):page546_i145@pure_quanta.q_inductor(chips~
)';

PART_NAME
 L36 'Q_INDUCTOR_SMLF-BLM18PG121SN1DB':;

SECTION_NUMBER 1
 '@S9S_MB_2U_LIB.S9S_MB_2U(SCH_1):PAGE546_I143@PURE_QUANTA.Q_INDUCTOR(CHIPS)':
 C_PATH='@s9s_mb_2u_lib.s9s_mb_2u(sch_1):page546_i143@pure_quanta.q_inductor(chips~
)';

PART_NAME
 C1169 'Q_CAP_0402-0.1UF,25V,10%,X7R,CA':;

SECTION_NUMBER 1
 '@S9S_MB_2U_LIB.S9S_MB_2U(SCH_1):PAGE546_I131@PURE_QUANTA.Q_CAP(CHIPS)':
 C_PATH='@s9s_mb_2u_lib.s9s_mb_2u(sch_1):page546_i131@pure_quanta.q_cap(chips)';

PART_NAME
 C1168 'Q_CAP_0402-0.1UF,25V,10%,X7R,CA':;

SECTION_NUMBER 1
 '@S9S_MB_2U_LIB.S9S_MB_2U(SCH_1):PAGE546_I35@PURE_QUANTA.Q_CAP(CHIPS)':
 C_PATH='@s9s_mb_2u_lib.s9s_mb_2u(sch_1):page546_i35@pure_quanta.q_cap(chips)';

PART_NAME
 C1167 'Q_CAP_0402-0.1UF,25V,10%,X7R,CA':;

SECTION_NUMBER 1
 '@S9S_MB_2U_LIB.S9S_MB_2U(SCH_1):PAGE546_I29@PURE_QUANTA.Q_CAP(CHIPS)':
 C_PATH='@s9s_mb_2u_lib.s9s_mb_2u(sch_1):page546_i29@pure_quanta.q_cap(chips)';

PART_NAME
 C1166 'Q_CAP_0402-0.1UF,25V,10%,X7R,CA':;

SECTION_NUMBER 1
 '@S9S_MB_2U_LIB.S9S_MB_2U(SCH_1):PAGE546_I132@PURE_QUANTA.Q_CAP(CHIPS)':
 C_PATH='@s9s_mb_2u_lib.s9s_mb_2u(sch_1):page546_i132@pure_quanta.q_cap(chips)';

PART_NAME
 C1165 'Q_CAP_0402-0.1UF,25V,10%,X7R,CA':;

SECTION_NUMBER 1
 '@S9S_MB_2U_LIB.S9S_MB_2U(SCH_1):PAGE546_I36@PURE_QUANTA.Q_CAP(CHIPS)':
 C_PATH='@s9s_mb_2u_lib.s9s_mb_2u(sch_1):page546_i36@pure_quanta.q_cap(chips)';

PART_NAME
 C1164 'Q_CAP_0402-0.1UF,25V,10%,X7R,CA':;

SECTION_NUMBER 1
 '@S9S_MB_2U_LIB.S9S_MB_2U(SCH_1):PAGE546_I31@PURE_QUANTA.Q_CAP(CHIPS)':
 C_PATH='@s9s_mb_2u_lib.s9s_mb_2u(sch_1):page546_i31@pure_quanta.q_cap(chips)';

PART_NAME
 C1163 'Q_CAP_0402-0.1UF,25V,10%,X7R,CA':;

SECTION_NUMBER 1
 '@S9S_MB_2U_LIB.S9S_MB_2U(SCH_1):PAGE546_I151@PURE_QUANTA.Q_CAP(CHIPS)':
 C_PATH='@s9s_mb_2u_lib.s9s_mb_2u(sch_1):page546_i151@pure_quanta.q_cap(chips)';

PART_NAME
 C1162 'Q_CAP_0402-0.1UF,25V,10%,X7R,CA':;

SECTION_NUMBER 1
 '@S9S_MB_2U_LIB.S9S_MB_2U(SCH_1):PAGE546_I37@PURE_QUANTA.Q_CAP(CHIPS)':
 C_PATH='@s9s_mb_2u_lib.s9s_mb_2u(sch_1):page546_i37@pure_quanta.q_cap(chips)';

PART_NAME
 C1161 'Q_CAP_0402-0.1UF,25V,10%,X7R,CA':;

SECTION_NUMBER 1
 '@S9S_MB_2U_LIB.S9S_MB_2U(SCH_1):PAGE546_I32@PURE_QUANTA.Q_CAP(CHIPS)':
 C_PATH='@s9s_mb_2u_lib.s9s_mb_2u(sch_1):page546_i32@pure_quanta.q_cap(chips)';

PART_NAME
 C1160 'Q_CAP_0402-0.1UF,25V,10%,X7R,CA':;

SECTION_NUMBER 1
 '@S9S_MB_2U_LIB.S9S_MB_2U(SCH_1):PAGE546_I134@PURE_QUANTA.Q_CAP(CHIPS)':
 C_PATH='@s9s_mb_2u_lib.s9s_mb_2u(sch_1):page546_i134@pure_quanta.q_cap(chips)';

PART_NAME
 C1159 'Q_CAP_0402-0.1UF,25V,10%,X7R,CA':;

SECTION_NUMBER 1
 '@S9S_MB_2U_LIB.S9S_MB_2U(SCH_1):PAGE546_I147@PURE_QUANTA.Q_CAP(CHIPS)':
 C_PATH='@s9s_mb_2u_lib.s9s_mb_2u(sch_1):page546_i147@pure_quanta.q_cap(chips)';

PART_NAME
 C1158 'Q_CAP_0402-0.1UF,25V,10%,X7R,CA':;

SECTION_NUMBER 1
 '@S9S_MB_2U_LIB.S9S_MB_2U(SCH_1):PAGE546_I38@PURE_QUANTA.Q_CAP(CHIPS)':
 C_PATH='@s9s_mb_2u_lib.s9s_mb_2u(sch_1):page546_i38@pure_quanta.q_cap(chips)';

PART_NAME
 C1157 'Q_CAP_0402-0.1UF,25V,10%,X7R,CA':;

SECTION_NUMBER 1
 '@S9S_MB_2U_LIB.S9S_MB_2U(SCH_1):PAGE546_I33@PURE_QUANTA.Q_CAP(CHIPS)':
 C_PATH='@s9s_mb_2u_lib.s9s_mb_2u(sch_1):page546_i33@pure_quanta.q_cap(chips)';

PART_NAME
 C1156 'Q_CAP_0402-0.1UF,25V,10%,X7R,CA':;

SECTION_NUMBER 1
 '@S9S_MB_2U_LIB.S9S_MB_2U(SCH_1):PAGE546_I149@PURE_QUANTA.Q_CAP(CHIPS)':
 C_PATH='@s9s_mb_2u_lib.s9s_mb_2u(sch_1):page546_i149@pure_quanta.q_cap(chips)';

PART_NAME
 C1155 'Q_CAP_0402-0.1UF,25V,10%,X7R,CA':;

SECTION_NUMBER 1
 '@S9S_MB_2U_LIB.S9S_MB_2U(SCH_1):PAGE546_I39@PURE_QUANTA.Q_CAP(CHIPS)':
 C_PATH='@s9s_mb_2u_lib.s9s_mb_2u(sch_1):page546_i39@pure_quanta.q_cap(chips)';

PART_NAME
 C1154 'Q_CAP_0402-0.1UF,25V,10%,X7R,CA':;

SECTION_NUMBER 1
 '@S9S_MB_2U_LIB.S9S_MB_2U(SCH_1):PAGE546_I30@PURE_QUANTA.Q_CAP(CHIPS)':
 C_PATH='@s9s_mb_2u_lib.s9s_mb_2u(sch_1):page546_i30@pure_quanta.q_cap(chips)';

PART_NAME
 C1153 'Q_CAP_0402-0.1UF,25V,10%,X7R,CA':;

SECTION_NUMBER 1
 '@S9S_MB_2U_LIB.S9S_MB_2U(SCH_1):PAGE546_I40@PURE_QUANTA.Q_CAP(CHIPS)':
 C_PATH='@s9s_mb_2u_lib.s9s_mb_2u(sch_1):page546_i40@pure_quanta.q_cap(chips)';

PART_NAME
 C1152 'Q_CAP_0402-0.1UF,25V,10%,X7R,CA':;

SECTION_NUMBER 1
 '@S9S_MB_2U_LIB.S9S_MB_2U(SCH_1):PAGE546_I28@PURE_QUANTA.Q_CAP(CHIPS)':
 C_PATH='@s9s_mb_2u_lib.s9s_mb_2u(sch_1):page546_i28@pure_quanta.q_cap(chips)';

PART_NAME
 C1151 'Q_CAP_0402-0.1UF,25V,10%,X7R,CA':;

SECTION_NUMBER 1
 '@S9S_MB_2U_LIB.S9S_MB_2U(SCH_1):PAGE546_I41@PURE_QUANTA.Q_CAP(CHIPS)':
 C_PATH='@s9s_mb_2u_lib.s9s_mb_2u(sch_1):page546_i41@pure_quanta.q_cap(chips)';

PART_NAME
 C1150 'Q_CAP_0402-0.1UF,25V,10%,X7R,CA':;

SECTION_NUMBER 1
 '@S9S_MB_2U_LIB.S9S_MB_2U(SCH_1):PAGE546_I26@PURE_QUANTA.Q_CAP(CHIPS)':
 C_PATH='@s9s_mb_2u_lib.s9s_mb_2u(sch_1):page546_i26@pure_quanta.q_cap(chips)';

PART_NAME
 C1149 'Q_CAP_0402-0.1UF,25V,10%,X7R,CA':;

SECTION_NUMBER 1
 '@S9S_MB_2U_LIB.S9S_MB_2U(SCH_1):PAGE546_I68@PURE_QUANTA.Q_CAP(CHIPS)':
 C_PATH='@s9s_mb_2u_lib.s9s_mb_2u(sch_1):page546_i68@pure_quanta.q_cap(chips)';

PART_NAME
 C1148 'Q_CAP_0402-0.1UF,25V,10%,X7R,CA':;

SECTION_NUMBER 1
 '@S9S_MB_2U_LIB.S9S_MB_2U(SCH_1):PAGE546_I101@PURE_QUANTA.Q_CAP(CHIPS)':
 C_PATH='@s9s_mb_2u_lib.s9s_mb_2u(sch_1):page546_i101@pure_quanta.q_cap(chips)';

PART_NAME
 C1147 'Q_CAP_0402-0.1UF,25V,10%,X7R,CA':;

SECTION_NUMBER 1
 '@S9S_MB_2U_LIB.S9S_MB_2U(SCH_1):PAGE546_I42@PURE_QUANTA.Q_CAP(CHIPS)':
 C_PATH='@s9s_mb_2u_lib.s9s_mb_2u(sch_1):page546_i42@pure_quanta.q_cap(chips)';

PART_NAME
 C1146 'Q_CAP_0402-0.1UF,25V,10%,X7R,CA':;

SECTION_NUMBER 1
 '@S9S_MB_2U_LIB.S9S_MB_2U(SCH_1):PAGE546_I27@PURE_QUANTA.Q_CAP(CHIPS)':
 C_PATH='@s9s_mb_2u_lib.s9s_mb_2u(sch_1):page546_i27@pure_quanta.q_cap(chips)';

PART_NAME
 C1145 'Q_CAP_0402-0.1UF,25V,10%,X7R,CA':;

SECTION_NUMBER 1
 '@S9S_MB_2U_LIB.S9S_MB_2U(SCH_1):PAGE546_I56@PURE_QUANTA.Q_CAP(CHIPS)':
 C_PATH='@s9s_mb_2u_lib.s9s_mb_2u(sch_1):page546_i56@pure_quanta.q_cap(chips)';

PART_NAME
 C1144 'Q_CAP_0402-0.1UF,25V,10%,X7R,CA':;

SECTION_NUMBER 1
 '@S9S_MB_2U_LIB.S9S_MB_2U(SCH_1):PAGE546_I102@PURE_QUANTA.Q_CAP(CHIPS)':
 C_PATH='@s9s_mb_2u_lib.s9s_mb_2u(sch_1):page546_i102@pure_quanta.q_cap(chips)';

PART_NAME
 C1143 'Q_CAP_0402-0.1UF,25V,10%,X7R,CA':;

SECTION_NUMBER 1
 '@S9S_MB_2U_LIB.S9S_MB_2U(SCH_1):PAGE546_I43@PURE_QUANTA.Q_CAP(CHIPS)':
 C_PATH='@s9s_mb_2u_lib.s9s_mb_2u(sch_1):page546_i43@pure_quanta.q_cap(chips)';

PART_NAME
 C1142 'Q_CAP_0402-0.1UF,25V,10%,X7R,CA':;

SECTION_NUMBER 1
 '@S9S_MB_2U_LIB.S9S_MB_2U(SCH_1):PAGE546_I25@PURE_QUANTA.Q_CAP(CHIPS)':
 C_PATH='@s9s_mb_2u_lib.s9s_mb_2u(sch_1):page546_i25@pure_quanta.q_cap(chips)';

PART_NAME
 C1141 'Q_CAP_0402-0.1UF,25V,10%,X7R,CA':;

SECTION_NUMBER 1
 '@S9S_MB_2U_LIB.S9S_MB_2U(SCH_1):PAGE546_I57@PURE_QUANTA.Q_CAP(CHIPS)':
 C_PATH='@s9s_mb_2u_lib.s9s_mb_2u(sch_1):page546_i57@pure_quanta.q_cap(chips)';

PART_NAME
 C1140 'Q_CAP_0402-0.1UF,25V,10%,X7R,CA':;

SECTION_NUMBER 1
 '@S9S_MB_2U_LIB.S9S_MB_2U(SCH_1):PAGE546_I104@PURE_QUANTA.Q_CAP(CHIPS)':
 C_PATH='@s9s_mb_2u_lib.s9s_mb_2u(sch_1):page546_i104@pure_quanta.q_cap(chips)';

PART_NAME
 C1139 'Q_CAP_0402-0.1UF,25V,10%,X7R,CA':;

SECTION_NUMBER 1
 '@S9S_MB_2U_LIB.S9S_MB_2U(SCH_1):PAGE546_I44@PURE_QUANTA.Q_CAP(CHIPS)':
 C_PATH='@s9s_mb_2u_lib.s9s_mb_2u(sch_1):page546_i44@pure_quanta.q_cap(chips)';

PART_NAME
 C1138 'Q_CAP_0402-0.1UF,25V,10%,X7R,CA':;

SECTION_NUMBER 1
 '@S9S_MB_2U_LIB.S9S_MB_2U(SCH_1):PAGE546_I24@PURE_QUANTA.Q_CAP(CHIPS)':
 C_PATH='@s9s_mb_2u_lib.s9s_mb_2u(sch_1):page546_i24@pure_quanta.q_cap(chips)';

PART_NAME
 C1137 'Q_CAP_0402-0.1UF,25V,10%,X7R,CA':;

SECTION_NUMBER 1
 '@S9S_MB_2U_LIB.S9S_MB_2U(SCH_1):PAGE546_I58@PURE_QUANTA.Q_CAP(CHIPS)':
 C_PATH='@s9s_mb_2u_lib.s9s_mb_2u(sch_1):page546_i58@pure_quanta.q_cap(chips)';

PART_NAME
 C1136 'Q_CAP_0402-0.1UF,25V,10%,X7R,CA':;

SECTION_NUMBER 1
 '@S9S_MB_2U_LIB.S9S_MB_2U(SCH_1):PAGE546_I105@PURE_QUANTA.Q_CAP(CHIPS)':
 C_PATH='@s9s_mb_2u_lib.s9s_mb_2u(sch_1):page546_i105@pure_quanta.q_cap(chips)';

PART_NAME
 C1135 'Q_CAP_0402-0.1UF,25V,10%,X7R,CA':;

SECTION_NUMBER 1
 '@S9S_MB_2U_LIB.S9S_MB_2U(SCH_1):PAGE546_I125@PURE_QUANTA.Q_CAP(CHIPS)':
 C_PATH='@s9s_mb_2u_lib.s9s_mb_2u(sch_1):page546_i125@pure_quanta.q_cap(chips)';

PART_NAME
 C1134 'Q_CAP_0402-0.1UF,25V,10%,X7R,CA':;

SECTION_NUMBER 1
 '@S9S_MB_2U_LIB.S9S_MB_2U(SCH_1):PAGE546_I45@PURE_QUANTA.Q_CAP(CHIPS)':
 C_PATH='@s9s_mb_2u_lib.s9s_mb_2u(sch_1):page546_i45@pure_quanta.q_cap(chips)';

PART_NAME
 C1133 'Q_CAP_0402-0.1UF,25V,10%,X7R,CA':;

SECTION_NUMBER 1
 '@S9S_MB_2U_LIB.S9S_MB_2U(SCH_1):PAGE546_I23@PURE_QUANTA.Q_CAP(CHIPS)':
 C_PATH='@s9s_mb_2u_lib.s9s_mb_2u(sch_1):page546_i23@pure_quanta.q_cap(chips)';

PART_NAME
 C1132 'Q_CAP_0402-0.1UF,25V,10%,X7R,CA':;

SECTION_NUMBER 1
 '@S9S_MB_2U_LIB.S9S_MB_2U(SCH_1):PAGE546_I59@PURE_QUANTA.Q_CAP(CHIPS)':
 C_PATH='@s9s_mb_2u_lib.s9s_mb_2u(sch_1):page546_i59@pure_quanta.q_cap(chips)';

PART_NAME
 C1131 'Q_CAP_0402-0.1UF,25V,10%,X7R,CA':;

SECTION_NUMBER 1
 '@S9S_MB_2U_LIB.S9S_MB_2U(SCH_1):PAGE546_I98@PURE_QUANTA.Q_CAP(CHIPS)':
 C_PATH='@s9s_mb_2u_lib.s9s_mb_2u(sch_1):page546_i98@pure_quanta.q_cap(chips)';

PART_NAME
 C1130 'Q_CAP_0402-0.1UF,25V,10%,X7R,CA':;

SECTION_NUMBER 1
 '@S9S_MB_2U_LIB.S9S_MB_2U(SCH_1):PAGE546_I106@PURE_QUANTA.Q_CAP(CHIPS)':
 C_PATH='@s9s_mb_2u_lib.s9s_mb_2u(sch_1):page546_i106@pure_quanta.q_cap(chips)';

PART_NAME
 C1129 'Q_CAP_0402-0.1UF,25V,10%,X7R,CA':;

SECTION_NUMBER 1
 '@S9S_MB_2U_LIB.S9S_MB_2U(SCH_1):PAGE546_I126@PURE_QUANTA.Q_CAP(CHIPS)':
 C_PATH='@s9s_mb_2u_lib.s9s_mb_2u(sch_1):page546_i126@pure_quanta.q_cap(chips)';

PART_NAME
 C1128 'Q_CAP_0402-0.1UF,25V,10%,X7R,CA':;

SECTION_NUMBER 1
 '@S9S_MB_2U_LIB.S9S_MB_2U(SCH_1):PAGE546_I46@PURE_QUANTA.Q_CAP(CHIPS)':
 C_PATH='@s9s_mb_2u_lib.s9s_mb_2u(sch_1):page546_i46@pure_quanta.q_cap(chips)';

PART_NAME
 C1127 'Q_CAP_0402-0.1UF,25V,10%,X7R,CA':;

SECTION_NUMBER 1
 '@S9S_MB_2U_LIB.S9S_MB_2U(SCH_1):PAGE546_I22@PURE_QUANTA.Q_CAP(CHIPS)':
 C_PATH='@s9s_mb_2u_lib.s9s_mb_2u(sch_1):page546_i22@pure_quanta.q_cap(chips)';

PART_NAME
 C1126 'Q_CAP_0402-0.1UF,25V,10%,X7R,CA':;

SECTION_NUMBER 1
 '@S9S_MB_2U_LIB.S9S_MB_2U(SCH_1):PAGE546_I60@PURE_QUANTA.Q_CAP(CHIPS)':
 C_PATH='@s9s_mb_2u_lib.s9s_mb_2u(sch_1):page546_i60@pure_quanta.q_cap(chips)';

PART_NAME
 C1125 'Q_CAP_0402-0.1UF,25V,10%,X7R,CA':;

SECTION_NUMBER 1
 '@S9S_MB_2U_LIB.S9S_MB_2U(SCH_1):PAGE546_I95@PURE_QUANTA.Q_CAP(CHIPS)':
 C_PATH='@s9s_mb_2u_lib.s9s_mb_2u(sch_1):page546_i95@pure_quanta.q_cap(chips)';

PART_NAME
 C1124 'Q_CAP_0402-0.1UF,25V,10%,X7R,CA':;

SECTION_NUMBER 1
 '@S9S_MB_2U_LIB.S9S_MB_2U(SCH_1):PAGE546_I107@PURE_QUANTA.Q_CAP(CHIPS)':
 C_PATH='@s9s_mb_2u_lib.s9s_mb_2u(sch_1):page546_i107@pure_quanta.q_cap(chips)';

PART_NAME
 C1123 'Q_CAP_0402-0.1UF,25V,10%,X7R,CA':;

SECTION_NUMBER 1
 '@S9S_MB_2U_LIB.S9S_MB_2U(SCH_1):PAGE546_I47@PURE_QUANTA.Q_CAP(CHIPS)':
 C_PATH='@s9s_mb_2u_lib.s9s_mb_2u(sch_1):page546_i47@pure_quanta.q_cap(chips)';

PART_NAME
 C1122 'Q_CAP_0402-0.1UF,25V,10%,X7R,CA':;

SECTION_NUMBER 1
 '@S9S_MB_2U_LIB.S9S_MB_2U(SCH_1):PAGE546_I20@PURE_QUANTA.Q_CAP(CHIPS)':
 C_PATH='@s9s_mb_2u_lib.s9s_mb_2u(sch_1):page546_i20@pure_quanta.q_cap(chips)';

PART_NAME
 C1121 'Q_CAP_0402-0.1UF,25V,10%,X7R,CA':;

SECTION_NUMBER 1
 '@S9S_MB_2U_LIB.S9S_MB_2U(SCH_1):PAGE546_I61@PURE_QUANTA.Q_CAP(CHIPS)':
 C_PATH='@s9s_mb_2u_lib.s9s_mb_2u(sch_1):page546_i61@pure_quanta.q_cap(chips)';

PART_NAME
 C1120 'Q_CAP_0402-0.1UF,25V,10%,X7R,CA':;

SECTION_NUMBER 1
 '@S9S_MB_2U_LIB.S9S_MB_2U(SCH_1):PAGE546_I133@PURE_QUANTA.Q_CAP(CHIPS)':
 C_PATH='@s9s_mb_2u_lib.s9s_mb_2u(sch_1):page546_i133@pure_quanta.q_cap(chips)';

PART_NAME
 C1119 'Q_CAP_0402-0.1UF,25V,10%,X7R,CA':;

SECTION_NUMBER 1
 '@S9S_MB_2U_LIB.S9S_MB_2U(SCH_1):PAGE546_I48@PURE_QUANTA.Q_CAP(CHIPS)':
 C_PATH='@s9s_mb_2u_lib.s9s_mb_2u(sch_1):page546_i48@pure_quanta.q_cap(chips)';

PART_NAME
 C1118 'Q_CAP_0402-0.1UF,25V,10%,X7R,CA':;

SECTION_NUMBER 1
 '@S9S_MB_2U_LIB.S9S_MB_2U(SCH_1):PAGE546_I21@PURE_QUANTA.Q_CAP(CHIPS)':
 C_PATH='@s9s_mb_2u_lib.s9s_mb_2u(sch_1):page546_i21@pure_quanta.q_cap(chips)';

PART_NAME
 C1117 'Q_CAP_0402-0.1UF,25V,10%,X7R,CA':;

SECTION_NUMBER 1
 '@S9S_MB_2U_LIB.S9S_MB_2U(SCH_1):PAGE546_I62@PURE_QUANTA.Q_CAP(CHIPS)':
 C_PATH='@s9s_mb_2u_lib.s9s_mb_2u(sch_1):page546_i62@pure_quanta.q_cap(chips)';

PART_NAME
 C1116 'Q_CAP_C0402-2.2UF,6.3V,20%,X6SA':;

SECTION_NUMBER 1
 '@S9S_MB_2U_LIB.S9S_MB_2U(SCH_1):PAGE546_I93@PURE_QUANTA.Q_CAP(CHIPS)':
 C_PATH='@s9s_mb_2u_lib.s9s_mb_2u(sch_1):page546_i93@pure_quanta.q_cap(chips)';

PART_NAME
 C1115 'Q_CAP_C0402-2.2UF,6.3V,20%,X6SA':;

SECTION_NUMBER 1
 '@S9S_MB_2U_LIB.S9S_MB_2U(SCH_1):PAGE546_I99@PURE_QUANTA.Q_CAP(CHIPS)':
 C_PATH='@s9s_mb_2u_lib.s9s_mb_2u(sch_1):page546_i99@pure_quanta.q_cap(chips)';

PART_NAME
 C1114 'Q_CAP_0402-0.1UF,25V,10%,X7R,CA':;

SECTION_NUMBER 1
 '@S9S_MB_2U_LIB.S9S_MB_2U(SCH_1):PAGE546_I49@PURE_QUANTA.Q_CAP(CHIPS)':
 C_PATH='@s9s_mb_2u_lib.s9s_mb_2u(sch_1):page546_i49@pure_quanta.q_cap(chips)';

PART_NAME
 C1113 'Q_CAP_0402-0.1UF,25V,10%,X7R,CA':;

SECTION_NUMBER 1
 '@S9S_MB_2U_LIB.S9S_MB_2U(SCH_1):PAGE546_I19@PURE_QUANTA.Q_CAP(CHIPS)':
 C_PATH='@s9s_mb_2u_lib.s9s_mb_2u(sch_1):page546_i19@pure_quanta.q_cap(chips)';

PART_NAME
 C1112 'Q_CAP_0402-0.1UF,25V,10%,X7R,CA':;

SECTION_NUMBER 1
 '@S9S_MB_2U_LIB.S9S_MB_2U(SCH_1):PAGE546_I63@PURE_QUANTA.Q_CAP(CHIPS)':
 C_PATH='@s9s_mb_2u_lib.s9s_mb_2u(sch_1):page546_i63@pure_quanta.q_cap(chips)';

PART_NAME
 C1111 'Q_CAP_0402-0.1UF,25V,10%,X7R,CA':;

SECTION_NUMBER 1
 '@S9S_MB_2U_LIB.S9S_MB_2U(SCH_1):PAGE546_I51@PURE_QUANTA.Q_CAP(CHIPS)':
 C_PATH='@s9s_mb_2u_lib.s9s_mb_2u(sch_1):page546_i51@pure_quanta.q_cap(chips)';

PART_NAME
 C1110 'Q_CAP_0402-0.1UF,25V,10%,X7R,CA':;

SECTION_NUMBER 1
 '@S9S_MB_2U_LIB.S9S_MB_2U(SCH_1):PAGE546_I18@PURE_QUANTA.Q_CAP(CHIPS)':
 C_PATH='@s9s_mb_2u_lib.s9s_mb_2u(sch_1):page546_i18@pure_quanta.q_cap(chips)';

PART_NAME
 C1109 'Q_CAP_0402-0.1UF,25V,10%,X7R,CA':;

SECTION_NUMBER 1
 '@S9S_MB_2U_LIB.S9S_MB_2U(SCH_1):PAGE546_I65@PURE_QUANTA.Q_CAP(CHIPS)':
 C_PATH='@s9s_mb_2u_lib.s9s_mb_2u(sch_1):page546_i65@pure_quanta.q_cap(chips)';

PART_NAME
 C1108 'Q_CAP_0402-0.1UF,25V,10%,X7R,CA':;

SECTION_NUMBER 1
 '@S9S_MB_2U_LIB.S9S_MB_2U(SCH_1):PAGE546_I52@PURE_QUANTA.Q_CAP(CHIPS)':
 C_PATH='@s9s_mb_2u_lib.s9s_mb_2u(sch_1):page546_i52@pure_quanta.q_cap(chips)';

PART_NAME
 C1107 'Q_CAP_0402-0.1UF,25V,10%,X7R,CA':;

SECTION_NUMBER 1
 '@S9S_MB_2U_LIB.S9S_MB_2U(SCH_1):PAGE546_I15@PURE_QUANTA.Q_CAP(CHIPS)':
 C_PATH='@s9s_mb_2u_lib.s9s_mb_2u(sch_1):page546_i15@pure_quanta.q_cap(chips)';

PART_NAME
 C1106 'Q_CAP_0402-0.1UF,25V,10%,X7R,CA':;

SECTION_NUMBER 1
 '@S9S_MB_2U_LIB.S9S_MB_2U(SCH_1):PAGE546_I66@PURE_QUANTA.Q_CAP(CHIPS)':
 C_PATH='@s9s_mb_2u_lib.s9s_mb_2u(sch_1):page546_i66@pure_quanta.q_cap(chips)';

PART_NAME
 R1605 'Q_RES_0402LF-1K,1%,1/16W,CHIP,A':;

SECTION_NUMBER 1
 '@S9S_MB_2U_LIB.S9S_MB_2U(SCH_1):PAGE526_I105@PURE_QUANTA.Q_RES(CHIPS)':
 C_PATH='@s9s_mb_2u_lib.s9s_mb_2u(sch_1):page526_i105@pure_quanta.q_res(chips)';

PART_NAME
 R1604 'Q_RES_0402LF-1K,1%,1/16W,CHIP,A':;

SECTION_NUMBER 1
 '@S9S_MB_2U_LIB.S9S_MB_2U(SCH_1):PAGE526_I109@PURE_QUANTA.Q_RES(CHIPS)':
 C_PATH='@s9s_mb_2u_lib.s9s_mb_2u(sch_1):page526_i109@pure_quanta.q_res(chips)';

PART_NAME
 R1397 'Q_RES_0402LF-10K,1%,1/16W,CHIPA':;

SECTION_NUMBER 1
 '@S9S_MB_2U_LIB.S9S_MB_2U(SCH_1):PAGE526_I225@PURE_QUANTA.Q_RES(CHIPS)':
 C_PATH='@s9s_mb_2u_lib.s9s_mb_2u(sch_1):page526_i225@pure_quanta.q_res(chips)';

PART_NAME
 R1396 'Q_RES_0402LF-10K,1%,1/16W,CHIPA':;

SECTION_NUMBER 1
 '@S9S_MB_2U_LIB.S9S_MB_2U(SCH_1):PAGE526_I167@PURE_QUANTA.Q_RES(CHIPS)':
 C_PATH='@s9s_mb_2u_lib.s9s_mb_2u(sch_1):page526_i167@pure_quanta.q_res(chips)';

PART_NAME
 R492 'Q_RES_0402LF-4.7K,1%,1/16W,EMPA':;

SECTION_NUMBER 1
 '@S9S_MB_2U_LIB.S9S_MB_2U(SCH_1):PAGE526_I230@PURE_QUANTA.Q_RES(CHIPS)':
 C_PATH='@s9s_mb_2u_lib.s9s_mb_2u(sch_1):page526_i230@pure_quanta.q_res(chips)';

PART_NAME
 R491 'Q_RES_0402LF-4.7K,1%,1/16W,EMPA':;

SECTION_NUMBER 1
 '@S9S_MB_2U_LIB.S9S_MB_2U(SCH_1):PAGE526_I164@PURE_QUANTA.Q_RES(CHIPS)':
 C_PATH='@s9s_mb_2u_lib.s9s_mb_2u(sch_1):page526_i164@pure_quanta.q_res(chips)';

PART_NAME
 R490 'Q_RES_0402LF-0,5%,1/16W,CHIP,CA':;

SECTION_NUMBER 1
 '@S9S_MB_2U_LIB.S9S_MB_2U(SCH_1):PAGE526_I229@PURE_QUANTA.Q_RES(CHIPS)':
 C_PATH='@s9s_mb_2u_lib.s9s_mb_2u(sch_1):page526_i229@pure_quanta.q_res(chips)';

PART_NAME
 R489 'Q_RES_0402LF-0,5%,1/16W,CHIP,CA':;

SECTION_NUMBER 1
 '@S9S_MB_2U_LIB.S9S_MB_2U(SCH_1):PAGE526_I228@PURE_QUANTA.Q_RES(CHIPS)':
 C_PATH='@s9s_mb_2u_lib.s9s_mb_2u(sch_1):page526_i228@pure_quanta.q_res(chips)';

PART_NAME
 R488 'Q_RES_0402LF-1K,1%,1/16W,EMPTYA':;

SECTION_NUMBER 1
 '@S9S_MB_2U_LIB.S9S_MB_2U(SCH_1):PAGE526_I226@PURE_QUANTA.Q_RES(CHIPS)':
 C_PATH='@s9s_mb_2u_lib.s9s_mb_2u(sch_1):page526_i226@pure_quanta.q_res(chips)';

PART_NAME
 R487 'Q_RES_0402LF-1K,1%,1/16W,EMPTYA':;

SECTION_NUMBER 1
 '@S9S_MB_2U_LIB.S9S_MB_2U(SCH_1):PAGE526_I173@PURE_QUANTA.Q_RES(CHIPS)':
 C_PATH='@s9s_mb_2u_lib.s9s_mb_2u(sch_1):page526_i173@pure_quanta.q_res(chips)';

PART_NAME
 R486 'Q_RES_0402LF-0,5%,1/16W,CHIP,CA':;

SECTION_NUMBER 1
 '@S9S_MB_2U_LIB.S9S_MB_2U(SCH_1):PAGE526_I162@PURE_QUANTA.Q_RES(CHIPS)':
 C_PATH='@s9s_mb_2u_lib.s9s_mb_2u(sch_1):page526_i162@pure_quanta.q_res(chips)';

PART_NAME
 R485 'Q_RES_0402LF-0,5%,1/16W,CHIP,CA':;

SECTION_NUMBER 1
 '@S9S_MB_2U_LIB.S9S_MB_2U(SCH_1):PAGE526_I122@PURE_QUANTA.Q_RES(CHIPS)':
 C_PATH='@s9s_mb_2u_lib.s9s_mb_2u(sch_1):page526_i122@pure_quanta.q_res(chips)';

PART_NAME
 R484 'Q_RES_0402LF-4.7K,1%,1/16W,EMPA':;

SECTION_NUMBER 1
 '@S9S_MB_2U_LIB.S9S_MB_2U(SCH_1):PAGE526_I170@PURE_QUANTA.Q_RES(CHIPS)':
 C_PATH='@s9s_mb_2u_lib.s9s_mb_2u(sch_1):page526_i170@pure_quanta.q_res(chips)';

PART_NAME
 R479 'Q_RES_0402LF-4.7K,1%,1/16W,CHIA':;

SECTION_NUMBER 1
 '@S9S_MB_2U_LIB.S9S_MB_2U(SCH_1):PAGE526_I227@PURE_QUANTA.Q_RES(CHIPS)':
 C_PATH='@s9s_mb_2u_lib.s9s_mb_2u(sch_1):page526_i227@pure_quanta.q_res(chips)';

PART_NAME
 R478 'Q_RES_0402LF-4.7K,1%,1/16W,CHIA':;

SECTION_NUMBER 1
 '@S9S_MB_2U_LIB.S9S_MB_2U(SCH_1):PAGE526_I176@PURE_QUANTA.Q_RES(CHIPS)':
 C_PATH='@s9s_mb_2u_lib.s9s_mb_2u(sch_1):page526_i176@pure_quanta.q_res(chips)';

PART_NAME
 J60 'SCONN75K_APCI0155P004A-SCONN75A':;

SECTION_NUMBER 1
 '@S9S_MB_2U_LIB.S9S_MB_2U(SCH_1):PAGE526_I224@PURE_QUANTA.SCONN75K_APCI0155P004A(CHIPS)':
 C_PATH='@s9s_mb_2u_lib.s9s_mb_2u(sch_1):page526_i224@pure_quanta.sconn75k_apci015~
5p004a(chips)';

PART_NAME
 J59 'SCONN75K_APCI0155P004A-SCONN75A':;

SECTION_NUMBER 1
 '@S9S_MB_2U_LIB.S9S_MB_2U(SCH_1):PAGE526_I178@PURE_QUANTA.SCONN75K_APCI0155P004A(CHIPS)':
 C_PATH='@s9s_mb_2u_lib.s9s_mb_2u(sch_1):page526_i178@pure_quanta.sconn75k_apci015~
5p004a(chips)';

PART_NAME
 C1421 'Q_CAP_DIFFBUS_C0201-DIFF BUS_0B':;

SECTION_NUMBER 1
 '@S9S_MB_2U_LIB.S9S_MB_2U(SCH_1):PAGE526_I246@PURE_QUANTA.Q_CAP_DIFFBUS(CHIPS)':
 C_PATH='@s9s_mb_2u_lib.s9s_mb_2u(sch_1):page526_i246@pure_quanta.q_cap_diffbus(ch~
ips)';

PART_NAME
 C1420 'Q_CAP_DIFFBUS_C0201-DIFF BUS_0B':;

SECTION_NUMBER 1
 '@S9S_MB_2U_LIB.S9S_MB_2U(SCH_1):PAGE526_I243@PURE_QUANTA.Q_CAP_DIFFBUS(CHIPS)':
 C_PATH='@s9s_mb_2u_lib.s9s_mb_2u(sch_1):page526_i243@pure_quanta.q_cap_diffbus(ch~
ips)';

PART_NAME
 C1419 'Q_CAP_DIFFBUS_C0201-DIFF BUS_0B':;

SECTION_NUMBER 1
 '@S9S_MB_2U_LIB.S9S_MB_2U(SCH_1):PAGE526_I240@PURE_QUANTA.Q_CAP_DIFFBUS(CHIPS)':
 C_PATH='@s9s_mb_2u_lib.s9s_mb_2u(sch_1):page526_i240@pure_quanta.q_cap_diffbus(ch~
ips)';

PART_NAME
 C1418 'Q_CAP_DIFFBUS_C0201-DIFF BUS_0B':;

SECTION_NUMBER 1
 '@S9S_MB_2U_LIB.S9S_MB_2U(SCH_1):PAGE526_I239@PURE_QUANTA.Q_CAP_DIFFBUS(CHIPS)':
 C_PATH='@s9s_mb_2u_lib.s9s_mb_2u(sch_1):page526_i239@pure_quanta.q_cap_diffbus(ch~
ips)';

PART_NAME
 C1089 'Q_CAP_0402-0.1UF,25V,10%,X7R,CA':;

SECTION_NUMBER 1
 '@S9S_MB_2U_LIB.S9S_MB_2U(SCH_1):PAGE526_I95@PURE_QUANTA.Q_CAP(CHIPS)':
 C_PATH='@s9s_mb_2u_lib.s9s_mb_2u(sch_1):page526_i95@pure_quanta.q_cap(chips)';

PART_NAME
 C1088 'Q_CAP_0402-0.1UF,25V,10%,X7R,CA':;

SECTION_NUMBER 1
 '@S9S_MB_2U_LIB.S9S_MB_2U(SCH_1):PAGE526_I100@PURE_QUANTA.Q_CAP(CHIPS)':
 C_PATH='@s9s_mb_2u_lib.s9s_mb_2u(sch_1):page526_i100@pure_quanta.q_cap(chips)';

PART_NAME
 C1087 'Q_CAP_0402-0.1UF,25V,10%,X7R,CA':;

SECTION_NUMBER 1
 '@S9S_MB_2U_LIB.S9S_MB_2U(SCH_1):PAGE526_I93@PURE_QUANTA.Q_CAP(CHIPS)':
 C_PATH='@s9s_mb_2u_lib.s9s_mb_2u(sch_1):page526_i93@pure_quanta.q_cap(chips)';

PART_NAME
 C1086 'Q_CAP_0402-0.1UF,25V,10%,X7R,CA':;

SECTION_NUMBER 1
 '@S9S_MB_2U_LIB.S9S_MB_2U(SCH_1):PAGE526_I98@PURE_QUANTA.Q_CAP(CHIPS)':
 C_PATH='@s9s_mb_2u_lib.s9s_mb_2u(sch_1):page526_i98@pure_quanta.q_cap(chips)';

PART_NAME
 C1085 'Q_CAP_0402-0.1UF,25V,10%,X7R,CA':;

SECTION_NUMBER 1
 '@S9S_MB_2U_LIB.S9S_MB_2U(SCH_1):PAGE526_I92@PURE_QUANTA.Q_CAP(CHIPS)':
 C_PATH='@s9s_mb_2u_lib.s9s_mb_2u(sch_1):page526_i92@pure_quanta.q_cap(chips)';

PART_NAME
 C1084 'Q_CAP_0402-0.1UF,25V,10%,X7R,CA':;

SECTION_NUMBER 1
 '@S9S_MB_2U_LIB.S9S_MB_2U(SCH_1):PAGE526_I97@PURE_QUANTA.Q_CAP(CHIPS)':
 C_PATH='@s9s_mb_2u_lib.s9s_mb_2u(sch_1):page526_i97@pure_quanta.q_cap(chips)';

PART_NAME
 C1083 'Q_CAP_C0603-22UF,6.3V,20%,X6S,A':;

SECTION_NUMBER 1
 '@S9S_MB_2U_LIB.S9S_MB_2U(SCH_1):PAGE526_I91@PURE_QUANTA.Q_CAP(CHIPS)':
 C_PATH='@s9s_mb_2u_lib.s9s_mb_2u(sch_1):page526_i91@pure_quanta.q_cap(chips)';

PART_NAME
 C1082 'Q_CAP_C0603-22UF,6.3V,20%,X6S,A':;

SECTION_NUMBER 1
 '@S9S_MB_2U_LIB.S9S_MB_2U(SCH_1):PAGE526_I96@PURE_QUANTA.Q_CAP(CHIPS)':
 C_PATH='@s9s_mb_2u_lib.s9s_mb_2u(sch_1):page526_i96@pure_quanta.q_cap(chips)';

PART_NAME
 C1081 'Q_CAP_C0603-22UF,6.3V,20%,X6S,A':;

SECTION_NUMBER 1
 '@S9S_MB_2U_LIB.S9S_MB_2U(SCH_1):PAGE526_I76@PURE_QUANTA.Q_CAP(CHIPS)':
 C_PATH='@s9s_mb_2u_lib.s9s_mb_2u(sch_1):page526_i76@pure_quanta.q_cap(chips)';

PART_NAME
 C1080 'Q_CAP_C0603-22UF,6.3V,20%,X6S,A':;

SECTION_NUMBER 1
 '@S9S_MB_2U_LIB.S9S_MB_2U(SCH_1):PAGE526_I90@PURE_QUANTA.Q_CAP(CHIPS)':
 C_PATH='@s9s_mb_2u_lib.s9s_mb_2u(sch_1):page526_i90@pure_quanta.q_cap(chips)';

PART_NAME
 C1079 'Q_CAP_C0603-22UF,6.3V,20%,X6S,A':;

SECTION_NUMBER 1
 '@S9S_MB_2U_LIB.S9S_MB_2U(SCH_1):PAGE526_I75@PURE_QUANTA.Q_CAP(CHIPS)':
 C_PATH='@s9s_mb_2u_lib.s9s_mb_2u(sch_1):page526_i75@pure_quanta.q_cap(chips)';

PART_NAME
 C1078 'Q_CAP_C0603-22UF,6.3V,20%,X6S,A':;

SECTION_NUMBER 1
 '@S9S_MB_2U_LIB.S9S_MB_2U(SCH_1):PAGE526_I88@PURE_QUANTA.Q_CAP(CHIPS)':
 C_PATH='@s9s_mb_2u_lib.s9s_mb_2u(sch_1):page526_i88@pure_quanta.q_cap(chips)';

PART_NAME
 R1865 'Q_RES_0402LF-33.2,1%,1/16W,CHIA':;

SECTION_NUMBER 1
 '@S9S_MB_2U_LIB.S9S_MB_2U(SCH_1):PAGE499_I146@PURE_QUANTA.Q_RES(CHIPS)':
 C_PATH='@s9s_mb_2u_lib.s9s_mb_2u(sch_1):page499_i146@pure_quanta.q_res(chips)';

PART_NAME
 R1864 'Q_RES_0402LF-33.2,1%,1/16W,CHIA':;

SECTION_NUMBER 1
 '@S9S_MB_2U_LIB.S9S_MB_2U(SCH_1):PAGE499_I144@PURE_QUANTA.Q_RES(CHIPS)':
 C_PATH='@s9s_mb_2u_lib.s9s_mb_2u(sch_1):page499_i144@pure_quanta.q_res(chips)';

PART_NAME
 R1620 'Q_RES_0402LF-100,1%,1/16W,CHIPA':;

SECTION_NUMBER 1
 '@S9S_MB_2U_LIB.S9S_MB_2U(SCH_1):PAGE499_I93@PURE_QUANTA.Q_RES(CHIPS)':
 C_PATH='@s9s_mb_2u_lib.s9s_mb_2u(sch_1):page499_i93@pure_quanta.q_res(chips)';

PART_NAME
 R1619 'Q_RES_0402LF-4.7K,5%,1/16W,CHIA':;

SECTION_NUMBER 1
 '@S9S_MB_2U_LIB.S9S_MB_2U(SCH_1):PAGE499_I95@PURE_QUANTA.Q_RES(CHIPS)':
 C_PATH='@s9s_mb_2u_lib.s9s_mb_2u(sch_1):page499_i95@pure_quanta.q_res(chips)';

PART_NAME
 R1612 'Q_RES_0402LF-10K,1%,1/16W,CHIPA':;

SECTION_NUMBER 1
 '@S9S_MB_2U_LIB.S9S_MB_2U(SCH_1):PAGE499_I85@PURE_QUANTA.Q_RES(CHIPS)':
 C_PATH='@s9s_mb_2u_lib.s9s_mb_2u(sch_1):page499_i85@pure_quanta.q_res(chips)';

PART_NAME
 R1591 'Q_RES_0402LF-0,5%,1/16W,CHIP,CA':;

SECTION_NUMBER 1
 '@S9S_MB_2U_LIB.S9S_MB_2U(SCH_1):PAGE499_I124@PURE_QUANTA.Q_RES(CHIPS)':
 C_PATH='@s9s_mb_2u_lib.s9s_mb_2u(sch_1):page499_i124@pure_quanta.q_res(chips)';

PART_NAME
 R1590 'Q_RES_0402LF-10K,5%,1/16W,EMPTA':;

SECTION_NUMBER 1
 '@S9S_MB_2U_LIB.S9S_MB_2U(SCH_1):PAGE499_I126@PURE_QUANTA.Q_RES(CHIPS)':
 C_PATH='@s9s_mb_2u_lib.s9s_mb_2u(sch_1):page499_i126@pure_quanta.q_res(chips)';

PART_NAME
 R408 'Q_RES_0402LF-10K,1%,1/16W,CHIPA':;

SECTION_NUMBER 1
 '@S9S_MB_2U_LIB.S9S_MB_2U(SCH_1):PAGE499_I78@PURE_QUANTA.Q_RES(CHIPS)':
 C_PATH='@s9s_mb_2u_lib.s9s_mb_2u(sch_1):page499_i78@pure_quanta.q_res(chips)';

PART_NAME
 R407 'Q_RES_0402LF-10K,1%,1/16W,CHIPA':;

SECTION_NUMBER 1
 '@S9S_MB_2U_LIB.S9S_MB_2U(SCH_1):PAGE499_I77@PURE_QUANTA.Q_RES(CHIPS)':
 C_PATH='@s9s_mb_2u_lib.s9s_mb_2u(sch_1):page499_i77@pure_quanta.q_res(chips)';

PART_NAME
 R406 'Q_RES_0402LF-4.7K,5%,1/16W,CHIA':;

SECTION_NUMBER 1
 '@S9S_MB_2U_LIB.S9S_MB_2U(SCH_1):PAGE499_I70@PURE_QUANTA.Q_RES(CHIPS)':
 C_PATH='@s9s_mb_2u_lib.s9s_mb_2u(sch_1):page499_i70@pure_quanta.q_res(chips)';

PART_NAME
 J36 'SCONN84_123318136-SCONN84_1-23A':;

SECTION_NUMBER 1
 '@S9S_MB_2U_LIB.S9S_MB_2U(SCH_1):PAGE499_I52@PURE_QUANTA.SCONN84_123318136(CHIPS)':
 C_PATH='@s9s_mb_2u_lib.s9s_mb_2u(sch_1):page499_i52@pure_quanta.sconn84_123318136~
(chips)';

PART_NAME
 C1221 'Q_CAP_0402-0.1UF,25V,10%,X7R,CA':;

SECTION_NUMBER 1
 '@S9S_MB_2U_LIB.S9S_MB_2U(SCH_1):PAGE499_I89@PURE_QUANTA.Q_CAP(CHIPS)':
 C_PATH='@s9s_mb_2u_lib.s9s_mb_2u(sch_1):page499_i89@pure_quanta.q_cap(chips)';

PART_NAME
 C1220 'Q_CAP_0402-0.1UF,25V,10%,X7R,CA':;

SECTION_NUMBER 1
 '@S9S_MB_2U_LIB.S9S_MB_2U(SCH_1):PAGE499_I91@PURE_QUANTA.Q_CAP(CHIPS)':
 C_PATH='@s9s_mb_2u_lib.s9s_mb_2u(sch_1):page499_i91@pure_quanta.q_cap(chips)';

PART_NAME
 C1077 'Q_CAP_C0805-22UF,16V,20%,X6S,CA':;

SECTION_NUMBER 1
 '@S9S_MB_2U_LIB.S9S_MB_2U(SCH_1):PAGE499_I11@PURE_QUANTA.Q_CAP(CHIPS)':
 C_PATH='@s9s_mb_2u_lib.s9s_mb_2u(sch_1):page499_i11@pure_quanta.q_cap(chips)';

PART_NAME
 C1076 'Q_CAP_0402-0.1UF,25V,10%,X7R,CA':;

SECTION_NUMBER 1
 '@S9S_MB_2U_LIB.S9S_MB_2U(SCH_1):PAGE499_I13@PURE_QUANTA.Q_CAP(CHIPS)':
 C_PATH='@s9s_mb_2u_lib.s9s_mb_2u(sch_1):page499_i13@pure_quanta.q_cap(chips)';

PART_NAME
 C1075 'Q_CAP_0402-0.1UF,25V,10%,X7R,CA':;

SECTION_NUMBER 1
 '@S9S_MB_2U_LIB.S9S_MB_2U(SCH_1):PAGE499_I36@PURE_QUANTA.Q_CAP(CHIPS)':
 C_PATH='@s9s_mb_2u_lib.s9s_mb_2u(sch_1):page499_i36@pure_quanta.q_cap(chips)';

PART_NAME
 C1074 'Q_CAP_0402-0.1UF,25V,10%,X7R,CA':;

SECTION_NUMBER 1
 '@S9S_MB_2U_LIB.S9S_MB_2U(SCH_1):PAGE499_I37@PURE_QUANTA.Q_CAP(CHIPS)':
 C_PATH='@s9s_mb_2u_lib.s9s_mb_2u(sch_1):page499_i37@pure_quanta.q_cap(chips)';

PART_NAME
 C1073 'Q_CAP_0402-0.1UF,25V,10%,X7R,CA':;

SECTION_NUMBER 1
 '@S9S_MB_2U_LIB.S9S_MB_2U(SCH_1):PAGE499_I38@PURE_QUANTA.Q_CAP(CHIPS)':
 C_PATH='@s9s_mb_2u_lib.s9s_mb_2u(sch_1):page499_i38@pure_quanta.q_cap(chips)';

PART_NAME
 C1072 'Q_CAP_0402-0.1UF,25V,10%,X7R,CA':;

SECTION_NUMBER 1
 '@S9S_MB_2U_LIB.S9S_MB_2U(SCH_1):PAGE499_I39@PURE_QUANTA.Q_CAP(CHIPS)':
 C_PATH='@s9s_mb_2u_lib.s9s_mb_2u(sch_1):page499_i39@pure_quanta.q_cap(chips)';

PART_NAME
 C1071 'Q_CAP_C0805-22UF,16V,20%,X6S,CA':;

SECTION_NUMBER 1
 '@S9S_MB_2U_LIB.S9S_MB_2U(SCH_1):PAGE499_I59@PURE_QUANTA.Q_CAP(CHIPS)':
 C_PATH='@s9s_mb_2u_lib.s9s_mb_2u(sch_1):page499_i59@pure_quanta.q_cap(chips)';

PART_NAME
 C1070 'Q_CAP_C0805-22UF,16V,20%,X6S,CA':;

SECTION_NUMBER 1
 '@S9S_MB_2U_LIB.S9S_MB_2U(SCH_1):PAGE499_I17@PURE_QUANTA.Q_CAP(CHIPS)':
 C_PATH='@s9s_mb_2u_lib.s9s_mb_2u(sch_1):page499_i17@pure_quanta.q_cap(chips)';

PART_NAME
 R1863 'Q_RES_0402LF-33.2,1%,1/16W,CHIA':;

SECTION_NUMBER 1
 '@S9S_MB_2U_LIB.S9S_MB_2U(SCH_1):PAGE498_I144@PURE_QUANTA.Q_RES(CHIPS)':
 C_PATH='@s9s_mb_2u_lib.s9s_mb_2u(sch_1):page498_i144@pure_quanta.q_res(chips)';

PART_NAME
 R1862 'Q_RES_0402LF-33.2,1%,1/16W,CHIA':;

SECTION_NUMBER 1
 '@S9S_MB_2U_LIB.S9S_MB_2U(SCH_1):PAGE498_I142@PURE_QUANTA.Q_RES(CHIPS)':
 C_PATH='@s9s_mb_2u_lib.s9s_mb_2u(sch_1):page498_i142@pure_quanta.q_res(chips)';

PART_NAME
 R1618 'Q_RES_0402LF-100,1%,1/16W,CHIPA':;

SECTION_NUMBER 1
 '@S9S_MB_2U_LIB.S9S_MB_2U(SCH_1):PAGE498_I93@PURE_QUANTA.Q_RES(CHIPS)':
 C_PATH='@s9s_mb_2u_lib.s9s_mb_2u(sch_1):page498_i93@pure_quanta.q_res(chips)';

PART_NAME
 R1617 'Q_RES_0402LF-4.7K,5%,1/16W,CHIA':;

SECTION_NUMBER 1
 '@S9S_MB_2U_LIB.S9S_MB_2U(SCH_1):PAGE498_I95@PURE_QUANTA.Q_RES(CHIPS)':
 C_PATH='@s9s_mb_2u_lib.s9s_mb_2u(sch_1):page498_i95@pure_quanta.q_res(chips)';

PART_NAME
 R1611 'Q_RES_0402LF-10K,1%,1/16W,CHIPA':;

SECTION_NUMBER 1
 '@S9S_MB_2U_LIB.S9S_MB_2U(SCH_1):PAGE498_I85@PURE_QUANTA.Q_RES(CHIPS)':
 C_PATH='@s9s_mb_2u_lib.s9s_mb_2u(sch_1):page498_i85@pure_quanta.q_res(chips)';

PART_NAME
 R1589 'Q_RES_0402LF-0,5%,1/16W,CHIP,CA':;

SECTION_NUMBER 1
 '@S9S_MB_2U_LIB.S9S_MB_2U(SCH_1):PAGE498_I120@PURE_QUANTA.Q_RES(CHIPS)':
 C_PATH='@s9s_mb_2u_lib.s9s_mb_2u(sch_1):page498_i120@pure_quanta.q_res(chips)';

PART_NAME
 R1588 'Q_RES_0402LF-10K,5%,1/16W,EMPTA':;

SECTION_NUMBER 1
 '@S9S_MB_2U_LIB.S9S_MB_2U(SCH_1):PAGE498_I121@PURE_QUANTA.Q_RES(CHIPS)':
 C_PATH='@s9s_mb_2u_lib.s9s_mb_2u(sch_1):page498_i121@pure_quanta.q_res(chips)';

PART_NAME
 R404 'Q_RES_0402LF-10K,1%,1/16W,CHIPA':;

SECTION_NUMBER 1
 '@S9S_MB_2U_LIB.S9S_MB_2U(SCH_1):PAGE498_I78@PURE_QUANTA.Q_RES(CHIPS)':
 C_PATH='@s9s_mb_2u_lib.s9s_mb_2u(sch_1):page498_i78@pure_quanta.q_res(chips)';

PART_NAME
 R403 'Q_RES_0402LF-10K,1%,1/16W,CHIPA':;

SECTION_NUMBER 1
 '@S9S_MB_2U_LIB.S9S_MB_2U(SCH_1):PAGE498_I77@PURE_QUANTA.Q_RES(CHIPS)':
 C_PATH='@s9s_mb_2u_lib.s9s_mb_2u(sch_1):page498_i77@pure_quanta.q_res(chips)';

PART_NAME
 R402 'Q_RES_0402LF-4.7K,5%,1/16W,CHIA':;

SECTION_NUMBER 1
 '@S9S_MB_2U_LIB.S9S_MB_2U(SCH_1):PAGE498_I70@PURE_QUANTA.Q_RES(CHIPS)':
 C_PATH='@s9s_mb_2u_lib.s9s_mb_2u(sch_1):page498_i70@pure_quanta.q_res(chips)';

PART_NAME
 J35 'SCONN84_123318136-SCONN84_1-23A':;

SECTION_NUMBER 1
 '@S9S_MB_2U_LIB.S9S_MB_2U(SCH_1):PAGE498_I64@PURE_QUANTA.SCONN84_123318136(CHIPS)':
 C_PATH='@s9s_mb_2u_lib.s9s_mb_2u(sch_1):page498_i64@pure_quanta.sconn84_123318136~
(chips)';

PART_NAME
 C1219 'Q_CAP_0402-0.1UF,25V,10%,X7R,CA':;

SECTION_NUMBER 1
 '@S9S_MB_2U_LIB.S9S_MB_2U(SCH_1):PAGE498_I89@PURE_QUANTA.Q_CAP(CHIPS)':
 C_PATH='@s9s_mb_2u_lib.s9s_mb_2u(sch_1):page498_i89@pure_quanta.q_cap(chips)';

PART_NAME
 C1218 'Q_CAP_0402-0.1UF,25V,10%,X7R,CA':;

SECTION_NUMBER 1
 '@S9S_MB_2U_LIB.S9S_MB_2U(SCH_1):PAGE498_I91@PURE_QUANTA.Q_CAP(CHIPS)':
 C_PATH='@s9s_mb_2u_lib.s9s_mb_2u(sch_1):page498_i91@pure_quanta.q_cap(chips)';

PART_NAME
 C1069 'Q_CAP_C0805-22UF,16V,20%,X6S,CA':;

SECTION_NUMBER 1
 '@S9S_MB_2U_LIB.S9S_MB_2U(SCH_1):PAGE498_I2@PURE_QUANTA.Q_CAP(CHIPS)':
 C_PATH='@s9s_mb_2u_lib.s9s_mb_2u(sch_1):page498_i2@pure_quanta.q_cap(chips)';

PART_NAME
 C1068 'Q_CAP_0402-0.1UF,25V,10%,X7R,CA':;

SECTION_NUMBER 1
 '@S9S_MB_2U_LIB.S9S_MB_2U(SCH_1):PAGE498_I28@PURE_QUANTA.Q_CAP(CHIPS)':
 C_PATH='@s9s_mb_2u_lib.s9s_mb_2u(sch_1):page498_i28@pure_quanta.q_cap(chips)';

PART_NAME
 C1067 'Q_CAP_0402-0.1UF,25V,10%,X7R,CA':;

SECTION_NUMBER 1
 '@S9S_MB_2U_LIB.S9S_MB_2U(SCH_1):PAGE498_I29@PURE_QUANTA.Q_CAP(CHIPS)':
 C_PATH='@s9s_mb_2u_lib.s9s_mb_2u(sch_1):page498_i29@pure_quanta.q_cap(chips)';

PART_NAME
 C1066 'Q_CAP_0402-0.1UF,25V,10%,X7R,CA':;

SECTION_NUMBER 1
 '@S9S_MB_2U_LIB.S9S_MB_2U(SCH_1):PAGE498_I30@PURE_QUANTA.Q_CAP(CHIPS)':
 C_PATH='@s9s_mb_2u_lib.s9s_mb_2u(sch_1):page498_i30@pure_quanta.q_cap(chips)';

PART_NAME
 C1065 'Q_CAP_0402-0.1UF,25V,10%,X7R,CA':;

SECTION_NUMBER 1
 '@S9S_MB_2U_LIB.S9S_MB_2U(SCH_1):PAGE498_I33@PURE_QUANTA.Q_CAP(CHIPS)':
 C_PATH='@s9s_mb_2u_lib.s9s_mb_2u(sch_1):page498_i33@pure_quanta.q_cap(chips)';

PART_NAME
 C1064 'Q_CAP_0402-0.1UF,25V,10%,X7R,CA':;

SECTION_NUMBER 1
 '@S9S_MB_2U_LIB.S9S_MB_2U(SCH_1):PAGE498_I37@PURE_QUANTA.Q_CAP(CHIPS)':
 C_PATH='@s9s_mb_2u_lib.s9s_mb_2u(sch_1):page498_i37@pure_quanta.q_cap(chips)';

PART_NAME
 C1063 'Q_CAP_C0805-22UF,16V,20%,X6S,CA':;

SECTION_NUMBER 1
 '@S9S_MB_2U_LIB.S9S_MB_2U(SCH_1):PAGE498_I39@PURE_QUANTA.Q_CAP(CHIPS)':
 C_PATH='@s9s_mb_2u_lib.s9s_mb_2u(sch_1):page498_i39@pure_quanta.q_cap(chips)';

PART_NAME
 C1062 'Q_CAP_C0805-22UF,16V,20%,X6S,CA':;

SECTION_NUMBER 1
 '@S9S_MB_2U_LIB.S9S_MB_2U(SCH_1):PAGE498_I40@PURE_QUANTA.Q_CAP(CHIPS)':
 C_PATH='@s9s_mb_2u_lib.s9s_mb_2u(sch_1):page498_i40@pure_quanta.q_cap(chips)';

PART_NAME
 R1861 'Q_RES_0402LF-33.2,1%,1/16W,CHIA':;

SECTION_NUMBER 1
 '@S9S_MB_2U_LIB.S9S_MB_2U(SCH_1):PAGE497_I106@PURE_QUANTA.Q_RES(CHIPS)':
 C_PATH='@s9s_mb_2u_lib.s9s_mb_2u(sch_1):page497_i106@pure_quanta.q_res(chips)';

PART_NAME
 R1860 'Q_RES_0402LF-33.2,1%,1/16W,CHIA':;

SECTION_NUMBER 1
 '@S9S_MB_2U_LIB.S9S_MB_2U(SCH_1):PAGE497_I104@PURE_QUANTA.Q_RES(CHIPS)':
 C_PATH='@s9s_mb_2u_lib.s9s_mb_2u(sch_1):page497_i104@pure_quanta.q_res(chips)';

PART_NAME
 R1616 'Q_RES_0402LF-100,1%,1/16W,CHIPA':;

SECTION_NUMBER 1
 '@S9S_MB_2U_LIB.S9S_MB_2U(SCH_1):PAGE497_I93@PURE_QUANTA.Q_RES(CHIPS)':
 C_PATH='@s9s_mb_2u_lib.s9s_mb_2u(sch_1):page497_i93@pure_quanta.q_res(chips)';

PART_NAME
 R1615 'Q_RES_0402LF-4.7K,5%,1/16W,CHIA':;

SECTION_NUMBER 1
 '@S9S_MB_2U_LIB.S9S_MB_2U(SCH_1):PAGE497_I95@PURE_QUANTA.Q_RES(CHIPS)':
 C_PATH='@s9s_mb_2u_lib.s9s_mb_2u(sch_1):page497_i95@pure_quanta.q_res(chips)';

PART_NAME
 R1610 'Q_RES_0402LF-10K,1%,1/16W,CHIPA':;

SECTION_NUMBER 1
 '@S9S_MB_2U_LIB.S9S_MB_2U(SCH_1):PAGE497_I85@PURE_QUANTA.Q_RES(CHIPS)':
 C_PATH='@s9s_mb_2u_lib.s9s_mb_2u(sch_1):page497_i85@pure_quanta.q_res(chips)';

PART_NAME
 R1587 'Q_RES_0402LF-0,5%,1/16W,CHIP,CA':;

SECTION_NUMBER 1
 '@S9S_MB_2U_LIB.S9S_MB_2U(SCH_1):PAGE497_I98@PURE_QUANTA.Q_RES(CHIPS)':
 C_PATH='@s9s_mb_2u_lib.s9s_mb_2u(sch_1):page497_i98@pure_quanta.q_res(chips)';

PART_NAME
 R1586 'Q_RES_0402LF-10K,5%,1/16W,EMPTA':;

SECTION_NUMBER 1
 '@S9S_MB_2U_LIB.S9S_MB_2U(SCH_1):PAGE497_I100@PURE_QUANTA.Q_RES(CHIPS)':
 C_PATH='@s9s_mb_2u_lib.s9s_mb_2u(sch_1):page497_i100@pure_quanta.q_res(chips)';

PART_NAME
 R400 'Q_RES_0402LF-10K,1%,1/16W,CHIPA':;

SECTION_NUMBER 1
 '@S9S_MB_2U_LIB.S9S_MB_2U(SCH_1):PAGE497_I78@PURE_QUANTA.Q_RES(CHIPS)':
 C_PATH='@s9s_mb_2u_lib.s9s_mb_2u(sch_1):page497_i78@pure_quanta.q_res(chips)';

PART_NAME
 R399 'Q_RES_0402LF-10K,1%,1/16W,CHIPA':;

SECTION_NUMBER 1
 '@S9S_MB_2U_LIB.S9S_MB_2U(SCH_1):PAGE497_I77@PURE_QUANTA.Q_RES(CHIPS)':
 C_PATH='@s9s_mb_2u_lib.s9s_mb_2u(sch_1):page497_i77@pure_quanta.q_res(chips)';

PART_NAME
 R398 'Q_RES_0402LF-4.7K,5%,1/16W,CHIA':;

SECTION_NUMBER 1
 '@S9S_MB_2U_LIB.S9S_MB_2U(SCH_1):PAGE497_I71@PURE_QUANTA.Q_RES(CHIPS)':
 C_PATH='@s9s_mb_2u_lib.s9s_mb_2u(sch_1):page497_i71@pure_quanta.q_res(chips)';

PART_NAME
 J34 'SCONN84_123318136-SCONN84_1-23A':;

SECTION_NUMBER 1
 '@S9S_MB_2U_LIB.S9S_MB_2U(SCH_1):PAGE497_I43@PURE_QUANTA.SCONN84_123318136(CHIPS)':
 C_PATH='@s9s_mb_2u_lib.s9s_mb_2u(sch_1):page497_i43@pure_quanta.sconn84_123318136~
(chips)';

PART_NAME
 C1217 'Q_CAP_0402-0.1UF,25V,10%,X7R,CA':;

SECTION_NUMBER 1
 '@S9S_MB_2U_LIB.S9S_MB_2U(SCH_1):PAGE497_I89@PURE_QUANTA.Q_CAP(CHIPS)':
 C_PATH='@s9s_mb_2u_lib.s9s_mb_2u(sch_1):page497_i89@pure_quanta.q_cap(chips)';

PART_NAME
 C1216 'Q_CAP_0402-0.1UF,25V,10%,X7R,CA':;

SECTION_NUMBER 1
 '@S9S_MB_2U_LIB.S9S_MB_2U(SCH_1):PAGE497_I91@PURE_QUANTA.Q_CAP(CHIPS)':
 C_PATH='@s9s_mb_2u_lib.s9s_mb_2u(sch_1):page497_i91@pure_quanta.q_cap(chips)';

PART_NAME
 C1061 'Q_CAP_C0805-22UF,16V,20%,X6S,CA':;

SECTION_NUMBER 1
 '@S9S_MB_2U_LIB.S9S_MB_2U(SCH_1):PAGE497_I53@PURE_QUANTA.Q_CAP(CHIPS)':
 C_PATH='@s9s_mb_2u_lib.s9s_mb_2u(sch_1):page497_i53@pure_quanta.q_cap(chips)';

PART_NAME
 C1060 'Q_CAP_0402-0.1UF,25V,10%,X7R,CA':;

SECTION_NUMBER 1
 '@S9S_MB_2U_LIB.S9S_MB_2U(SCH_1):PAGE497_I54@PURE_QUANTA.Q_CAP(CHIPS)':
 C_PATH='@s9s_mb_2u_lib.s9s_mb_2u(sch_1):page497_i54@pure_quanta.q_cap(chips)';

PART_NAME
 C1059 'Q_CAP_0402-0.1UF,25V,10%,X7R,CA':;

SECTION_NUMBER 1
 '@S9S_MB_2U_LIB.S9S_MB_2U(SCH_1):PAGE497_I56@PURE_QUANTA.Q_CAP(CHIPS)':
 C_PATH='@s9s_mb_2u_lib.s9s_mb_2u(sch_1):page497_i56@pure_quanta.q_cap(chips)';

PART_NAME
 C1058 'Q_CAP_0402-0.1UF,25V,10%,X7R,CA':;

SECTION_NUMBER 1
 '@S9S_MB_2U_LIB.S9S_MB_2U(SCH_1):PAGE497_I57@PURE_QUANTA.Q_CAP(CHIPS)':
 C_PATH='@s9s_mb_2u_lib.s9s_mb_2u(sch_1):page497_i57@pure_quanta.q_cap(chips)';

PART_NAME
 C1057 'Q_CAP_0402-0.1UF,25V,10%,X7R,CA':;

SECTION_NUMBER 1
 '@S9S_MB_2U_LIB.S9S_MB_2U(SCH_1):PAGE497_I58@PURE_QUANTA.Q_CAP(CHIPS)':
 C_PATH='@s9s_mb_2u_lib.s9s_mb_2u(sch_1):page497_i58@pure_quanta.q_cap(chips)';

PART_NAME
 C1056 'Q_CAP_0402-0.1UF,25V,10%,X7R,CA':;

SECTION_NUMBER 1
 '@S9S_MB_2U_LIB.S9S_MB_2U(SCH_1):PAGE497_I59@PURE_QUANTA.Q_CAP(CHIPS)':
 C_PATH='@s9s_mb_2u_lib.s9s_mb_2u(sch_1):page497_i59@pure_quanta.q_cap(chips)';

PART_NAME
 C1055 'Q_CAP_C0805-22UF,16V,20%,X6S,CA':;

SECTION_NUMBER 1
 '@S9S_MB_2U_LIB.S9S_MB_2U(SCH_1):PAGE497_I60@PURE_QUANTA.Q_CAP(CHIPS)':
 C_PATH='@s9s_mb_2u_lib.s9s_mb_2u(sch_1):page497_i60@pure_quanta.q_cap(chips)';

PART_NAME
 C1054 'Q_CAP_C0805-22UF,16V,20%,X6S,CA':;

SECTION_NUMBER 1
 '@S9S_MB_2U_LIB.S9S_MB_2U(SCH_1):PAGE497_I30@PURE_QUANTA.Q_CAP(CHIPS)':
 C_PATH='@s9s_mb_2u_lib.s9s_mb_2u(sch_1):page497_i30@pure_quanta.q_cap(chips)';

PART_NAME
 R1859 'Q_RES_0402LF-33.2,1%,1/16W,CHIA':;

SECTION_NUMBER 1
 '@S9S_MB_2U_LIB.S9S_MB_2U(SCH_1):PAGE496_I145@PURE_QUANTA.Q_RES(CHIPS)':
 C_PATH='@s9s_mb_2u_lib.s9s_mb_2u(sch_1):page496_i145@pure_quanta.q_res(chips)';

PART_NAME
 R1858 'Q_RES_0402LF-33.2,1%,1/16W,CHIA':;

SECTION_NUMBER 1
 '@S9S_MB_2U_LIB.S9S_MB_2U(SCH_1):PAGE496_I146@PURE_QUANTA.Q_RES(CHIPS)':
 C_PATH='@s9s_mb_2u_lib.s9s_mb_2u(sch_1):page496_i146@pure_quanta.q_res(chips)';

PART_NAME
 R1614 'Q_RES_0402LF-100,1%,1/16W,CHIPA':;

SECTION_NUMBER 1
 '@S9S_MB_2U_LIB.S9S_MB_2U(SCH_1):PAGE496_I98@PURE_QUANTA.Q_RES(CHIPS)':
 C_PATH='@s9s_mb_2u_lib.s9s_mb_2u(sch_1):page496_i98@pure_quanta.q_res(chips)';

PART_NAME
 R1613 'Q_RES_0402LF-4.7K,5%,1/16W,CHIA':;

SECTION_NUMBER 1
 '@S9S_MB_2U_LIB.S9S_MB_2U(SCH_1):PAGE496_I97@PURE_QUANTA.Q_RES(CHIPS)':
 C_PATH='@s9s_mb_2u_lib.s9s_mb_2u(sch_1):page496_i97@pure_quanta.q_res(chips)';

PART_NAME
 R1609 'Q_RES_0402LF-10K,1%,1/16W,CHIPA':;

SECTION_NUMBER 1
 '@S9S_MB_2U_LIB.S9S_MB_2U(SCH_1):PAGE496_I88@PURE_QUANTA.Q_RES(CHIPS)':
 C_PATH='@s9s_mb_2u_lib.s9s_mb_2u(sch_1):page496_i88@pure_quanta.q_res(chips)';

PART_NAME
 R1585 'Q_RES_0402LF-0,5%,1/16W,CHIP,CA':;

SECTION_NUMBER 1
 '@S9S_MB_2U_LIB.S9S_MB_2U(SCH_1):PAGE496_I112@PURE_QUANTA.Q_RES(CHIPS)':
 C_PATH='@s9s_mb_2u_lib.s9s_mb_2u(sch_1):page496_i112@pure_quanta.q_res(chips)';

PART_NAME
 R1584 'Q_RES_0402LF-10K,5%,1/16W,EMPTA':;

SECTION_NUMBER 1
 '@S9S_MB_2U_LIB.S9S_MB_2U(SCH_1):PAGE496_I114@PURE_QUANTA.Q_RES(CHIPS)':
 C_PATH='@s9s_mb_2u_lib.s9s_mb_2u(sch_1):page496_i114@pure_quanta.q_res(chips)';

PART_NAME
 R396 'Q_RES_0402LF-10K,1%,1/16W,CHIPA':;

SECTION_NUMBER 1
 '@S9S_MB_2U_LIB.S9S_MB_2U(SCH_1):PAGE496_I78@PURE_QUANTA.Q_RES(CHIPS)':
 C_PATH='@s9s_mb_2u_lib.s9s_mb_2u(sch_1):page496_i78@pure_quanta.q_res(chips)';

PART_NAME
 R395 'Q_RES_0402LF-10K,1%,1/16W,CHIPA':;

SECTION_NUMBER 1
 '@S9S_MB_2U_LIB.S9S_MB_2U(SCH_1):PAGE496_I77@PURE_QUANTA.Q_RES(CHIPS)':
 C_PATH='@s9s_mb_2u_lib.s9s_mb_2u(sch_1):page496_i77@pure_quanta.q_res(chips)';

PART_NAME
 R394 'Q_RES_0402LF-4.7K,5%,1/16W,CHIA':;

SECTION_NUMBER 1
 '@S9S_MB_2U_LIB.S9S_MB_2U(SCH_1):PAGE496_I71@PURE_QUANTA.Q_RES(CHIPS)':
 C_PATH='@s9s_mb_2u_lib.s9s_mb_2u(sch_1):page496_i71@pure_quanta.q_res(chips)';

PART_NAME
 J33 'SCONN84_123318136-SCONN84_1-23A':;

SECTION_NUMBER 1
 '@S9S_MB_2U_LIB.S9S_MB_2U(SCH_1):PAGE496_I53@PURE_QUANTA.SCONN84_123318136(CHIPS)':
 C_PATH='@s9s_mb_2u_lib.s9s_mb_2u(sch_1):page496_i53@pure_quanta.sconn84_123318136~
(chips)';

PART_NAME
 C1215 'Q_CAP_0402-0.1UF,25V,10%,X7R,CA':;

SECTION_NUMBER 1
 '@S9S_MB_2U_LIB.S9S_MB_2U(SCH_1):PAGE496_I92@PURE_QUANTA.Q_CAP(CHIPS)':
 C_PATH='@s9s_mb_2u_lib.s9s_mb_2u(sch_1):page496_i92@pure_quanta.q_cap(chips)';

PART_NAME
 C1208 'Q_CAP_0402-0.1UF,25V,10%,X7R,CA':;

SECTION_NUMBER 1
 '@S9S_MB_2U_LIB.S9S_MB_2U(SCH_1):PAGE496_I94@PURE_QUANTA.Q_CAP(CHIPS)':
 C_PATH='@s9s_mb_2u_lib.s9s_mb_2u(sch_1):page496_i94@pure_quanta.q_cap(chips)';

PART_NAME
 C1053 'Q_CAP_C0805-22UF,16V,20%,X6S,CA':;

SECTION_NUMBER 1
 '@S9S_MB_2U_LIB.S9S_MB_2U(SCH_1):PAGE496_I29@PURE_QUANTA.Q_CAP(CHIPS)':
 C_PATH='@s9s_mb_2u_lib.s9s_mb_2u(sch_1):page496_i29@pure_quanta.q_cap(chips)';

PART_NAME
 C1052 'Q_CAP_0402-0.1UF,25V,10%,X7R,CA':;

SECTION_NUMBER 1
 '@S9S_MB_2U_LIB.S9S_MB_2U(SCH_1):PAGE496_I31@PURE_QUANTA.Q_CAP(CHIPS)':
 C_PATH='@s9s_mb_2u_lib.s9s_mb_2u(sch_1):page496_i31@pure_quanta.q_cap(chips)';

PART_NAME
 C1051 'Q_CAP_0402-0.1UF,25V,10%,X7R,CA':;

SECTION_NUMBER 1
 '@S9S_MB_2U_LIB.S9S_MB_2U(SCH_1):PAGE496_I33@PURE_QUANTA.Q_CAP(CHIPS)':
 C_PATH='@s9s_mb_2u_lib.s9s_mb_2u(sch_1):page496_i33@pure_quanta.q_cap(chips)';

PART_NAME
 C1050 'Q_CAP_0402-0.1UF,25V,10%,X7R,CA':;

SECTION_NUMBER 1
 '@S9S_MB_2U_LIB.S9S_MB_2U(SCH_1):PAGE496_I34@PURE_QUANTA.Q_CAP(CHIPS)':
 C_PATH='@s9s_mb_2u_lib.s9s_mb_2u(sch_1):page496_i34@pure_quanta.q_cap(chips)';

PART_NAME
 C1049 'Q_CAP_0402-0.1UF,25V,10%,X7R,CA':;

SECTION_NUMBER 1
 '@S9S_MB_2U_LIB.S9S_MB_2U(SCH_1):PAGE496_I35@PURE_QUANTA.Q_CAP(CHIPS)':
 C_PATH='@s9s_mb_2u_lib.s9s_mb_2u(sch_1):page496_i35@pure_quanta.q_cap(chips)';

PART_NAME
 C1048 'Q_CAP_0402-0.1UF,25V,10%,X7R,CA':;

SECTION_NUMBER 1
 '@S9S_MB_2U_LIB.S9S_MB_2U(SCH_1):PAGE496_I36@PURE_QUANTA.Q_CAP(CHIPS)':
 C_PATH='@s9s_mb_2u_lib.s9s_mb_2u(sch_1):page496_i36@pure_quanta.q_cap(chips)';

PART_NAME
 C1047 'Q_CAP_C0805-22UF,16V,20%,X6S,CA':;

SECTION_NUMBER 1
 '@S9S_MB_2U_LIB.S9S_MB_2U(SCH_1):PAGE496_I37@PURE_QUANTA.Q_CAP(CHIPS)':
 C_PATH='@s9s_mb_2u_lib.s9s_mb_2u(sch_1):page496_i37@pure_quanta.q_cap(chips)';

PART_NAME
 C1046 'Q_CAP_C0805-22UF,16V,20%,X6S,CA':;

SECTION_NUMBER 1
 '@S9S_MB_2U_LIB.S9S_MB_2U(SCH_1):PAGE496_I40@PURE_QUANTA.Q_CAP(CHIPS)':
 C_PATH='@s9s_mb_2u_lib.s9s_mb_2u(sch_1):page496_i40@pure_quanta.q_cap(chips)';

PART_NAME
 U99 'RT9818C44GV-RT9818C-44GV,SMLF,A':;

SECTION_NUMBER 1
 '@S9S_MB_2U_LIB.S9S_MB_2U(SCH_1):PAGE576_I70@PURE_QUANTA.RT9818C44GV(CHIPS)':
 C_PATH='@s9s_mb_2u_lib.s9s_mb_2u(sch_1):page576_i70@pure_quanta.rt9818c44gv(chips~
)';

PART_NAME
 U79 'SLG55221120010VTR-SLG55221-120A':;

SECTION_NUMBER 1
 '@S9S_MB_2U_LIB.S9S_MB_2U(SCH_1):PAGE576_I62@PURE_QUANTA.SLG55221120010VTR(CHIPS)':
 C_PATH='@s9s_mb_2u_lib.s9s_mb_2u(sch_1):page576_i62@pure_quanta.slg55221120010vtr~
(chips)';

PART_NAME
 R1706 'Q_RES_0402LF-4.7K,5%,1/16W,EMPA':;

SECTION_NUMBER 1
 '@S9S_MB_2U_LIB.S9S_MB_2U(SCH_1):PAGE576_I68@PURE_QUANTA.Q_RES(CHIPS)':
 C_PATH='@s9s_mb_2u_lib.s9s_mb_2u(sch_1):page576_i68@pure_quanta.q_res(chips)';

PART_NAME
 R1698 'Q_RES_0402LF-20K,5%,1/16W,CHIPA':;

SECTION_NUMBER 1
 '@S9S_MB_2U_LIB.S9S_MB_2U(SCH_1):PAGE576_I89@PURE_QUANTA.Q_RES(CHIPS)':
 C_PATH='@s9s_mb_2u_lib.s9s_mb_2u(sch_1):page576_i89@pure_quanta.q_res(chips)';

PART_NAME
 R1682 'Q_RES_0402LF-10K,5%,1/16W,CHIPA':
;

SECTION_NUMBER 1
 '@S9S_MB_2U_LIB.S9S_MB_2U(SCH_1):PAGE576_I88@PURE_QUANTA.Q_RES(CHIPS)':
 C_PATH='@s9s_mb_2u_lib.s9s_mb_2u(sch_1):page576_i88@pure_quanta.q_res(chips)';

PART_NAME
 R1655 'Q_RES_0402LF-10K,5%,1/16W,CHIPA':;

SECTION_NUMBER 1
 '@S9S_MB_2U_LIB.S9S_MB_2U(SCH_1):PAGE576_I71@PURE_QUANTA.Q_RES(CHIPS)':
 C_PATH='@s9s_mb_2u_lib.s9s_mb_2u(sch_1):page576_i71@pure_quanta.q_res(chips)';

PART_NAME
 R1654 'Q_RES_0402LF-1K,5%,1/16W,CHIP,A':
;

SECTION_NUMBER 1
 '@S9S_MB_2U_LIB.S9S_MB_2U(SCH_1):PAGE576_I77@PURE_QUANTA.Q_RES(CHIPS)':
 C_PATH='@s9s_mb_2u_lib.s9s_mb_2u(sch_1):page576_i77@pure_quanta.q_res(chips)';

PART_NAME
 R1643 'Q_RES_0402LF-100K,5%,1/16W,CHIA':
;

SECTION_NUMBER 1
 '@S9S_MB_2U_LIB.S9S_MB_2U(SCH_1):PAGE576_I86@PURE_QUANTA.Q_RES(CHIPS)':
 C_PATH='@s9s_mb_2u_lib.s9s_mb_2u(sch_1):page576_i86@pure_quanta.q_res(chips)';

PART_NAME
 R1642 'Q_RES_0402LF-10K,5%,1/16W,CHIPA':
;

SECTION_NUMBER 1
 '@S9S_MB_2U_LIB.S9S_MB_2U(SCH_1):PAGE576_I87@PURE_QUANTA.Q_RES(CHIPS)':
 C_PATH='@s9s_mb_2u_lib.s9s_mb_2u(sch_1):page576_i87@pure_quanta.q_res(chips)';

PART_NAME
 R1641 'Q_RES_0402LF-100,1%,1/16W,CHIPA':;

SECTION_NUMBER 1
 '@S9S_MB_2U_LIB.S9S_MB_2U(SCH_1):PAGE576_I74@PURE_QUANTA.Q_RES(CHIPS)':
 C_PATH='@s9s_mb_2u_lib.s9s_mb_2u(sch_1):page576_i74@pure_quanta.q_res(chips)';

PART_NAME
 R1640 'Q_RES_0402LF-0,5%,1/16W,EMPTY,A':;

SECTION_NUMBER 1
 '@S9S_MB_2U_LIB.S9S_MB_2U(SCH_1):PAGE576_I84@PURE_QUANTA.Q_RES(CHIPS)':
 C_PATH='@s9s_mb_2u_lib.s9s_mb_2u(sch_1):page576_i84@pure_quanta.q_res(chips)';

PART_NAME
 R1607 'Q_RES_0402LF-0,5%,1/16W,CHIP,CA':;

SECTION_NUMBER 1
 '@S9S_MB_2U_LIB.S9S_MB_2U(SCH_1):PAGE576_I85@PURE_QUANTA.Q_RES(CHIPS)':
 C_PATH='@s9s_mb_2u_lib.s9s_mb_2u(sch_1):page576_i85@pure_quanta.q_res(chips)';

PART_NAME
 Q37 'MOSFET_NCH_DUAL-2N7002KDW,SMLFA':;

SECTION_NUMBER 1
 '@S9S_MB_2U_LIB.S9S_MB_2U(SCH_1):PAGE576_I75@PURE_QUANTA.MOSFET_NCH_DUAL(CHIPS)':
 C_PATH='@s9s_mb_2u_lib.s9s_mb_2u(sch_1):page576_i75@pure_quanta.mosfet_nch_dual(c~
hips)';

SECTION_NUMBER 2
 '@S9S_MB_2U_LIB.S9S_MB_2U(SCH_1):PAGE576_I76@PURE_QUANTA.MOSFET_NCH_DUAL(CHIPS)':
 C_PATH='@s9s_mb_2u_lib.s9s_mb_2u(sch_1):page576_i76@pure_quanta.mosfet_nch_dual(c~
hips)';

PART_NAME
 PQ2 'MOSFET_NCH_1D3S-PSMNR58-30YLH,A':;

SECTION_NUMBER 1
 '@S9S_MB_2U_LIB.S9S_MB_2U(SCH_1):PAGE576_I90@PURE_QUANTA.MOSFET_NCH_1D3S(CHIPS)':
 C_PATH='@s9s_mb_2u_lib.s9s_mb_2u(sch_1):page576_i90@pure_quanta.mosfet_nch_1d3s(c~
hips)';

PART_NAME
 PQ1 'MOSFET_NCH_1D3S-PSMNR58-30YLH,A':;

SECTION_NUMBER 1
 '@S9S_MB_2U_LIB.S9S_MB_2U(SCH_1):PAGE576_I91@PURE_QUANTA.MOSFET_NCH_1D3S(CHIPS)':
 C_PATH='@s9s_mb_2u_lib.s9s_mb_2u(sch_1):page576_i91@pure_quanta.mosfet_nch_1d3s(c~
hips)';

PART_NAME
 D7 'BAT547F-BAT547F,SMLF,IC,BC0BATA':;

SECTION_NUMBER 1
 '@S9S_MB_2U_LIB.S9S_MB_2U(SCH_1):PAGE576_I69@PURE_QUANTA.BAT547F(CHIPS)':
 C_PATH='@s9s_mb_2u_lib.s9s_mb_2u(sch_1):page576_i69@pure_quanta.bat547f(chips)';

PART_NAME
 C1340 'Q_CAP_C0805-10UF,16V,10%,X6S,CA':;

SECTION_NUMBER 1
 '@S9S_MB_2U_LIB.S9S_MB_2U(SCH_1):PAGE576_I67@PURE_QUANTA.Q_CAP(CHIPS)':
 C_PATH='@s9s_mb_2u_lib.s9s_mb_2u(sch_1):page576_i67@pure_quanta.q_cap(chips)';

PART_NAME
 C1339 'Q_CAP_C0402-100NF,50V,10%,X7R,A':;

SECTION_NUMBER 1
 '@S9S_MB_2U_LIB.S9S_MB_2U(SCH_1):PAGE576_I66@PURE_QUANTA.Q_CAP(CHIPS)':
 C_PATH='@s9s_mb_2u_lib.s9s_mb_2u(sch_1):page576_i66@pure_quanta.q_cap(chips)';

PART_NAME
 C1338 'Q_CAP_C0805-10UF,16V,10%,EMPTYA':;

SECTION_NUMBER 1
 '@S9S_MB_2U_LIB.S9S_MB_2U(SCH_1):PAGE576_I65@PURE_QUANTA.Q_CAP(CHIPS)':
 C_PATH='@s9s_mb_2u_lib.s9s_mb_2u(sch_1):page576_i65@pure_quanta.q_cap(chips)';

PART_NAME
 C1333 'Q_CAP_C0805-10UF,16V,10%,X6S,CA':;

SECTION_NUMBER 1
 '@S9S_MB_2U_LIB.S9S_MB_2U(SCH_1):PAGE576_I64@PURE_QUANTA.Q_CAP(CHIPS)':
 C_PATH='@s9s_mb_2u_lib.s9s_mb_2u(sch_1):page576_i64@pure_quanta.q_cap(chips)';

PART_NAME
 C1332 'Q_CAP_C0402-100NF,50V,10%,X7R,A':;

SECTION_NUMBER 1
 '@S9S_MB_2U_LIB.S9S_MB_2U(SCH_1):PAGE576_I63@PURE_QUANTA.Q_CAP(CHIPS)':
 C_PATH='@s9s_mb_2u_lib.s9s_mb_2u(sch_1):page576_i63@pure_quanta.q_cap(chips)';

PART_NAME
 C1331 'Q_CAP_C0805-10UF,16V,10%,X6S,CA':
;

SECTION_NUMBER 1
 '@S9S_MB_2U_LIB.S9S_MB_2U(SCH_1):PAGE576_I83@PURE_QUANTA.Q_CAP(CHIPS)':
 C_PATH='@s9s_mb_2u_lib.s9s_mb_2u(sch_1):page576_i83@pure_quanta.q_cap(chips)';

PART_NAME
 C1326 'Q_CAP_C0402-100NF,50V,10%,X7R,A':
;

SECTION_NUMBER 1
 '@S9S_MB_2U_LIB.S9S_MB_2U(SCH_1):PAGE576_I73@PURE_QUANTA.Q_CAP(CHIPS)':
 C_PATH='@s9s_mb_2u_lib.s9s_mb_2u(sch_1):page576_i73@pure_quanta.q_cap(chips)';

PART_NAME
 C1227 'Q_CAP_C0402-100NF,50V,10%,X7R,A':
;

SECTION_NUMBER 1
 '@S9S_MB_2U_LIB.S9S_MB_2U(SCH_1):PAGE576_I82@PURE_QUANTA.Q_CAP(CHIPS)':
 C_PATH='@s9s_mb_2u_lib.s9s_mb_2u(sch_1):page576_i82@pure_quanta.q_cap(chips)';

PART_NAME
 C1226 'Q_CAP_0402-0.22UF,16V,10%,X7R,A':;

SECTION_NUMBER 1
 '@S9S_MB_2U_LIB.S9S_MB_2U(SCH_1):PAGE576_I78@PURE_QUANTA.Q_CAP(CHIPS)':
 C_PATH='@s9s_mb_2u_lib.s9s_mb_2u(sch_1):page576_i78@pure_quanta.q_cap(chips)';

PART_NAME
 C1172 'Q_CAP_C0402-100NF,50V,10%,X7R,A':;

SECTION_NUMBER 1
 '@S9S_MB_2U_LIB.S9S_MB_2U(SCH_1):PAGE576_I72@PURE_QUANTA.Q_CAP(CHIPS)':
 C_PATH='@s9s_mb_2u_lib.s9s_mb_2u(sch_1):page576_i72@pure_quanta.q_cap(chips)';

PART_NAME
 C1171 'Q_CAP_C0805-10UF,16V,10%,EMPTYA':
;

SECTION_NUMBER 1
 '@S9S_MB_2U_LIB.S9S_MB_2U(SCH_1):PAGE576_I81@PURE_QUANTA.Q_CAP(CHIPS)':
 C_PATH='@s9s_mb_2u_lib.s9s_mb_2u(sch_1):page576_i81@pure_quanta.q_cap(chips)';

PART_NAME
 C1170 'Q_CAP_C0805-10UF,16V,10%,X6S,CA':
;

SECTION_NUMBER 1
 '@S9S_MB_2U_LIB.S9S_MB_2U(SCH_1):PAGE576_I80@PURE_QUANTA.Q_CAP(CHIPS)':
 C_PATH='@s9s_mb_2u_lib.s9s_mb_2u(sch_1):page576_i80@pure_quanta.q_cap(chips)';

PART_NAME
 C1042 'Q_CAP_C0402-100NF,50V,10%,X7R,A':
;

SECTION_NUMBER 1
 '@S9S_MB_2U_LIB.S9S_MB_2U(SCH_1):PAGE576_I79@PURE_QUANTA.Q_CAP(CHIPS)':
 C_PATH='@s9s_mb_2u_lib.s9s_mb_2u(sch_1):page576_i79@pure_quanta.q_cap(chips)';

PART_NAME
 C965 'Q_CAP_DIFFBUS_C0201-DIFF BUS_0A':;

SECTION_NUMBER 1
 '@S9S_MB_2U_LIB.S9S_MB_2U(SCH_1):PAGE461_I115@PURE_QUANTA.Q_CAP_DIFFBUS(CHIPS)':
 C_PATH='@s9s_mb_2u_lib.s9s_mb_2u(sch_1):page461_i115@pure_quanta.q_cap_diffbus(ch~
ips)';

PART_NAME
 C964 'Q_CAP_DIFFBUS_C0201-DIFF BUS_0A':;

SECTION_NUMBER 1
 '@S9S_MB_2U_LIB.S9S_MB_2U(SCH_1):PAGE461_I117@PURE_QUANTA.Q_CAP_DIFFBUS(CHIPS)':
 C_PATH='@s9s_mb_2u_lib.s9s_mb_2u(sch_1):page461_i117@pure_quanta.q_cap_diffbus(ch~
ips)';

PART_NAME
 C963 'Q_CAP_DIFFBUS_C0201-DIFF BUS_0A':;

SECTION_NUMBER 1
 '@S9S_MB_2U_LIB.S9S_MB_2U(SCH_1):PAGE461_I116@PURE_QUANTA.Q_CAP_DIFFBUS(CHIPS)':
 C_PATH='@s9s_mb_2u_lib.s9s_mb_2u(sch_1):page461_i116@pure_quanta.q_cap_diffbus(ch~
ips)';

PART_NAME
 C962 'Q_CAP_DIFFBUS_C0201-DIFF BUS_0A':;

SECTION_NUMBER 1
 '@S9S_MB_2U_LIB.S9S_MB_2U(SCH_1):PAGE461_I118@PURE_QUANTA.Q_CAP_DIFFBUS(CHIPS)':
 C_PATH='@s9s_mb_2u_lib.s9s_mb_2u(sch_1):page461_i118@pure_quanta.q_cap_diffbus(ch~
ips)';

PART_NAME
 C961 'Q_CAP_DIFFBUS_C0201-DIFF BUS_0A':;

SECTION_NUMBER 1
 '@S9S_MB_2U_LIB.S9S_MB_2U(SCH_1):PAGE461_I120@PURE_QUANTA.Q_CAP_DIFFBUS(CHIPS)':
 C_PATH='@s9s_mb_2u_lib.s9s_mb_2u(sch_1):page461_i120@pure_quanta.q_cap_diffbus(ch~
ips)';

PART_NAME
 C960 'Q_CAP_DIFFBUS_C0201-DIFF BUS_0A':;

SECTION_NUMBER 1
 '@S9S_MB_2U_LIB.S9S_MB_2U(SCH_1):PAGE461_I119@PURE_QUANTA.Q_CAP_DIFFBUS(CHIPS)':
 C_PATH='@s9s_mb_2u_lib.s9s_mb_2u(sch_1):page461_i119@pure_quanta.q_cap_diffbus(ch~
ips)';

PART_NAME
 C959 'Q_CAP_DIFFBUS_C0201-DIFF BUS_0A':;

SECTION_NUMBER 1
 '@S9S_MB_2U_LIB.S9S_MB_2U(SCH_1):PAGE461_I121@PURE_QUANTA.Q_CAP_DIFFBUS(CHIPS)':
 C_PATH='@s9s_mb_2u_lib.s9s_mb_2u(sch_1):page461_i121@pure_quanta.q_cap_diffbus(ch~
ips)';

PART_NAME
 C958 'Q_CAP_DIFFBUS_C0201-DIFF BUS_0A':;

SECTION_NUMBER 1
 '@S9S_MB_2U_LIB.S9S_MB_2U(SCH_1):PAGE461_I122@PURE_QUANTA.Q_CAP_DIFFBUS(CHIPS)':
 C_PATH='@s9s_mb_2u_lib.s9s_mb_2u(sch_1):page461_i122@pure_quanta.q_cap_diffbus(ch~
ips)';

PART_NAME
 C957 'Q_CAP_DIFFBUS_C0201-DIFF BUS_0A':;

SECTION_NUMBER 1
 '@S9S_MB_2U_LIB.S9S_MB_2U(SCH_1):PAGE461_I123@PURE_QUANTA.Q_CAP_DIFFBUS(CHIPS)':
 C_PATH='@s9s_mb_2u_lib.s9s_mb_2u(sch_1):page461_i123@pure_quanta.q_cap_diffbus(ch~
ips)';

PART_NAME
 C956 'Q_CAP_DIFFBUS_C0201-DIFF BUS_0A':;

SECTION_NUMBER 1
 '@S9S_MB_2U_LIB.S9S_MB_2U(SCH_1):PAGE461_I124@PURE_QUANTA.Q_CAP_DIFFBUS(CHIPS)':
 C_PATH='@s9s_mb_2u_lib.s9s_mb_2u(sch_1):page461_i124@pure_quanta.q_cap_diffbus(ch~
ips)';

PART_NAME
 C955 'Q_CAP_DIFFBUS_C0201-DIFF BUS_0A':;

SECTION_NUMBER 1
 '@S9S_MB_2U_LIB.S9S_MB_2U(SCH_1):PAGE461_I125@PURE_QUANTA.Q_CAP_DIFFBUS(CHIPS)':
 C_PATH='@s9s_mb_2u_lib.s9s_mb_2u(sch_1):page461_i125@pure_quanta.q_cap_diffbus(ch~
ips)';

PART_NAME
 C954 'Q_CAP_DIFFBUS_C0201-DIFF BUS_0A':;

SECTION_NUMBER 1
 '@S9S_MB_2U_LIB.S9S_MB_2U(SCH_1):PAGE461_I162@PURE_QUANTA.Q_CAP_DIFFBUS(CHIPS)':
 C_PATH='@s9s_mb_2u_lib.s9s_mb_2u(sch_1):page461_i162@pure_quanta.q_cap_diffbus(ch~
ips)';

PART_NAME
 C953 'Q_CAP_DIFFBUS_C0201-DIFF BUS_0A':;

SECTION_NUMBER 1
 '@S9S_MB_2U_LIB.S9S_MB_2U(SCH_1):PAGE461_I163@PURE_QUANTA.Q_CAP_DIFFBUS(CHIPS)':
 C_PATH='@s9s_mb_2u_lib.s9s_mb_2u(sch_1):page461_i163@pure_quanta.q_cap_diffbus(ch~
ips)';

PART_NAME
 C952 'Q_CAP_DIFFBUS_C0201-DIFF BUS_0A':;

SECTION_NUMBER 1
 '@S9S_MB_2U_LIB.S9S_MB_2U(SCH_1):PAGE461_I164@PURE_QUANTA.Q_CAP_DIFFBUS(CHIPS)':
 C_PATH='@s9s_mb_2u_lib.s9s_mb_2u(sch_1):page461_i164@pure_quanta.q_cap_diffbus(ch~
ips)';

PART_NAME
 C951 'Q_CAP_DIFFBUS_C0201-DIFF BUS_0A':;

SECTION_NUMBER 1
 '@S9S_MB_2U_LIB.S9S_MB_2U(SCH_1):PAGE461_I166@PURE_QUANTA.Q_CAP_DIFFBUS(CHIPS)':
 C_PATH='@s9s_mb_2u_lib.s9s_mb_2u(sch_1):page461_i166@pure_quanta.q_cap_diffbus(ch~
ips)';

PART_NAME
 C950 'Q_CAP_DIFFBUS_C0201-DIFF BUS_0A':;

SECTION_NUMBER 1
 '@S9S_MB_2U_LIB.S9S_MB_2U(SCH_1):PAGE461_I165@PURE_QUANTA.Q_CAP_DIFFBUS(CHIPS)':
 C_PATH='@s9s_mb_2u_lib.s9s_mb_2u(sch_1):page461_i165@pure_quanta.q_cap_diffbus(ch~
ips)';

PART_NAME
 C949 'Q_CAP_DIFFBUS_C0201-DIFF BUS_0A':;

SECTION_NUMBER 1
 '@S9S_MB_2U_LIB.S9S_MB_2U(SCH_1):PAGE461_I167@PURE_QUANTA.Q_CAP_DIFFBUS(CHIPS)':
 C_PATH='@s9s_mb_2u_lib.s9s_mb_2u(sch_1):page461_i167@pure_quanta.q_cap_diffbus(ch~
ips)';

PART_NAME
 C948 'Q_CAP_DIFFBUS_C0201-DIFF BUS_0A':;

SECTION_NUMBER 1
 '@S9S_MB_2U_LIB.S9S_MB_2U(SCH_1):PAGE461_I168@PURE_QUANTA.Q_CAP_DIFFBUS(CHIPS)':
 C_PATH='@s9s_mb_2u_lib.s9s_mb_2u(sch_1):page461_i168@pure_quanta.q_cap_diffbus(ch~
ips)';

PART_NAME
 C947 'Q_CAP_DIFFBUS_C0201-DIFF BUS_0A':;

SECTION_NUMBER 1
 '@S9S_MB_2U_LIB.S9S_MB_2U(SCH_1):PAGE461_I176@PURE_QUANTA.Q_CAP_DIFFBUS(CHIPS)':
 C_PATH='@s9s_mb_2u_lib.s9s_mb_2u(sch_1):page461_i176@pure_quanta.q_cap_diffbus(ch~
ips)';

PART_NAME
 C946 'Q_CAP_DIFFBUS_C0201-DIFF BUS_0A':;

SECTION_NUMBER 1
 '@S9S_MB_2U_LIB.S9S_MB_2U(SCH_1):PAGE461_I177@PURE_QUANTA.Q_CAP_DIFFBUS(CHIPS)':
 C_PATH='@s9s_mb_2u_lib.s9s_mb_2u(sch_1):page461_i177@pure_quanta.q_cap_diffbus(ch~
ips)';

PART_NAME
 C945 'Q_CAP_DIFFBUS_C0201-DIFF BUS_0A':;

SECTION_NUMBER 1
 '@S9S_MB_2U_LIB.S9S_MB_2U(SCH_1):PAGE461_I178@PURE_QUANTA.Q_CAP_DIFFBUS(CHIPS)':
 C_PATH='@s9s_mb_2u_lib.s9s_mb_2u(sch_1):page461_i178@pure_quanta.q_cap_diffbus(ch~
ips)';

PART_NAME
 C944 'Q_CAP_DIFFBUS_C0201-DIFF BUS_0A':;

SECTION_NUMBER 1
 '@S9S_MB_2U_LIB.S9S_MB_2U(SCH_1):PAGE461_I179@PURE_QUANTA.Q_CAP_DIFFBUS(CHIPS)':
 C_PATH='@s9s_mb_2u_lib.s9s_mb_2u(sch_1):page461_i179@pure_quanta.q_cap_diffbus(ch~
ips)';

PART_NAME
 C943 'Q_CAP_DIFFBUS_C0201-DIFF BUS_0A':;

SECTION_NUMBER 1
 '@S9S_MB_2U_LIB.S9S_MB_2U(SCH_1):PAGE461_I182@PURE_QUANTA.Q_CAP_DIFFBUS(CHIPS)':
 C_PATH='@s9s_mb_2u_lib.s9s_mb_2u(sch_1):page461_i182@pure_quanta.q_cap_diffbus(ch~
ips)';

PART_NAME
 C942 'Q_CAP_DIFFBUS_C0201-DIFF BUS_0A':;

SECTION_NUMBER 1
 '@S9S_MB_2U_LIB.S9S_MB_2U(SCH_1):PAGE461_I181@PURE_QUANTA.Q_CAP_DIFFBUS(CHIPS)':
 C_PATH='@s9s_mb_2u_lib.s9s_mb_2u(sch_1):page461_i181@pure_quanta.q_cap_diffbus(ch~
ips)';

PART_NAME
 C941 'Q_CAP_DIFFBUS_C0201-DIFF BUS_0A':;

SECTION_NUMBER 1
 '@S9S_MB_2U_LIB.S9S_MB_2U(SCH_1):PAGE461_I180@PURE_QUANTA.Q_CAP_DIFFBUS(CHIPS)':
 C_PATH='@s9s_mb_2u_lib.s9s_mb_2u(sch_1):page461_i180@pure_quanta.q_cap_diffbus(ch~
ips)';

PART_NAME
 C940 'Q_CAP_DIFFBUS_C0201-DIFF BUS_0A':;

SECTION_NUMBER 1
 '@S9S_MB_2U_LIB.S9S_MB_2U(SCH_1):PAGE461_I185@PURE_QUANTA.Q_CAP_DIFFBUS(CHIPS)':
 C_PATH='@s9s_mb_2u_lib.s9s_mb_2u(sch_1):page461_i185@pure_quanta.q_cap_diffbus(ch~
ips)';

PART_NAME
 C939 'Q_CAP_DIFFBUS_C0201-DIFF BUS_0A':;

SECTION_NUMBER 1
 '@S9S_MB_2U_LIB.S9S_MB_2U(SCH_1):PAGE461_I184@PURE_QUANTA.Q_CAP_DIFFBUS(CHIPS)':
 C_PATH='@s9s_mb_2u_lib.s9s_mb_2u(sch_1):page461_i184@pure_quanta.q_cap_diffbus(ch~
ips)';

PART_NAME
 C938 'Q_CAP_DIFFBUS_C0201-DIFF BUS_0A':;

SECTION_NUMBER 1
 '@S9S_MB_2U_LIB.S9S_MB_2U(SCH_1):PAGE461_I183@PURE_QUANTA.Q_CAP_DIFFBUS(CHIPS)':
 C_PATH='@s9s_mb_2u_lib.s9s_mb_2u(sch_1):page461_i183@pure_quanta.q_cap_diffbus(ch~
ips)';

PART_NAME
 C937 'Q_CAP_DIFFBUS_C0201-DIFF BUS_0A':;

SECTION_NUMBER 1
 '@S9S_MB_2U_LIB.S9S_MB_2U(SCH_1):PAGE461_I199@PURE_QUANTA.Q_CAP_DIFFBUS(CHIPS)':
 C_PATH='@s9s_mb_2u_lib.s9s_mb_2u(sch_1):page461_i199@pure_quanta.q_cap_diffbus(ch~
ips)';

PART_NAME
 C936 'Q_CAP_DIFFBUS_C0201-DIFF BUS_0A':;

SECTION_NUMBER 1
 '@S9S_MB_2U_LIB.S9S_MB_2U(SCH_1):PAGE461_I200@PURE_QUANTA.Q_CAP_DIFFBUS(CHIPS)':
 C_PATH='@s9s_mb_2u_lib.s9s_mb_2u(sch_1):page461_i200@pure_quanta.q_cap_diffbus(ch~
ips)';

PART_NAME
 C935 'Q_CAP_DIFFBUS_C0201-DIFF BUS_0A':;

SECTION_NUMBER 1
 '@S9S_MB_2U_LIB.S9S_MB_2U(SCH_1):PAGE461_I202@PURE_QUANTA.Q_CAP_DIFFBUS(CHIPS)':
 C_PATH='@s9s_mb_2u_lib.s9s_mb_2u(sch_1):page461_i202@pure_quanta.q_cap_diffbus(ch~
ips)';

PART_NAME
 C934 'Q_CAP_DIFFBUS_C0201-DIFF BUS_0A':;

SECTION_NUMBER 1
 '@S9S_MB_2U_LIB.S9S_MB_2U(SCH_1):PAGE461_I201@PURE_QUANTA.Q_CAP_DIFFBUS(CHIPS)':
 C_PATH='@s9s_mb_2u_lib.s9s_mb_2u(sch_1):page461_i201@pure_quanta.q_cap_diffbus(ch~
ips)';

PART_NAME
 C933 'Q_CAP_DIFFBUS_C0201-DIFF BUS_0A':;

SECTION_NUMBER 1
 '@S9S_MB_2U_LIB.S9S_MB_2U(SCH_1):PAGE461_I15@PURE_QUANTA.Q_CAP_DIFFBUS(CHIPS)':
 C_PATH='@s9s_mb_2u_lib.s9s_mb_2u(sch_1):page461_i15@pure_quanta.q_cap_diffbus(chi~
ps)';

PART_NAME
 C932 'Q_CAP_DIFFBUS_C0201-DIFF BUS_0A':;

SECTION_NUMBER 1
 '@S9S_MB_2U_LIB.S9S_MB_2U(SCH_1):PAGE461_I16@PURE_QUANTA.Q_CAP_DIFFBUS(CHIPS)':
 C_PATH='@s9s_mb_2u_lib.s9s_mb_2u(sch_1):page461_i16@pure_quanta.q_cap_diffbus(chi~
ps)';

PART_NAME
 C931 'Q_CAP_DIFFBUS_C0201-DIFF BUS_0A':;

SECTION_NUMBER 1
 '@S9S_MB_2U_LIB.S9S_MB_2U(SCH_1):PAGE461_I17@PURE_QUANTA.Q_CAP_DIFFBUS(CHIPS)':
 C_PATH='@s9s_mb_2u_lib.s9s_mb_2u(sch_1):page461_i17@pure_quanta.q_cap_diffbus(chi~
ps)';

PART_NAME
 C930 'Q_CAP_DIFFBUS_C0201-DIFF BUS_0A':;

SECTION_NUMBER 1
 '@S9S_MB_2U_LIB.S9S_MB_2U(SCH_1):PAGE461_I18@PURE_QUANTA.Q_CAP_DIFFBUS(CHIPS)':
 C_PATH='@s9s_mb_2u_lib.s9s_mb_2u(sch_1):page461_i18@pure_quanta.q_cap_diffbus(chi~
ps)';

PART_NAME
 C929 'Q_CAP_DIFFBUS_C0201-DIFF BUS_0A':;

SECTION_NUMBER 1
 '@S9S_MB_2U_LIB.S9S_MB_2U(SCH_1):PAGE461_I19@PURE_QUANTA.Q_CAP_DIFFBUS(CHIPS)':
 C_PATH='@s9s_mb_2u_lib.s9s_mb_2u(sch_1):page461_i19@pure_quanta.q_cap_diffbus(chi~
ps)';

PART_NAME
 C928 'Q_CAP_DIFFBUS_C0201-DIFF BUS_0A':;

SECTION_NUMBER 1
 '@S9S_MB_2U_LIB.S9S_MB_2U(SCH_1):PAGE461_I20@PURE_QUANTA.Q_CAP_DIFFBUS(CHIPS)':
 C_PATH='@s9s_mb_2u_lib.s9s_mb_2u(sch_1):page461_i20@pure_quanta.q_cap_diffbus(chi~
ps)';

PART_NAME
 C927 'Q_CAP_DIFFBUS_C0201-DIFF BUS_0A':;

SECTION_NUMBER 1
 '@S9S_MB_2U_LIB.S9S_MB_2U(SCH_1):PAGE461_I21@PURE_QUANTA.Q_CAP_DIFFBUS(CHIPS)':
 C_PATH='@s9s_mb_2u_lib.s9s_mb_2u(sch_1):page461_i21@pure_quanta.q_cap_diffbus(chi~
ps)';

PART_NAME
 C926 'Q_CAP_DIFFBUS_C0201-DIFF BUS_0A':;

SECTION_NUMBER 1
 '@S9S_MB_2U_LIB.S9S_MB_2U(SCH_1):PAGE461_I22@PURE_QUANTA.Q_CAP_DIFFBUS(CHIPS)':
 C_PATH='@s9s_mb_2u_lib.s9s_mb_2u(sch_1):page461_i22@pure_quanta.q_cap_diffbus(chi~
ps)';

PART_NAME
 C925 'Q_CAP_DIFFBUS_C0201-DIFF BUS_0A':;

SECTION_NUMBER 1
 '@S9S_MB_2U_LIB.S9S_MB_2U(SCH_1):PAGE461_I23@PURE_QUANTA.Q_CAP_DIFFBUS(CHIPS)':
 C_PATH='@s9s_mb_2u_lib.s9s_mb_2u(sch_1):page461_i23@pure_quanta.q_cap_diffbus(chi~
ps)';

PART_NAME
 C924 'Q_CAP_DIFFBUS_C0201-DIFF BUS_0A':;

SECTION_NUMBER 1
 '@S9S_MB_2U_LIB.S9S_MB_2U(SCH_1):PAGE461_I24@PURE_QUANTA.Q_CAP_DIFFBUS(CHIPS)':
 C_PATH='@s9s_mb_2u_lib.s9s_mb_2u(sch_1):page461_i24@pure_quanta.q_cap_diffbus(chi~
ps)';

PART_NAME
 C923 'Q_CAP_DIFFBUS_C0201-DIFF BUS_0A':;

SECTION_NUMBER 1
 '@S9S_MB_2U_LIB.S9S_MB_2U(SCH_1):PAGE461_I25@PURE_QUANTA.Q_CAP_DIFFBUS(CHIPS)':
 C_PATH='@s9s_mb_2u_lib.s9s_mb_2u(sch_1):page461_i25@pure_quanta.q_cap_diffbus(chi~
ps)';

PART_NAME
 C922 'Q_CAP_DIFFBUS_C0201-DIFF BUS_0A':;

SECTION_NUMBER 1
 '@S9S_MB_2U_LIB.S9S_MB_2U(SCH_1):PAGE461_I53@PURE_QUANTA.Q_CAP_DIFFBUS(CHIPS)':
 C_PATH='@s9s_mb_2u_lib.s9s_mb_2u(sch_1):page461_i53@pure_quanta.q_cap_diffbus(chi~
ps)';

PART_NAME
 C921 'Q_CAP_DIFFBUS_C0201-DIFF BUS_0A':;

SECTION_NUMBER 1
 '@S9S_MB_2U_LIB.S9S_MB_2U(SCH_1):PAGE461_I55@PURE_QUANTA.Q_CAP_DIFFBUS(CHIPS)':
 C_PATH='@s9s_mb_2u_lib.s9s_mb_2u(sch_1):page461_i55@pure_quanta.q_cap_diffbus(chi~
ps)';

PART_NAME
 C920 'Q_CAP_DIFFBUS_C0201-DIFF BUS_0A':;

SECTION_NUMBER 1
 '@S9S_MB_2U_LIB.S9S_MB_2U(SCH_1):PAGE461_I54@PURE_QUANTA.Q_CAP_DIFFBUS(CHIPS)':
 C_PATH='@s9s_mb_2u_lib.s9s_mb_2u(sch_1):page461_i54@pure_quanta.q_cap_diffbus(chi~
ps)';

PART_NAME
 C919 'Q_CAP_DIFFBUS_C0201-DIFF BUS_0A':;

SECTION_NUMBER 1
 '@S9S_MB_2U_LIB.S9S_MB_2U(SCH_1):PAGE461_I56@PURE_QUANTA.Q_CAP_DIFFBUS(CHIPS)':
 C_PATH='@s9s_mb_2u_lib.s9s_mb_2u(sch_1):page461_i56@pure_quanta.q_cap_diffbus(chi~
ps)';

PART_NAME
 C918 'Q_CAP_DIFFBUS_C0201-DIFF BUS_0A':;

SECTION_NUMBER 1
 '@S9S_MB_2U_LIB.S9S_MB_2U(SCH_1):PAGE461_I57@PURE_QUANTA.Q_CAP_DIFFBUS(CHIPS)':
 C_PATH='@s9s_mb_2u_lib.s9s_mb_2u(sch_1):page461_i57@pure_quanta.q_cap_diffbus(chi~
ps)';

PART_NAME
 C917 'Q_CAP_DIFFBUS_C0201-DIFF BUS_0A':;

SECTION_NUMBER 1
 '@S9S_MB_2U_LIB.S9S_MB_2U(SCH_1):PAGE461_I58@PURE_QUANTA.Q_CAP_DIFFBUS(CHIPS)':
 C_PATH='@s9s_mb_2u_lib.s9s_mb_2u(sch_1):page461_i58@pure_quanta.q_cap_diffbus(chi~
ps)';

PART_NAME
 C916 'Q_CAP_DIFFBUS_C0201-DIFF BUS_0A':;

SECTION_NUMBER 1
 '@S9S_MB_2U_LIB.S9S_MB_2U(SCH_1):PAGE461_I59@PURE_QUANTA.Q_CAP_DIFFBUS(CHIPS)':
 C_PATH='@s9s_mb_2u_lib.s9s_mb_2u(sch_1):page461_i59@pure_quanta.q_cap_diffbus(chi~
ps)';

PART_NAME
 C915 'Q_CAP_DIFFBUS_C0201-DIFF BUS_0A':;

SECTION_NUMBER 1
 '@S9S_MB_2U_LIB.S9S_MB_2U(SCH_1):PAGE461_I61@PURE_QUANTA.Q_CAP_DIFFBUS(CHIPS)':
 C_PATH='@s9s_mb_2u_lib.s9s_mb_2u(sch_1):page461_i61@pure_quanta.q_cap_diffbus(chi~
ps)';

PART_NAME
 C914 'Q_CAP_DIFFBUS_C0201-DIFF BUS_0A':;

SECTION_NUMBER 1
 '@S9S_MB_2U_LIB.S9S_MB_2U(SCH_1):PAGE461_I62@PURE_QUANTA.Q_CAP_DIFFBUS(CHIPS)':
 C_PATH='@s9s_mb_2u_lib.s9s_mb_2u(sch_1):page461_i62@pure_quanta.q_cap_diffbus(chi~
ps)';

PART_NAME
 C913 'Q_CAP_DIFFBUS_C0201-DIFF BUS_0A':;

SECTION_NUMBER 1
 '@S9S_MB_2U_LIB.S9S_MB_2U(SCH_1):PAGE461_I63@PURE_QUANTA.Q_CAP_DIFFBUS(CHIPS)':
 C_PATH='@s9s_mb_2u_lib.s9s_mb_2u(sch_1):page461_i63@pure_quanta.q_cap_diffbus(chi~
ps)';

PART_NAME
 C912 'Q_CAP_DIFFBUS_C0201-DIFF BUS_0A':;

SECTION_NUMBER 1
 '@S9S_MB_2U_LIB.S9S_MB_2U(SCH_1):PAGE461_I64@PURE_QUANTA.Q_CAP_DIFFBUS(CHIPS)':
 C_PATH='@s9s_mb_2u_lib.s9s_mb_2u(sch_1):page461_i64@pure_quanta.q_cap_diffbus(chi~
ps)';

PART_NAME
 C911 'Q_CAP_DIFFBUS_C0201-DIFF BUS_0A':;

SECTION_NUMBER 1
 '@S9S_MB_2U_LIB.S9S_MB_2U(SCH_1):PAGE461_I65@PURE_QUANTA.Q_CAP_DIFFBUS(CHIPS)':
 C_PATH='@s9s_mb_2u_lib.s9s_mb_2u(sch_1):page461_i65@pure_quanta.q_cap_diffbus(chi~
ps)';

PART_NAME
 C910 'Q_CAP_DIFFBUS_C0201-DIFF BUS_0A':;

SECTION_NUMBER 1
 '@S9S_MB_2U_LIB.S9S_MB_2U(SCH_1):PAGE461_I66@PURE_QUANTA.Q_CAP_DIFFBUS(CHIPS)':
 C_PATH='@s9s_mb_2u_lib.s9s_mb_2u(sch_1):page461_i66@pure_quanta.q_cap_diffbus(chi~
ps)';

PART_NAME
 C909 'Q_CAP_DIFFBUS_C0201-DIFF BUS_0A':;

SECTION_NUMBER 1
 '@S9S_MB_2U_LIB.S9S_MB_2U(SCH_1):PAGE461_I67@PURE_QUANTA.Q_CAP_DIFFBUS(CHIPS)':
 C_PATH='@s9s_mb_2u_lib.s9s_mb_2u(sch_1):page461_i67@pure_quanta.q_cap_diffbus(chi~
ps)';

PART_NAME
 C908 'Q_CAP_DIFFBUS_C0201-DIFF BUS_0A':;

SECTION_NUMBER 1
 '@S9S_MB_2U_LIB.S9S_MB_2U(SCH_1):PAGE461_I68@PURE_QUANTA.Q_CAP_DIFFBUS(CHIPS)':
 C_PATH='@s9s_mb_2u_lib.s9s_mb_2u(sch_1):page461_i68@pure_quanta.q_cap_diffbus(chi~
ps)';

PART_NAME
 C907 'Q_CAP_DIFFBUS_C0201-DIFF BUS_0A':;

SECTION_NUMBER 1
 '@S9S_MB_2U_LIB.S9S_MB_2U(SCH_1):PAGE461_I70@PURE_QUANTA.Q_CAP_DIFFBUS(CHIPS)':
 C_PATH='@s9s_mb_2u_lib.s9s_mb_2u(sch_1):page461_i70@pure_quanta.q_cap_diffbus(chi~
ps)';

PART_NAME
 C906 'Q_CAP_DIFFBUS_C0201-DIFF BUS_0A':;

SECTION_NUMBER 1
 '@S9S_MB_2U_LIB.S9S_MB_2U(SCH_1):PAGE461_I69@PURE_QUANTA.Q_CAP_DIFFBUS(CHIPS)':
 C_PATH='@s9s_mb_2u_lib.s9s_mb_2u(sch_1):page461_i69@pure_quanta.q_cap_diffbus(chi~
ps)';

PART_NAME
 C905 'Q_CAP_DIFFBUS_C0201-DIFF BUS_0A':;

SECTION_NUMBER 1
 '@S9S_MB_2U_LIB.S9S_MB_2U(SCH_1):PAGE461_I75@PURE_QUANTA.Q_CAP_DIFFBUS(CHIPS)':
 C_PATH='@s9s_mb_2u_lib.s9s_mb_2u(sch_1):page461_i75@pure_quanta.q_cap_diffbus(chi~
ps)';

PART_NAME
 C904 'Q_CAP_DIFFBUS_C0201-DIFF BUS_0A':;

SECTION_NUMBER 1
 '@S9S_MB_2U_LIB.S9S_MB_2U(SCH_1):PAGE461_I76@PURE_QUANTA.Q_CAP_DIFFBUS(CHIPS)':
 C_PATH='@s9s_mb_2u_lib.s9s_mb_2u(sch_1):page461_i76@pure_quanta.q_cap_diffbus(chi~
ps)';

PART_NAME
 C903 'Q_CAP_DIFFBUS_C0201-DIFF BUS_0A':;

SECTION_NUMBER 1
 '@S9S_MB_2U_LIB.S9S_MB_2U(SCH_1):PAGE461_I78@PURE_QUANTA.Q_CAP_DIFFBUS(CHIPS)':
 C_PATH='@s9s_mb_2u_lib.s9s_mb_2u(sch_1):page461_i78@pure_quanta.q_cap_diffbus(chi~
ps)';

PART_NAME
 C902 'Q_CAP_DIFFBUS_C0201-DIFF BUS_0A':;

SECTION_NUMBER 1
 '@S9S_MB_2U_LIB.S9S_MB_2U(SCH_1):PAGE461_I77@PURE_QUANTA.Q_CAP_DIFFBUS(CHIPS)':
 C_PATH='@s9s_mb_2u_lib.s9s_mb_2u(sch_1):page461_i77@pure_quanta.q_cap_diffbus(chi~
ps)';

PART_NAME
 C901 'Q_CAP_DIFFBUS_C0201-DIFF BUS_0A':;

SECTION_NUMBER 1
 '@S9S_MB_2U_LIB.S9S_MB_2U(SCH_1):PAGE460_I120@PURE_QUANTA.Q_CAP_DIFFBUS(CHIPS)':
 C_PATH='@s9s_mb_2u_lib.s9s_mb_2u(sch_1):page460_i120@pure_quanta.q_cap_diffbus(ch~
ips)';

PART_NAME
 C900 'Q_CAP_DIFFBUS_C0201-DIFF BUS_0A':;

SECTION_NUMBER 1
 '@S9S_MB_2U_LIB.S9S_MB_2U(SCH_1):PAGE460_I121@PURE_QUANTA.Q_CAP_DIFFBUS(CHIPS)':
 C_PATH='@s9s_mb_2u_lib.s9s_mb_2u(sch_1):page460_i121@pure_quanta.q_cap_diffbus(ch~
ips)';

PART_NAME
 C899 'Q_CAP_DIFFBUS_C0201-DIFF BUS_0A':;

SECTION_NUMBER 1
 '@S9S_MB_2U_LIB.S9S_MB_2U(SCH_1):PAGE460_I122@PURE_QUANTA.Q_CAP_DIFFBUS(CHIPS)':
 C_PATH='@s9s_mb_2u_lib.s9s_mb_2u(sch_1):page460_i122@pure_quanta.q_cap_diffbus(ch~
ips)';

PART_NAME
 C898 'Q_CAP_DIFFBUS_C0201-DIFF BUS_0A':;

SECTION_NUMBER 1
 '@S9S_MB_2U_LIB.S9S_MB_2U(SCH_1):PAGE460_I123@PURE_QUANTA.Q_CAP_DIFFBUS(CHIPS)':
 C_PATH='@s9s_mb_2u_lib.s9s_mb_2u(sch_1):page460_i123@pure_quanta.q_cap_diffbus(ch~
ips)';

PART_NAME
 C897 'Q_CAP_DIFFBUS_C0201-DIFF BUS_0A':;

SECTION_NUMBER 1
 '@S9S_MB_2U_LIB.S9S_MB_2U(SCH_1):PAGE460_I124@PURE_QUANTA.Q_CAP_DIFFBUS(CHIPS)':
 C_PATH='@s9s_mb_2u_lib.s9s_mb_2u(sch_1):page460_i124@pure_quanta.q_cap_diffbus(ch~
ips)';

PART_NAME
 C896 'Q_CAP_DIFFBUS_C0201-DIFF BUS_0A':;

SECTION_NUMBER 1
 '@S9S_MB_2U_LIB.S9S_MB_2U(SCH_1):PAGE460_I125@PURE_QUANTA.Q_CAP_DIFFBUS(CHIPS)':
 C_PATH='@s9s_mb_2u_lib.s9s_mb_2u(sch_1):page460_i125@pure_quanta.q_cap_diffbus(ch~
ips)';

PART_NAME
 C895 'Q_CAP_DIFFBUS_C0201-DIFF BUS_0A':;

SECTION_NUMBER 1
 '@S9S_MB_2U_LIB.S9S_MB_2U(SCH_1):PAGE460_I126@PURE_QUANTA.Q_CAP_DIFFBUS(CHIPS)':
 C_PATH='@s9s_mb_2u_lib.s9s_mb_2u(sch_1):page460_i126@pure_quanta.q_cap_diffbus(ch~
ips)';

PART_NAME
 C894 'Q_CAP_DIFFBUS_C0201-DIFF BUS_0A':;

SECTION_NUMBER 1
 '@S9S_MB_2U_LIB.S9S_MB_2U(SCH_1):PAGE460_I127@PURE_QUANTA.Q_CAP_DIFFBUS(CHIPS)':
 C_PATH='@s9s_mb_2u_lib.s9s_mb_2u(sch_1):page460_i127@pure_quanta.q_cap_diffbus(ch~
ips)';

PART_NAME
 C893 'Q_CAP_DIFFBUS_C0201-DIFF BUS_0A':;

SECTION_NUMBER 1
 '@S9S_MB_2U_LIB.S9S_MB_2U(SCH_1):PAGE460_I128@PURE_QUANTA.Q_CAP_DIFFBUS(CHIPS)':
 C_PATH='@s9s_mb_2u_lib.s9s_mb_2u(sch_1):page460_i128@pure_quanta.q_cap_diffbus(ch~
ips)';

PART_NAME
 C892 'Q_CAP_DIFFBUS_C0201-DIFF BUS_0A':;

SECTION_NUMBER 1
 '@S9S_MB_2U_LIB.S9S_MB_2U(SCH_1):PAGE460_I129@PURE_QUANTA.Q_CAP_DIFFBUS(CHIPS)':
 C_PATH='@s9s_mb_2u_lib.s9s_mb_2u(sch_1):page460_i129@pure_quanta.q_cap_diffbus(ch~
ips)';

PART_NAME
 C891 'Q_CAP_DIFFBUS_C0201-DIFF BUS_0A':;

SECTION_NUMBER 1
 '@S9S_MB_2U_LIB.S9S_MB_2U(SCH_1):PAGE460_I134@PURE_QUANTA.Q_CAP_DIFFBUS(CHIPS)':
 C_PATH='@s9s_mb_2u_lib.s9s_mb_2u(sch_1):page460_i134@pure_quanta.q_cap_diffbus(ch~
ips)';

PART_NAME
 C890 'Q_CAP_DIFFBUS_C0201-DIFF BUS_0A':;

SECTION_NUMBER 1
 '@S9S_MB_2U_LIB.S9S_MB_2U(SCH_1):PAGE460_I135@PURE_QUANTA.Q_CAP_DIFFBUS(CHIPS)':
 C_PATH='@s9s_mb_2u_lib.s9s_mb_2u(sch_1):page460_i135@pure_quanta.q_cap_diffbus(ch~
ips)';

PART_NAME
 C889 'Q_CAP_DIFFBUS_C0201-DIFF BUS_0A':;

SECTION_NUMBER 1
 '@S9S_MB_2U_LIB.S9S_MB_2U(SCH_1):PAGE460_I136@PURE_QUANTA.Q_CAP_DIFFBUS(CHIPS)':
 C_PATH='@s9s_mb_2u_lib.s9s_mb_2u(sch_1):page460_i136@pure_quanta.q_cap_diffbus(ch~
ips)';

PART_NAME
 C888 'Q_CAP_DIFFBUS_C0201-DIFF BUS_0A':;

SECTION_NUMBER 1
 '@S9S_MB_2U_LIB.S9S_MB_2U(SCH_1):PAGE460_I137@PURE_QUANTA.Q_CAP_DIFFBUS(CHIPS)':
 C_PATH='@s9s_mb_2u_lib.s9s_mb_2u(sch_1):page460_i137@pure_quanta.q_cap_diffbus(ch~
ips)';

PART_NAME
 C887 'Q_CAP_DIFFBUS_C0201-DIFF BUS_0A':;

SECTION_NUMBER 1
 '@S9S_MB_2U_LIB.S9S_MB_2U(SCH_1):PAGE460_I138@PURE_QUANTA.Q_CAP_DIFFBUS(CHIPS)':
 C_PATH='@s9s_mb_2u_lib.s9s_mb_2u(sch_1):page460_i138@pure_quanta.q_cap_diffbus(ch~
ips)';

PART_NAME
 C886 'Q_CAP_DIFFBUS_C0201-DIFF BUS_0A':;

SECTION_NUMBER 1
 '@S9S_MB_2U_LIB.S9S_MB_2U(SCH_1):PAGE460_I139@PURE_QUANTA.Q_CAP_DIFFBUS(CHIPS)':
 C_PATH='@s9s_mb_2u_lib.s9s_mb_2u(sch_1):page460_i139@pure_quanta.q_cap_diffbus(ch~
ips)';

PART_NAME
 C885 'Q_CAP_DIFFBUS_C0201-DIFF BUS_0A':;

SECTION_NUMBER 1
 '@S9S_MB_2U_LIB.S9S_MB_2U(SCH_1):PAGE460_I152@PURE_QUANTA.Q_CAP_DIFFBUS(CHIPS)':
 C_PATH='@s9s_mb_2u_lib.s9s_mb_2u(sch_1):page460_i152@pure_quanta.q_cap_diffbus(ch~
ips)';

PART_NAME
 C884 'Q_CAP_DIFFBUS_C0201-DIFF BUS_0A':;

SECTION_NUMBER 1
 '@S9S_MB_2U_LIB.S9S_MB_2U(SCH_1):PAGE460_I153@PURE_QUANTA.Q_CAP_DIFFBUS(CHIPS)':
 C_PATH='@s9s_mb_2u_lib.s9s_mb_2u(sch_1):page460_i153@pure_quanta.q_cap_diffbus(ch~
ips)';

PART_NAME
 C883 'Q_CAP_DIFFBUS_C0201-DIFF BUS_0A':;

SECTION_NUMBER 1
 '@S9S_MB_2U_LIB.S9S_MB_2U(SCH_1):PAGE460_I154@PURE_QUANTA.Q_CAP_DIFFBUS(CHIPS)':
 C_PATH='@s9s_mb_2u_lib.s9s_mb_2u(sch_1):page460_i154@pure_quanta.q_cap_diffbus(ch~
ips)';

PART_NAME
 C882 'Q_CAP_DIFFBUS_C0201-DIFF BUS_0A':;

SECTION_NUMBER 1
 '@S9S_MB_2U_LIB.S9S_MB_2U(SCH_1):PAGE460_I155@PURE_QUANTA.Q_CAP_DIFFBUS(CHIPS)':
 C_PATH='@s9s_mb_2u_lib.s9s_mb_2u(sch_1):page460_i155@pure_quanta.q_cap_diffbus(ch~
ips)';

PART_NAME
 C881 'Q_CAP_DIFFBUS_C0201-DIFF BUS_0A':;

SECTION_NUMBER 1
 '@S9S_MB_2U_LIB.S9S_MB_2U(SCH_1):PAGE460_I156@PURE_QUANTA.Q_CAP_DIFFBUS(CHIPS)':
 C_PATH='@s9s_mb_2u_lib.s9s_mb_2u(sch_1):page460_i156@pure_quanta.q_cap_diffbus(ch~
ips)';

PART_NAME
 C880 'Q_CAP_DIFFBUS_C0201-DIFF BUS_0A':;

SECTION_NUMBER 1
 '@S9S_MB_2U_LIB.S9S_MB_2U(SCH_1):PAGE460_I157@PURE_QUANTA.Q_CAP_DIFFBUS(CHIPS)':
 C_PATH='@s9s_mb_2u_lib.s9s_mb_2u(sch_1):page460_i157@pure_quanta.q_cap_diffbus(ch~
ips)';

PART_NAME
 C879 'Q_CAP_DIFFBUS_C0201-DIFF BUS_0A':;

SECTION_NUMBER 1
 '@S9S_MB_2U_LIB.S9S_MB_2U(SCH_1):PAGE460_I158@PURE_QUANTA.Q_CAP_DIFFBUS(CHIPS)':
 C_PATH='@s9s_mb_2u_lib.s9s_mb_2u(sch_1):page460_i158@pure_quanta.q_cap_diffbus(ch~
ips)';

PART_NAME
 C878 'Q_CAP_DIFFBUS_C0201-DIFF BUS_0A':;

SECTION_NUMBER 1
 '@S9S_MB_2U_LIB.S9S_MB_2U(SCH_1):PAGE460_I159@PURE_QUANTA.Q_CAP_DIFFBUS(CHIPS)':
 C_PATH='@s9s_mb_2u_lib.s9s_mb_2u(sch_1):page460_i159@pure_quanta.q_cap_diffbus(ch~
ips)';

PART_NAME
 C877 'Q_CAP_DIFFBUS_C0201-DIFF BUS_0A':;

SECTION_NUMBER 1
 '@S9S_MB_2U_LIB.S9S_MB_2U(SCH_1):PAGE460_I160@PURE_QUANTA.Q_CAP_DIFFBUS(CHIPS)':
 C_PATH='@s9s_mb_2u_lib.s9s_mb_2u(sch_1):page460_i160@pure_quanta.q_cap_diffbus(ch~
ips)';

PART_NAME
 C876 'Q_CAP_DIFFBUS_C0201-DIFF BUS_0A':;

SECTION_NUMBER 1
 '@S9S_MB_2U_LIB.S9S_MB_2U(SCH_1):PAGE460_I161@PURE_QUANTA.Q_CAP_DIFFBUS(CHIPS)':
 C_PATH='@s9s_mb_2u_lib.s9s_mb_2u(sch_1):page460_i161@pure_quanta.q_cap_diffbus(ch~
ips)';

PART_NAME
 C875 'Q_CAP_DIFFBUS_C0201-DIFF BUS_0A':;

SECTION_NUMBER 1
 '@S9S_MB_2U_LIB.S9S_MB_2U(SCH_1):PAGE460_I165@PURE_QUANTA.Q_CAP_DIFFBUS(CHIPS)':
 C_PATH='@s9s_mb_2u_lib.s9s_mb_2u(sch_1):page460_i165@pure_quanta.q_cap_diffbus(ch~
ips)';

PART_NAME
 C874 'Q_CAP_DIFFBUS_C0201-DIFF BUS_0A':;

SECTION_NUMBER 1
 '@S9S_MB_2U_LIB.S9S_MB_2U(SCH_1):PAGE460_I166@PURE_QUANTA.Q_CAP_DIFFBUS(CHIPS)':
 C_PATH='@s9s_mb_2u_lib.s9s_mb_2u(sch_1):page460_i166@pure_quanta.q_cap_diffbus(ch~
ips)';

PART_NAME
 C873 'Q_CAP_DIFFBUS_C0201-DIFF BUS_0A':;

SECTION_NUMBER 1
 '@S9S_MB_2U_LIB.S9S_MB_2U(SCH_1):PAGE460_I167@PURE_QUANTA.Q_CAP_DIFFBUS(CHIPS)':
 C_PATH='@s9s_mb_2u_lib.s9s_mb_2u(sch_1):page460_i167@pure_quanta.q_cap_diffbus(ch~
ips)';

PART_NAME
 C872 'Q_CAP_DIFFBUS_C0201-DIFF BUS_0A':;

SECTION_NUMBER 1
 '@S9S_MB_2U_LIB.S9S_MB_2U(SCH_1):PAGE460_I168@PURE_QUANTA.Q_CAP_DIFFBUS(CHIPS)':
 C_PATH='@s9s_mb_2u_lib.s9s_mb_2u(sch_1):page460_i168@pure_quanta.q_cap_diffbus(ch~
ips)';

PART_NAME
 C871 'Q_CAP_DIFFBUS_C0201-DIFF BUS_0A':;

SECTION_NUMBER 1
 '@S9S_MB_2U_LIB.S9S_MB_2U(SCH_1):PAGE460_I169@PURE_QUANTA.Q_CAP_DIFFBUS(CHIPS)':
 C_PATH='@s9s_mb_2u_lib.s9s_mb_2u(sch_1):page460_i169@pure_quanta.q_cap_diffbus(ch~
ips)';

PART_NAME
 C870 'Q_CAP_DIFFBUS_C0201-DIFF BUS_0A':;

SECTION_NUMBER 1
 '@S9S_MB_2U_LIB.S9S_MB_2U(SCH_1):PAGE460_I170@PURE_QUANTA.Q_CAP_DIFFBUS(CHIPS)':
 C_PATH='@s9s_mb_2u_lib.s9s_mb_2u(sch_1):page460_i170@pure_quanta.q_cap_diffbus(ch~
ips)';

PART_NAME
 C869 'Q_CAP_DIFFBUS_C0201-DIFF BUS_0A':;

SECTION_NUMBER 1
 '@S9S_MB_2U_LIB.S9S_MB_2U(SCH_1):PAGE460_I22@PURE_QUANTA.Q_CAP_DIFFBUS(CHIPS)':
 C_PATH='@s9s_mb_2u_lib.s9s_mb_2u(sch_1):page460_i22@pure_quanta.q_cap_diffbus(chi~
ps)';

PART_NAME
 C868 'Q_CAP_DIFFBUS_C0201-DIFF BUS_0A':;

SECTION_NUMBER 1
 '@S9S_MB_2U_LIB.S9S_MB_2U(SCH_1):PAGE460_I21@PURE_QUANTA.Q_CAP_DIFFBUS(CHIPS)':
 C_PATH='@s9s_mb_2u_lib.s9s_mb_2u(sch_1):page460_i21@pure_quanta.q_cap_diffbus(chi~
ps)';

PART_NAME
 C867 'Q_CAP_DIFFBUS_C0201-DIFF BUS_0A':;

SECTION_NUMBER 1
 '@S9S_MB_2U_LIB.S9S_MB_2U(SCH_1):PAGE460_I23@PURE_QUANTA.Q_CAP_DIFFBUS(CHIPS)':
 C_PATH='@s9s_mb_2u_lib.s9s_mb_2u(sch_1):page460_i23@pure_quanta.q_cap_diffbus(chi~
ps)';

PART_NAME
 C866 'Q_CAP_DIFFBUS_C0201-DIFF BUS_0A':;

SECTION_NUMBER 1
 '@S9S_MB_2U_LIB.S9S_MB_2U(SCH_1):PAGE460_I24@PURE_QUANTA.Q_CAP_DIFFBUS(CHIPS)':
 C_PATH='@s9s_mb_2u_lib.s9s_mb_2u(sch_1):page460_i24@pure_quanta.q_cap_diffbus(chi~
ps)';

PART_NAME
 C865 'Q_CAP_DIFFBUS_C0201-DIFF BUS_0A':;

SECTION_NUMBER 1
 '@S9S_MB_2U_LIB.S9S_MB_2U(SCH_1):PAGE460_I26@PURE_QUANTA.Q_CAP_DIFFBUS(CHIPS)':
 C_PATH='@s9s_mb_2u_lib.s9s_mb_2u(sch_1):page460_i26@pure_quanta.q_cap_diffbus(chi~
ps)';

PART_NAME
 C864 'Q_CAP_DIFFBUS_C0201-DIFF BUS_0A':;

SECTION_NUMBER 1
 '@S9S_MB_2U_LIB.S9S_MB_2U(SCH_1):PAGE460_I25@PURE_QUANTA.Q_CAP_DIFFBUS(CHIPS)':
 C_PATH='@s9s_mb_2u_lib.s9s_mb_2u(sch_1):page460_i25@pure_quanta.q_cap_diffbus(chi~
ps)';

PART_NAME
 C863 'Q_CAP_DIFFBUS_C0201-DIFF BUS_0A':;

SECTION_NUMBER 1
 '@S9S_MB_2U_LIB.S9S_MB_2U(SCH_1):PAGE460_I27@PURE_QUANTA.Q_CAP_DIFFBUS(CHIPS)':
 C_PATH='@s9s_mb_2u_lib.s9s_mb_2u(sch_1):page460_i27@pure_quanta.q_cap_diffbus(chi~
ps)';

PART_NAME
 C862 'Q_CAP_DIFFBUS_C0201-DIFF BUS_0A':;

SECTION_NUMBER 1
 '@S9S_MB_2U_LIB.S9S_MB_2U(SCH_1):PAGE460_I28@PURE_QUANTA.Q_CAP_DIFFBUS(CHIPS)':
 C_PATH='@s9s_mb_2u_lib.s9s_mb_2u(sch_1):page460_i28@pure_quanta.q_cap_diffbus(chi~
ps)';

PART_NAME
 C861 'Q_CAP_DIFFBUS_C0201-DIFF BUS_0A':;

SECTION_NUMBER 1
 '@S9S_MB_2U_LIB.S9S_MB_2U(SCH_1):PAGE460_I29@PURE_QUANTA.Q_CAP_DIFFBUS(CHIPS)':
 C_PATH='@s9s_mb_2u_lib.s9s_mb_2u(sch_1):page460_i29@pure_quanta.q_cap_diffbus(chi~
ps)';

PART_NAME
 C860 'Q_CAP_DIFFBUS_C0201-DIFF BUS_0A':;

SECTION_NUMBER 1
 '@S9S_MB_2U_LIB.S9S_MB_2U(SCH_1):PAGE460_I30@PURE_QUANTA.Q_CAP_DIFFBUS(CHIPS)':
 C_PATH='@s9s_mb_2u_lib.s9s_mb_2u(sch_1):page460_i30@pure_quanta.q_cap_diffbus(chi~
ps)';

PART_NAME
 C859 'Q_CAP_DIFFBUS_C0201-DIFF BUS_0A':;

SECTION_NUMBER 1
 '@S9S_MB_2U_LIB.S9S_MB_2U(SCH_1):PAGE460_I31@PURE_QUANTA.Q_CAP_DIFFBUS(CHIPS)':
 C_PATH='@s9s_mb_2u_lib.s9s_mb_2u(sch_1):page460_i31@pure_quanta.q_cap_diffbus(chi~
ps)';

PART_NAME
 C858 'Q_CAP_DIFFBUS_C0201-DIFF BUS_0A':;

SECTION_NUMBER 1
 '@S9S_MB_2U_LIB.S9S_MB_2U(SCH_1):PAGE460_I32@PURE_QUANTA.Q_CAP_DIFFBUS(CHIPS)':
 C_PATH='@s9s_mb_2u_lib.s9s_mb_2u(sch_1):page460_i32@pure_quanta.q_cap_diffbus(chi~
ps)';

PART_NAME
 C857 'Q_CAP_DIFFBUS_C0201-DIFF BUS_0A':;

SECTION_NUMBER 1
 '@S9S_MB_2U_LIB.S9S_MB_2U(SCH_1):PAGE460_I33@PURE_QUANTA.Q_CAP_DIFFBUS(CHIPS)':
 C_PATH='@s9s_mb_2u_lib.s9s_mb_2u(sch_1):page460_i33@pure_quanta.q_cap_diffbus(chi~
ps)';

PART_NAME
 C856 'Q_CAP_DIFFBUS_C0201-DIFF BUS_0A':;

SECTION_NUMBER 1
 '@S9S_MB_2U_LIB.S9S_MB_2U(SCH_1):PAGE460_I34@PURE_QUANTA.Q_CAP_DIFFBUS(CHIPS)':
 C_PATH='@s9s_mb_2u_lib.s9s_mb_2u(sch_1):page460_i34@pure_quanta.q_cap_diffbus(chi~
ps)';

PART_NAME
 C855 'Q_CAP_DIFFBUS_C0201-DIFF BUS_0A':;

SECTION_NUMBER 1
 '@S9S_MB_2U_LIB.S9S_MB_2U(SCH_1):PAGE460_I36@PURE_QUANTA.Q_CAP_DIFFBUS(CHIPS)':
 C_PATH='@s9s_mb_2u_lib.s9s_mb_2u(sch_1):page460_i36@pure_quanta.q_cap_diffbus(chi~
ps)';

PART_NAME
 C854 'Q_CAP_DIFFBUS_C0201-DIFF BUS_0A':;

SECTION_NUMBER 1
 '@S9S_MB_2U_LIB.S9S_MB_2U(SCH_1):PAGE460_I35@PURE_QUANTA.Q_CAP_DIFFBUS(CHIPS)':
 C_PATH='@s9s_mb_2u_lib.s9s_mb_2u(sch_1):page460_i35@pure_quanta.q_cap_diffbus(chi~
ps)';

PART_NAME
 C853 'Q_CAP_DIFFBUS_C0201-DIFF BUS_0A':;

SECTION_NUMBER 1
 '@S9S_MB_2U_LIB.S9S_MB_2U(SCH_1):PAGE460_I53@PURE_QUANTA.Q_CAP_DIFFBUS(CHIPS)':
 C_PATH='@s9s_mb_2u_lib.s9s_mb_2u(sch_1):page460_i53@pure_quanta.q_cap_diffbus(chi~
ps)';

PART_NAME
 C852 'Q_CAP_DIFFBUS_C0201-DIFF BUS_0A':;

SECTION_NUMBER 1
 '@S9S_MB_2U_LIB.S9S_MB_2U(SCH_1):PAGE460_I52@PURE_QUANTA.Q_CAP_DIFFBUS(CHIPS)':
 C_PATH='@s9s_mb_2u_lib.s9s_mb_2u(sch_1):page460_i52@pure_quanta.q_cap_diffbus(chi~
ps)';

PART_NAME
 C851 'Q_CAP_DIFFBUS_C0201-DIFF BUS_0A':;

SECTION_NUMBER 1
 '@S9S_MB_2U_LIB.S9S_MB_2U(SCH_1):PAGE460_I54@PURE_QUANTA.Q_CAP_DIFFBUS(CHIPS)':
 C_PATH='@s9s_mb_2u_lib.s9s_mb_2u(sch_1):page460_i54@pure_quanta.q_cap_diffbus(chi~
ps)';

PART_NAME
 C850 'Q_CAP_DIFFBUS_C0201-DIFF BUS_0A':;

SECTION_NUMBER 1
 '@S9S_MB_2U_LIB.S9S_MB_2U(SCH_1):PAGE460_I55@PURE_QUANTA.Q_CAP_DIFFBUS(CHIPS)':
 C_PATH='@s9s_mb_2u_lib.s9s_mb_2u(sch_1):page460_i55@pure_quanta.q_cap_diffbus(chi~
ps)';

PART_NAME
 C849 'Q_CAP_DIFFBUS_C0201-DIFF BUS_0A':;

SECTION_NUMBER 1
 '@S9S_MB_2U_LIB.S9S_MB_2U(SCH_1):PAGE460_I56@PURE_QUANTA.Q_CAP_DIFFBUS(CHIPS)':
 C_PATH='@s9s_mb_2u_lib.s9s_mb_2u(sch_1):page460_i56@pure_quanta.q_cap_diffbus(chi~
ps)';

PART_NAME
 C848 'Q_CAP_DIFFBUS_C0201-DIFF BUS_0A':;

SECTION_NUMBER 1
 '@S9S_MB_2U_LIB.S9S_MB_2U(SCH_1):PAGE460_I57@PURE_QUANTA.Q_CAP_DIFFBUS(CHIPS)':
 C_PATH='@s9s_mb_2u_lib.s9s_mb_2u(sch_1):page460_i57@pure_quanta.q_cap_diffbus(chi~
ps)';

PART_NAME
 C847 'Q_CAP_DIFFBUS_C0201-DIFF BUS_0A':;

SECTION_NUMBER 1
 '@S9S_MB_2U_LIB.S9S_MB_2U(SCH_1):PAGE460_I58@PURE_QUANTA.Q_CAP_DIFFBUS(CHIPS)':
 C_PATH='@s9s_mb_2u_lib.s9s_mb_2u(sch_1):page460_i58@pure_quanta.q_cap_diffbus(chi~
ps)';

PART_NAME
 C846 'Q_CAP_DIFFBUS_C0201-DIFF BUS_0A':;

SECTION_NUMBER 1
 '@S9S_MB_2U_LIB.S9S_MB_2U(SCH_1):PAGE460_I59@PURE_QUANTA.Q_CAP_DIFFBUS(CHIPS)':
 C_PATH='@s9s_mb_2u_lib.s9s_mb_2u(sch_1):page460_i59@pure_quanta.q_cap_diffbus(chi~
ps)';

PART_NAME
 C845 'Q_CAP_DIFFBUS_C0201-DIFF BUS_0A':;

SECTION_NUMBER 1
 '@S9S_MB_2U_LIB.S9S_MB_2U(SCH_1):PAGE460_I60@PURE_QUANTA.Q_CAP_DIFFBUS(CHIPS)':
 C_PATH='@s9s_mb_2u_lib.s9s_mb_2u(sch_1):page460_i60@pure_quanta.q_cap_diffbus(chi~
ps)';

PART_NAME
 C844 'Q_CAP_DIFFBUS_C0201-DIFF BUS_0A':;

SECTION_NUMBER 1
 '@S9S_MB_2U_LIB.S9S_MB_2U(SCH_1):PAGE460_I61@PURE_QUANTA.Q_CAP_DIFFBUS(CHIPS)':
 C_PATH='@s9s_mb_2u_lib.s9s_mb_2u(sch_1):page460_i61@pure_quanta.q_cap_diffbus(chi~
ps)';

PART_NAME
 C843 'Q_CAP_DIFFBUS_C0201-DIFF BUS_0A':;

SECTION_NUMBER 1
 '@S9S_MB_2U_LIB.S9S_MB_2U(SCH_1):PAGE460_I63@PURE_QUANTA.Q_CAP_DIFFBUS(CHIPS)':
 C_PATH='@s9s_mb_2u_lib.s9s_mb_2u(sch_1):page460_i63@pure_quanta.q_cap_diffbus(chi~
ps)';

PART_NAME
 C842 'Q_CAP_DIFFBUS_C0201-DIFF BUS_0A':;

SECTION_NUMBER 1
 '@S9S_MB_2U_LIB.S9S_MB_2U(SCH_1):PAGE460_I62@PURE_QUANTA.Q_CAP_DIFFBUS(CHIPS)':
 C_PATH='@s9s_mb_2u_lib.s9s_mb_2u(sch_1):page460_i62@pure_quanta.q_cap_diffbus(chi~
ps)';

PART_NAME
 C841 'Q_CAP_DIFFBUS_C0201-DIFF BUS_0A':;

SECTION_NUMBER 1
 '@S9S_MB_2U_LIB.S9S_MB_2U(SCH_1):PAGE460_I64@PURE_QUANTA.Q_CAP_DIFFBUS(CHIPS)':
 C_PATH='@s9s_mb_2u_lib.s9s_mb_2u(sch_1):page460_i64@pure_quanta.q_cap_diffbus(chi~
ps)';

PART_NAME
 C840 'Q_CAP_DIFFBUS_C0201-DIFF BUS_0A':;

SECTION_NUMBER 1
 '@S9S_MB_2U_LIB.S9S_MB_2U(SCH_1):PAGE460_I65@PURE_QUANTA.Q_CAP_DIFFBUS(CHIPS)':
 C_PATH='@s9s_mb_2u_lib.s9s_mb_2u(sch_1):page460_i65@pure_quanta.q_cap_diffbus(chi~
ps)';

PART_NAME
 C839 'Q_CAP_DIFFBUS_C0201-DIFF BUS_0A':;

SECTION_NUMBER 1
 '@S9S_MB_2U_LIB.S9S_MB_2U(SCH_1):PAGE460_I66@PURE_QUANTA.Q_CAP_DIFFBUS(CHIPS)':
 C_PATH='@s9s_mb_2u_lib.s9s_mb_2u(sch_1):page460_i66@pure_quanta.q_cap_diffbus(chi~
ps)';

PART_NAME
 C838 'Q_CAP_DIFFBUS_C0201-DIFF BUS_0A':;

SECTION_NUMBER 1
 '@S9S_MB_2U_LIB.S9S_MB_2U(SCH_1):PAGE460_I67@PURE_QUANTA.Q_CAP_DIFFBUS(CHIPS)':
 C_PATH='@s9s_mb_2u_lib.s9s_mb_2u(sch_1):page460_i67@pure_quanta.q_cap_diffbus(chi~
ps)';

PART_NAME
 C837 'Q_CAP_DIFFBUS_C0201-DIFF BUS_0A':;

SECTION_NUMBER 1
 '@S9S_MB_2U_LIB.S9S_MB_2U(SCH_1):PAGE459_I122@PURE_QUANTA.Q_CAP_DIFFBUS(CHIPS)':
 C_PATH='@s9s_mb_2u_lib.s9s_mb_2u(sch_1):page459_i122@pure_quanta.q_cap_diffbus(ch~
ips)';

PART_NAME
 C836 'Q_CAP_DIFFBUS_C0201-DIFF BUS_0A':;

SECTION_NUMBER 1
 '@S9S_MB_2U_LIB.S9S_MB_2U(SCH_1):PAGE459_I123@PURE_QUANTA.Q_CAP_DIFFBUS(CHIPS)':
 C_PATH='@s9s_mb_2u_lib.s9s_mb_2u(sch_1):page459_i123@pure_quanta.q_cap_diffbus(ch~
ips)';

PART_NAME
 C835 'Q_CAP_DIFFBUS_C0201-DIFF BUS_0A':;

SECTION_NUMBER 1
 '@S9S_MB_2U_LIB.S9S_MB_2U(SCH_1):PAGE459_I124@PURE_QUANTA.Q_CAP_DIFFBUS(CHIPS)':
 C_PATH='@s9s_mb_2u_lib.s9s_mb_2u(sch_1):page459_i124@pure_quanta.q_cap_diffbus(ch~
ips)';

PART_NAME
 C834 'Q_CAP_DIFFBUS_C0201-DIFF BUS_0A':;

SECTION_NUMBER 1
 '@S9S_MB_2U_LIB.S9S_MB_2U(SCH_1):PAGE459_I125@PURE_QUANTA.Q_CAP_DIFFBUS(CHIPS)':
 C_PATH='@s9s_mb_2u_lib.s9s_mb_2u(sch_1):page459_i125@pure_quanta.q_cap_diffbus(ch~
ips)';

PART_NAME
 C833 'Q_CAP_DIFFBUS_C0201-DIFF BUS_0A':;

SECTION_NUMBER 1
 '@S9S_MB_2U_LIB.S9S_MB_2U(SCH_1):PAGE459_I126@PURE_QUANTA.Q_CAP_DIFFBUS(CHIPS)':
 C_PATH='@s9s_mb_2u_lib.s9s_mb_2u(sch_1):page459_i126@pure_quanta.q_cap_diffbus(ch~
ips)';

PART_NAME
 C832 'Q_CAP_DIFFBUS_C0201-DIFF BUS_0A':;

SECTION_NUMBER 1
 '@S9S_MB_2U_LIB.S9S_MB_2U(SCH_1):PAGE459_I127@PURE_QUANTA.Q_CAP_DIFFBUS(CHIPS)':
 C_PATH='@s9s_mb_2u_lib.s9s_mb_2u(sch_1):page459_i127@pure_quanta.q_cap_diffbus(ch~
ips)';

PART_NAME
 C831 'Q_CAP_DIFFBUS_C0201-DIFF BUS_0A':;

SECTION_NUMBER 1
 '@S9S_MB_2U_LIB.S9S_MB_2U(SCH_1):PAGE459_I128@PURE_QUANTA.Q_CAP_DIFFBUS(CHIPS)':
 C_PATH='@s9s_mb_2u_lib.s9s_mb_2u(sch_1):page459_i128@pure_quanta.q_cap_diffbus(ch~
ips)';

PART_NAME
 C830 'Q_CAP_DIFFBUS_C0201-DIFF BUS_0A':;

SECTION_NUMBER 1
 '@S9S_MB_2U_LIB.S9S_MB_2U(SCH_1):PAGE459_I129@PURE_QUANTA.Q_CAP_DIFFBUS(CHIPS)':
 C_PATH='@s9s_mb_2u_lib.s9s_mb_2u(sch_1):page459_i129@pure_quanta.q_cap_diffbus(ch~
ips)';

PART_NAME
 C829 'Q_CAP_DIFFBUS_C0201-DIFF BUS_0A':;

SECTION_NUMBER 1
 '@S9S_MB_2U_LIB.S9S_MB_2U(SCH_1):PAGE459_I131@PURE_QUANTA.Q_CAP_DIFFBUS(CHIPS)':
 C_PATH='@s9s_mb_2u_lib.s9s_mb_2u(sch_1):page459_i131@pure_quanta.q_cap_diffbus(ch~
ips)';

PART_NAME
 C828 'Q_CAP_DIFFBUS_C0201-DIFF BUS_0A':;

SECTION_NUMBER 1
 '@S9S_MB_2U_LIB.S9S_MB_2U(SCH_1):PAGE459_I130@PURE_QUANTA.Q_CAP_DIFFBUS(CHIPS)':
 C_PATH='@s9s_mb_2u_lib.s9s_mb_2u(sch_1):page459_i130@pure_quanta.q_cap_diffbus(ch~
ips)';

PART_NAME
 C827 'Q_CAP_DIFFBUS_C0201-DIFF BUS_0A':;

SECTION_NUMBER 1
 '@S9S_MB_2U_LIB.S9S_MB_2U(SCH_1):PAGE459_I135@PURE_QUANTA.Q_CAP_DIFFBUS(CHIPS)':
 C_PATH='@s9s_mb_2u_lib.s9s_mb_2u(sch_1):page459_i135@pure_quanta.q_cap_diffbus(ch~
ips)';

PART_NAME
 C826 'Q_CAP_DIFFBUS_C0201-DIFF BUS_0A':;

SECTION_NUMBER 1
 '@S9S_MB_2U_LIB.S9S_MB_2U(SCH_1):PAGE459_I136@PURE_QUANTA.Q_CAP_DIFFBUS(CHIPS)':
 C_PATH='@s9s_mb_2u_lib.s9s_mb_2u(sch_1):page459_i136@pure_quanta.q_cap_diffbus(ch~
ips)';

PART_NAME
 C825 'Q_CAP_DIFFBUS_C0201-DIFF BUS_0A':;

SECTION_NUMBER 1
 '@S9S_MB_2U_LIB.S9S_MB_2U(SCH_1):PAGE459_I137@PURE_QUANTA.Q_CAP_DIFFBUS(CHIPS)':
 C_PATH='@s9s_mb_2u_lib.s9s_mb_2u(sch_1):page459_i137@pure_quanta.q_cap_diffbus(ch~
ips)';

PART_NAME
 C824 'Q_CAP_DIFFBUS_C0201-DIFF BUS_0A':;

SECTION_NUMBER 1
 '@S9S_MB_2U_LIB.S9S_MB_2U(SCH_1):PAGE459_I138@PURE_QUANTA.Q_CAP_DIFFBUS(CHIPS)':
 C_PATH='@s9s_mb_2u_lib.s9s_mb_2u(sch_1):page459_i138@pure_quanta.q_cap_diffbus(ch~
ips)';

PART_NAME
 C823 'Q_CAP_DIFFBUS_C0201-DIFF BUS_0A':;

SECTION_NUMBER 1
 '@S9S_MB_2U_LIB.S9S_MB_2U(SCH_1):PAGE459_I139@PURE_QUANTA.Q_CAP_DIFFBUS(CHIPS)':
 C_PATH='@s9s_mb_2u_lib.s9s_mb_2u(sch_1):page459_i139@pure_quanta.q_cap_diffbus(ch~
ips)';

PART_NAME
 C822 'Q_CAP_DIFFBUS_C0201-DIFF BUS_0A':;

SECTION_NUMBER 1
 '@S9S_MB_2U_LIB.S9S_MB_2U(SCH_1):PAGE459_I140@PURE_QUANTA.Q_CAP_DIFFBUS(CHIPS)':
 C_PATH='@s9s_mb_2u_lib.s9s_mb_2u(sch_1):page459_i140@pure_quanta.q_cap_diffbus(ch~
ips)';

PART_NAME
 C821 'Q_CAP_DIFFBUS_C0201-DIFF BUS_0A':;

SECTION_NUMBER 1
 '@S9S_MB_2U_LIB.S9S_MB_2U(SCH_1):PAGE459_I154@PURE_QUANTA.Q_CAP_DIFFBUS(CHIPS)':
 C_PATH='@s9s_mb_2u_lib.s9s_mb_2u(sch_1):page459_i154@pure_quanta.q_cap_diffbus(ch~
ips)';

PART_NAME
 C820 'Q_CAP_DIFFBUS_C0201-DIFF BUS_0A':;

SECTION_NUMBER 1
 '@S9S_MB_2U_LIB.S9S_MB_2U(SCH_1):PAGE459_I155@PURE_QUANTA.Q_CAP_DIFFBUS(CHIPS)':
 C_PATH='@s9s_mb_2u_lib.s9s_mb_2u(sch_1):page459_i155@pure_quanta.q_cap_diffbus(ch~
ips)';

PART_NAME
 C819 'Q_CAP_DIFFBUS_C0201-DIFF BUS_0A':;

SECTION_NUMBER 1
 '@S9S_MB_2U_LIB.S9S_MB_2U(SCH_1):PAGE459_I156@PURE_QUANTA.Q_CAP_DIFFBUS(CHIPS)':
 C_PATH='@s9s_mb_2u_lib.s9s_mb_2u(sch_1):page459_i156@pure_quanta.q_cap_diffbus(ch~
ips)';

PART_NAME
 C818 'Q_CAP_DIFFBUS_C0201-DIFF BUS_0A':;

SECTION_NUMBER 1
 '@S9S_MB_2U_LIB.S9S_MB_2U(SCH_1):PAGE459_I157@PURE_QUANTA.Q_CAP_DIFFBUS(CHIPS)':
 C_PATH='@s9s_mb_2u_lib.s9s_mb_2u(sch_1):page459_i157@pure_quanta.q_cap_diffbus(ch~
ips)';

PART_NAME
 C817 'Q_CAP_DIFFBUS_C0201-DIFF BUS_0A':;

SECTION_NUMBER 1
 '@S9S_MB_2U_LIB.S9S_MB_2U(SCH_1):PAGE459_I158@PURE_QUANTA.Q_CAP_DIFFBUS(CHIPS)':
 C_PATH='@s9s_mb_2u_lib.s9s_mb_2u(sch_1):page459_i158@pure_quanta.q_cap_diffbus(ch~
ips)';

PART_NAME
 C816 'Q_CAP_DIFFBUS_C0201-DIFF BUS_0A':;

SECTION_NUMBER 1
 '@S9S_MB_2U_LIB.S9S_MB_2U(SCH_1):PAGE459_I159@PURE_QUANTA.Q_CAP_DIFFBUS(CHIPS)':
 C_PATH='@s9s_mb_2u_lib.s9s_mb_2u(sch_1):page459_i159@pure_quanta.q_cap_diffbus(ch~
ips)';

PART_NAME
 C815 'Q_CAP_DIFFBUS_C0201-DIFF BUS_0A':;

SECTION_NUMBER 1
 '@S9S_MB_2U_LIB.S9S_MB_2U(SCH_1):PAGE459_I161@PURE_QUANTA.Q_CAP_DIFFBUS(CHIPS)':
 C_PATH='@s9s_mb_2u_lib.s9s_mb_2u(sch_1):page459_i161@pure_quanta.q_cap_diffbus(ch~
ips)';

PART_NAME
 C814 'Q_CAP_DIFFBUS_C0201-DIFF BUS_0A':;

SECTION_NUMBER 1
 '@S9S_MB_2U_LIB.S9S_MB_2U(SCH_1):PAGE459_I160@PURE_QUANTA.Q_CAP_DIFFBUS(CHIPS)':
 C_PATH='@s9s_mb_2u_lib.s9s_mb_2u(sch_1):page459_i160@pure_quanta.q_cap_diffbus(ch~
ips)';

PART_NAME
 C813 'Q_CAP_DIFFBUS_C0201-DIFF BUS_0A':;

SECTION_NUMBER 1
 '@S9S_MB_2U_LIB.S9S_MB_2U(SCH_1):PAGE459_I162@PURE_QUANTA.Q_CAP_DIFFBUS(CHIPS)':
 C_PATH='@s9s_mb_2u_lib.s9s_mb_2u(sch_1):page459_i162@pure_quanta.q_cap_diffbus(ch~
ips)';

PART_NAME
 C812 'Q_CAP_DIFFBUS_C0201-DIFF BUS_0A':;

SECTION_NUMBER 1
 '@S9S_MB_2U_LIB.S9S_MB_2U(SCH_1):PAGE459_I163@PURE_QUANTA.Q_CAP_DIFFBUS(CHIPS)':
 C_PATH='@s9s_mb_2u_lib.s9s_mb_2u(sch_1):page459_i163@pure_quanta.q_cap_diffbus(ch~
ips)';

PART_NAME
 C811 'Q_CAP_DIFFBUS_C0201-DIFF BUS_0A':;

SECTION_NUMBER 1
 '@S9S_MB_2U_LIB.S9S_MB_2U(SCH_1):PAGE459_I167@PURE_QUANTA.Q_CAP_DIFFBUS(CHIPS)':
 C_PATH='@s9s_mb_2u_lib.s9s_mb_2u(sch_1):page459_i167@pure_quanta.q_cap_diffbus(ch~
ips)';

PART_NAME
 C810 'Q_CAP_DIFFBUS_C0201-DIFF BUS_0A':;

SECTION_NUMBER 1
 '@S9S_MB_2U_LIB.S9S_MB_2U(SCH_1):PAGE459_I168@PURE_QUANTA.Q_CAP_DIFFBUS(CHIPS)':
 C_PATH='@s9s_mb_2u_lib.s9s_mb_2u(sch_1):page459_i168@pure_quanta.q_cap_diffbus(ch~
ips)';

PART_NAME
 C809 'Q_CAP_DIFFBUS_C0201-DIFF BUS_0A':;

SECTION_NUMBER 1
 '@S9S_MB_2U_LIB.S9S_MB_2U(SCH_1):PAGE459_I169@PURE_QUANTA.Q_CAP_DIFFBUS(CHIPS)':
 C_PATH='@s9s_mb_2u_lib.s9s_mb_2u(sch_1):page459_i169@pure_quanta.q_cap_diffbus(ch~
ips)';

PART_NAME
 C808 'Q_CAP_DIFFBUS_C0201-DIFF BUS_0A':;

SECTION_NUMBER 1
 '@S9S_MB_2U_LIB.S9S_MB_2U(SCH_1):PAGE459_I170@PURE_QUANTA.Q_CAP_DIFFBUS(CHIPS)':
 C_PATH='@s9s_mb_2u_lib.s9s_mb_2u(sch_1):page459_i170@pure_quanta.q_cap_diffbus(ch~
ips)';

PART_NAME
 C807 'Q_CAP_DIFFBUS_C0201-DIFF BUS_0A':;

SECTION_NUMBER 1
 '@S9S_MB_2U_LIB.S9S_MB_2U(SCH_1):PAGE459_I172@PURE_QUANTA.Q_CAP_DIFFBUS(CHIPS)':
 C_PATH='@s9s_mb_2u_lib.s9s_mb_2u(sch_1):page459_i172@pure_quanta.q_cap_diffbus(ch~
ips)';

PART_NAME
 C806 'Q_CAP_DIFFBUS_C0201-DIFF BUS_0A':;

SECTION_NUMBER 1
 '@S9S_MB_2U_LIB.S9S_MB_2U(SCH_1):PAGE459_I171@PURE_QUANTA.Q_CAP_DIFFBUS(CHIPS)':
 C_PATH='@s9s_mb_2u_lib.s9s_mb_2u(sch_1):page459_i171@pure_quanta.q_cap_diffbus(ch~
ips)';

PART_NAME
 C805 'Q_CAP_DIFFBUS_C0201-DIFF BUS_0A':;

SECTION_NUMBER 1
 '@S9S_MB_2U_LIB.S9S_MB_2U(SCH_1):PAGE459_I22@PURE_QUANTA.Q_CAP_DIFFBUS(CHIPS)':
 C_PATH='@s9s_mb_2u_lib.s9s_mb_2u(sch_1):page459_i22@pure_quanta.q_cap_diffbus(chi~
ps)';

PART_NAME
 C804 'Q_CAP_DIFFBUS_C0201-DIFF BUS_0A':;

SECTION_NUMBER 1
 '@S9S_MB_2U_LIB.S9S_MB_2U(SCH_1):PAGE459_I21@PURE_QUANTA.Q_CAP_DIFFBUS(CHIPS)':
 C_PATH='@s9s_mb_2u_lib.s9s_mb_2u(sch_1):page459_i21@pure_quanta.q_cap_diffbus(chi~
ps)';

PART_NAME
 C803 'Q_CAP_DIFFBUS_C0201-DIFF BUS_0A':;

SECTION_NUMBER 1
 '@S9S_MB_2U_LIB.S9S_MB_2U(SCH_1):PAGE459_I23@PURE_QUANTA.Q_CAP_DIFFBUS(CHIPS)':
 C_PATH='@s9s_mb_2u_lib.s9s_mb_2u(sch_1):page459_i23@pure_quanta.q_cap_diffbus(chi~
ps)';

PART_NAME
 C802 'Q_CAP_DIFFBUS_C0201-DIFF BUS_0A':;

SECTION_NUMBER 1
 '@S9S_MB_2U_LIB.S9S_MB_2U(SCH_1):PAGE459_I24@PURE_QUANTA.Q_CAP_DIFFBUS(CHIPS)':
 C_PATH='@s9s_mb_2u_lib.s9s_mb_2u(sch_1):page459_i24@pure_quanta.q_cap_diffbus(chi~
ps)';

PART_NAME
 C801 'Q_CAP_DIFFBUS_C0201-DIFF BUS_0A':;

SECTION_NUMBER 1
 '@S9S_MB_2U_LIB.S9S_MB_2U(SCH_1):PAGE459_I26@PURE_QUANTA.Q_CAP_DIFFBUS(CHIPS)':
 C_PATH='@s9s_mb_2u_lib.s9s_mb_2u(sch_1):page459_i26@pure_quanta.q_cap_diffbus(chi~
ps)';

PART_NAME
 C800 'Q_CAP_DIFFBUS_C0201-DIFF BUS_0A':;

SECTION_NUMBER 1
 '@S9S_MB_2U_LIB.S9S_MB_2U(SCH_1):PAGE459_I25@PURE_QUANTA.Q_CAP_DIFFBUS(CHIPS)':
 C_PATH='@s9s_mb_2u_lib.s9s_mb_2u(sch_1):page459_i25@pure_quanta.q_cap_diffbus(chi~
ps)';

PART_NAME
 C799 'Q_CAP_DIFFBUS_C0201-DIFF BUS_0A':;

SECTION_NUMBER 1
 '@S9S_MB_2U_LIB.S9S_MB_2U(SCH_1):PAGE459_I27@PURE_QUANTA.Q_CAP_DIFFBUS(CHIPS)':
 C_PATH='@s9s_mb_2u_lib.s9s_mb_2u(sch_1):page459_i27@pure_quanta.q_cap_diffbus(chi~
ps)';

PART_NAME
 C798 'Q_CAP_DIFFBUS_C0201-DIFF BUS_0A':;

SECTION_NUMBER 1
 '@S9S_MB_2U_LIB.S9S_MB_2U(SCH_1):PAGE459_I28@PURE_QUANTA.Q_CAP_DIFFBUS(CHIPS)':
 C_PATH='@s9s_mb_2u_lib.s9s_mb_2u(sch_1):page459_i28@pure_quanta.q_cap_diffbus(chi~
ps)';

PART_NAME
 C797 'Q_CAP_DIFFBUS_C0201-DIFF BUS_0A':;

SECTION_NUMBER 1
 '@S9S_MB_2U_LIB.S9S_MB_2U(SCH_1):PAGE459_I29@PURE_QUANTA.Q_CAP_DIFFBUS(CHIPS)':
 C_PATH='@s9s_mb_2u_lib.s9s_mb_2u(sch_1):page459_i29@pure_quanta.q_cap_diffbus(chi~
ps)';

PART_NAME
 C796 'Q_CAP_DIFFBUS_C0201-DIFF BUS_0A':;

SECTION_NUMBER 1
 '@S9S_MB_2U_LIB.S9S_MB_2U(SCH_1):PAGE459_I30@PURE_QUANTA.Q_CAP_DIFFBUS(CHIPS)':
 C_PATH='@s9s_mb_2u_lib.s9s_mb_2u(sch_1):page459_i30@pure_quanta.q_cap_diffbus(chi~
ps)';

PART_NAME
 C795 'Q_CAP_DIFFBUS_C0201-DIFF BUS_0A':;

SECTION_NUMBER 1
 '@S9S_MB_2U_LIB.S9S_MB_2U(SCH_1):PAGE459_I36@PURE_QUANTA.Q_CAP_DIFFBUS(CHIPS)':
 C_PATH='@s9s_mb_2u_lib.s9s_mb_2u(sch_1):page459_i36@pure_quanta.q_cap_diffbus(chi~
ps)';

PART_NAME
 C794 'Q_CAP_DIFFBUS_C0201-DIFF BUS_0A':;

SECTION_NUMBER 1
 '@S9S_MB_2U_LIB.S9S_MB_2U(SCH_1):PAGE459_I37@PURE_QUANTA.Q_CAP_DIFFBUS(CHIPS)':
 C_PATH='@s9s_mb_2u_lib.s9s_mb_2u(sch_1):page459_i37@pure_quanta.q_cap_diffbus(chi~
ps)';

PART_NAME
 C793 'Q_CAP_DIFFBUS_C0201-DIFF BUS_0A':;

SECTION_NUMBER 1
 '@S9S_MB_2U_LIB.S9S_MB_2U(SCH_1):PAGE459_I38@PURE_QUANTA.Q_CAP_DIFFBUS(CHIPS)':
 C_PATH='@s9s_mb_2u_lib.s9s_mb_2u(sch_1):page459_i38@pure_quanta.q_cap_diffbus(chi~
ps)';

PART_NAME
 C792 'Q_CAP_DIFFBUS_C0201-DIFF BUS_0A':;

SECTION_NUMBER 1
 '@S9S_MB_2U_LIB.S9S_MB_2U(SCH_1):PAGE459_I39@PURE_QUANTA.Q_CAP_DIFFBUS(CHIPS)':
 C_PATH='@s9s_mb_2u_lib.s9s_mb_2u(sch_1):page459_i39@pure_quanta.q_cap_diffbus(chi~
ps)';

PART_NAME
 C791 'Q_CAP_DIFFBUS_C0201-DIFF BUS_0A':;

SECTION_NUMBER 1
 '@S9S_MB_2U_LIB.S9S_MB_2U(SCH_1):PAGE459_I40@PURE_QUANTA.Q_CAP_DIFFBUS(CHIPS)':
 C_PATH='@s9s_mb_2u_lib.s9s_mb_2u(sch_1):page459_i40@pure_quanta.q_cap_diffbus(chi~
ps)';

PART_NAME
 C790 'Q_CAP_DIFFBUS_C0201-DIFF BUS_0A':;

SECTION_NUMBER 1
 '@S9S_MB_2U_LIB.S9S_MB_2U(SCH_1):PAGE459_I41@PURE_QUANTA.Q_CAP_DIFFBUS(CHIPS)':
 C_PATH='@s9s_mb_2u_lib.s9s_mb_2u(sch_1):page459_i41@pure_quanta.q_cap_diffbus(chi~
ps)';

PART_NAME
 C789 'Q_CAP_DIFFBUS_C0201-DIFF BUS_0A':;

SECTION_NUMBER 1
 '@S9S_MB_2U_LIB.S9S_MB_2U(SCH_1):PAGE459_I62@PURE_QUANTA.Q_CAP_DIFFBUS(CHIPS)':
 C_PATH='@s9s_mb_2u_lib.s9s_mb_2u(sch_1):page459_i62@pure_quanta.q_cap_diffbus(chi~
ps)';

PART_NAME
 C788 'Q_CAP_DIFFBUS_C0201-DIFF BUS_0A':;

SECTION_NUMBER 1
 '@S9S_MB_2U_LIB.S9S_MB_2U(SCH_1):PAGE459_I61@PURE_QUANTA.Q_CAP_DIFFBUS(CHIPS)':
 C_PATH='@s9s_mb_2u_lib.s9s_mb_2u(sch_1):page459_i61@pure_quanta.q_cap_diffbus(chi~
ps)';

PART_NAME
 C787 'Q_CAP_DIFFBUS_C0201-DIFF BUS_0A':;

SECTION_NUMBER 1
 '@S9S_MB_2U_LIB.S9S_MB_2U(SCH_1):PAGE459_I63@PURE_QUANTA.Q_CAP_DIFFBUS(CHIPS)':
 C_PATH='@s9s_mb_2u_lib.s9s_mb_2u(sch_1):page459_i63@pure_quanta.q_cap_diffbus(chi~
ps)';

PART_NAME
 C786 'Q_CAP_DIFFBUS_C0201-DIFF BUS_0A':;

SECTION_NUMBER 1
 '@S9S_MB_2U_LIB.S9S_MB_2U(SCH_1):PAGE459_I64@PURE_QUANTA.Q_CAP_DIFFBUS(CHIPS)':
 C_PATH='@s9s_mb_2u_lib.s9s_mb_2u(sch_1):page459_i64@pure_quanta.q_cap_diffbus(chi~
ps)';

PART_NAME
 C785 'Q_CAP_DIFFBUS_C0201-DIFF BUS_0A':;

SECTION_NUMBER 1
 '@S9S_MB_2U_LIB.S9S_MB_2U(SCH_1):PAGE459_I65@PURE_QUANTA.Q_CAP_DIFFBUS(CHIPS)':
 C_PATH='@s9s_mb_2u_lib.s9s_mb_2u(sch_1):page459_i65@pure_quanta.q_cap_diffbus(chi~
ps)';

PART_NAME
 C784 'Q_CAP_DIFFBUS_C0201-DIFF BUS_0A':;

SECTION_NUMBER 1
 '@S9S_MB_2U_LIB.S9S_MB_2U(SCH_1):PAGE459_I66@PURE_QUANTA.Q_CAP_DIFFBUS(CHIPS)':
 C_PATH='@s9s_mb_2u_lib.s9s_mb_2u(sch_1):page459_i66@pure_quanta.q_cap_diffbus(chi~
ps)';

PART_NAME
 C783 'Q_CAP_DIFFBUS_C0201-DIFF BUS_0A':;

SECTION_NUMBER 1
 '@S9S_MB_2U_LIB.S9S_MB_2U(SCH_1):PAGE459_I67@PURE_QUANTA.Q_CAP_DIFFBUS(CHIPS)':
 C_PATH='@s9s_mb_2u_lib.s9s_mb_2u(sch_1):page459_i67@pure_quanta.q_cap_diffbus(chi~
ps)';

PART_NAME
 C782 'Q_CAP_DIFFBUS_C0201-DIFF BUS_0A':;

SECTION_NUMBER 1
 '@S9S_MB_2U_LIB.S9S_MB_2U(SCH_1):PAGE459_I68@PURE_QUANTA.Q_CAP_DIFFBUS(CHIPS)':
 C_PATH='@s9s_mb_2u_lib.s9s_mb_2u(sch_1):page459_i68@pure_quanta.q_cap_diffbus(chi~
ps)';

PART_NAME
 C781 'Q_CAP_DIFFBUS_C0201-DIFF BUS_0A':;

SECTION_NUMBER 1
 '@S9S_MB_2U_LIB.S9S_MB_2U(SCH_1):PAGE459_I69@PURE_QUANTA.Q_CAP_DIFFBUS(CHIPS)':
 C_PATH='@s9s_mb_2u_lib.s9s_mb_2u(sch_1):page459_i69@pure_quanta.q_cap_diffbus(chi~
ps)';

PART_NAME
 C780 'Q_CAP_DIFFBUS_C0201-DIFF BUS_0A':;

SECTION_NUMBER 1
 '@S9S_MB_2U_LIB.S9S_MB_2U(SCH_1):PAGE459_I70@PURE_QUANTA.Q_CAP_DIFFBUS(CHIPS)':
 C_PATH='@s9s_mb_2u_lib.s9s_mb_2u(sch_1):page459_i70@pure_quanta.q_cap_diffbus(chi~
ps)';

PART_NAME
 C779 'Q_CAP_DIFFBUS_C0201-DIFF BUS_0A':;

SECTION_NUMBER 1
 '@S9S_MB_2U_LIB.S9S_MB_2U(SCH_1):PAGE459_I77@PURE_QUANTA.Q_CAP_DIFFBUS(CHIPS)':
 C_PATH='@s9s_mb_2u_lib.s9s_mb_2u(sch_1):page459_i77@pure_quanta.q_cap_diffbus(chi~
ps)';

PART_NAME
 C778 'Q_CAP_DIFFBUS_C0201-DIFF BUS_0A':;

SECTION_NUMBER 1
 '@S9S_MB_2U_LIB.S9S_MB_2U(SCH_1):PAGE459_I76@PURE_QUANTA.Q_CAP_DIFFBUS(CHIPS)':
 C_PATH='@s9s_mb_2u_lib.s9s_mb_2u(sch_1):page459_i76@pure_quanta.q_cap_diffbus(chi~
ps)';

PART_NAME
 C777 'Q_CAP_DIFFBUS_C0201-DIFF BUS_0A':;

SECTION_NUMBER 1
 '@S9S_MB_2U_LIB.S9S_MB_2U(SCH_1):PAGE459_I78@PURE_QUANTA.Q_CAP_DIFFBUS(CHIPS)':
 C_PATH='@s9s_mb_2u_lib.s9s_mb_2u(sch_1):page459_i78@pure_quanta.q_cap_diffbus(chi~
ps)';

PART_NAME
 C776 'Q_CAP_DIFFBUS_C0201-DIFF BUS_0A':;

SECTION_NUMBER 1
 '@S9S_MB_2U_LIB.S9S_MB_2U(SCH_1):PAGE459_I79@PURE_QUANTA.Q_CAP_DIFFBUS(CHIPS)':
 C_PATH='@s9s_mb_2u_lib.s9s_mb_2u(sch_1):page459_i79@pure_quanta.q_cap_diffbus(chi~
ps)';

PART_NAME
 C775 'Q_CAP_DIFFBUS_C0201-DIFF BUS_0A':;

SECTION_NUMBER 1
 '@S9S_MB_2U_LIB.S9S_MB_2U(SCH_1):PAGE459_I80@PURE_QUANTA.Q_CAP_DIFFBUS(CHIPS)':
 C_PATH='@s9s_mb_2u_lib.s9s_mb_2u(sch_1):page459_i80@pure_quanta.q_cap_diffbus(chi~
ps)';

PART_NAME
 C774 'Q_CAP_DIFFBUS_C0201-DIFF BUS_0A':;

SECTION_NUMBER 1
 '@S9S_MB_2U_LIB.S9S_MB_2U(SCH_1):PAGE459_I81@PURE_QUANTA.Q_CAP_DIFFBUS(CHIPS)':
 C_PATH='@s9s_mb_2u_lib.s9s_mb_2u(sch_1):page459_i81@pure_quanta.q_cap_diffbus(chi~
ps)';

PART_NAME
 C773 'Q_CAP_DIFFBUS_C0201-DIFF BUS_0A':;

SECTION_NUMBER 1
 '@S9S_MB_2U_LIB.S9S_MB_2U(SCH_1):PAGE458_I122@PURE_QUANTA.Q_CAP_DIFFBUS(CHIPS)':
 C_PATH='@s9s_mb_2u_lib.s9s_mb_2u(sch_1):page458_i122@pure_quanta.q_cap_diffbus(ch~
ips)';

PART_NAME
 C772 'Q_CAP_DIFFBUS_C0201-DIFF BUS_0A':;

SECTION_NUMBER 1
 '@S9S_MB_2U_LIB.S9S_MB_2U(SCH_1):PAGE458_I123@PURE_QUANTA.Q_CAP_DIFFBUS(CHIPS)':
 C_PATH='@s9s_mb_2u_lib.s9s_mb_2u(sch_1):page458_i123@pure_quanta.q_cap_diffbus(ch~
ips)';

PART_NAME
 C771 'Q_CAP_DIFFBUS_C0201-DIFF BUS_0A':;

SECTION_NUMBER 1
 '@S9S_MB_2U_LIB.S9S_MB_2U(SCH_1):PAGE458_I124@PURE_QUANTA.Q_CAP_DIFFBUS(CHIPS)':
 C_PATH='@s9s_mb_2u_lib.s9s_mb_2u(sch_1):page458_i124@pure_quanta.q_cap_diffbus(ch~
ips)';

PART_NAME
 C770 'Q_CAP_DIFFBUS_C0201-DIFF BUS_0A':;

SECTION_NUMBER 1
 '@S9S_MB_2U_LIB.S9S_MB_2U(SCH_1):PAGE458_I125@PURE_QUANTA.Q_CAP_DIFFBUS(CHIPS)':
 C_PATH='@s9s_mb_2u_lib.s9s_mb_2u(sch_1):page458_i125@pure_quanta.q_cap_diffbus(ch~
ips)';

PART_NAME
 C769 'Q_CAP_DIFFBUS_C0201-DIFF BUS_0A':;

SECTION_NUMBER 1
 '@S9S_MB_2U_LIB.S9S_MB_2U(SCH_1):PAGE458_I126@PURE_QUANTA.Q_CAP_DIFFBUS(CHIPS)':
 C_PATH='@s9s_mb_2u_lib.s9s_mb_2u(sch_1):page458_i126@pure_quanta.q_cap_diffbus(ch~
ips)';

PART_NAME
 C768 'Q_CAP_DIFFBUS_C0201-DIFF BUS_0A':;

SECTION_NUMBER 1
 '@S9S_MB_2U_LIB.S9S_MB_2U(SCH_1):PAGE458_I127@PURE_QUANTA.Q_CAP_DIFFBUS(CHIPS)':
 C_PATH='@s9s_mb_2u_lib.s9s_mb_2u(sch_1):page458_i127@pure_quanta.q_cap_diffbus(ch~
ips)';

PART_NAME
 C767 'Q_CAP_DIFFBUS_C0201-DIFF BUS_0A':;

SECTION_NUMBER 1
 '@S9S_MB_2U_LIB.S9S_MB_2U(SCH_1):PAGE458_I128@PURE_QUANTA.Q_CAP_DIFFBUS(CHIPS)':
 C_PATH='@s9s_mb_2u_lib.s9s_mb_2u(sch_1):page458_i128@pure_quanta.q_cap_diffbus(ch~
ips)';

PART_NAME
 C766 'Q_CAP_DIFFBUS_C0201-DIFF BUS_0A':;

SECTION_NUMBER 1
 '@S9S_MB_2U_LIB.S9S_MB_2U(SCH_1):PAGE458_I129@PURE_QUANTA.Q_CAP_DIFFBUS(CHIPS)':
 C_PATH='@s9s_mb_2u_lib.s9s_mb_2u(sch_1):page458_i129@pure_quanta.q_cap_diffbus(ch~
ips)';

PART_NAME
 C765 'Q_CAP_DIFFBUS_C0201-DIFF BUS_0A':;

SECTION_NUMBER 1
 '@S9S_MB_2U_LIB.S9S_MB_2U(SCH_1):PAGE458_I131@PURE_QUANTA.Q_CAP_DIFFBUS(CHIPS)':
 C_PATH='@s9s_mb_2u_lib.s9s_mb_2u(sch_1):page458_i131@pure_quanta.q_cap_diffbus(ch~
ips)';

PART_NAME
 C764 'Q_CAP_DIFFBUS_C0201-DIFF BUS_0A':;

SECTION_NUMBER 1
 '@S9S_MB_2U_LIB.S9S_MB_2U(SCH_1):PAGE458_I130@PURE_QUANTA.Q_CAP_DIFFBUS(CHIPS)':
 C_PATH='@s9s_mb_2u_lib.s9s_mb_2u(sch_1):page458_i130@pure_quanta.q_cap_diffbus(ch~
ips)';

PART_NAME
 C763 'Q_CAP_DIFFBUS_C0201-DIFF BUS_0A':;

SECTION_NUMBER 1
 '@S9S_MB_2U_LIB.S9S_MB_2U(SCH_1):PAGE458_I135@PURE_QUANTA.Q_CAP_DIFFBUS(CHIPS)':
 C_PATH='@s9s_mb_2u_lib.s9s_mb_2u(sch_1):page458_i135@pure_quanta.q_cap_diffbus(ch~
ips)';

PART_NAME
 C762 'Q_CAP_DIFFBUS_C0201-DIFF BUS_0A':;

SECTION_NUMBER 1
 '@S9S_MB_2U_LIB.S9S_MB_2U(SCH_1):PAGE458_I136@PURE_QUANTA.Q_CAP_DIFFBUS(CHIPS)':
 C_PATH='@s9s_mb_2u_lib.s9s_mb_2u(sch_1):page458_i136@pure_quanta.q_cap_diffbus(ch~
ips)';

PART_NAME
 C761 'Q_CAP_DIFFBUS_C0201-DIFF BUS_0A':;

SECTION_NUMBER 1
 '@S9S_MB_2U_LIB.S9S_MB_2U(SCH_1):PAGE458_I137@PURE_QUANTA.Q_CAP_DIFFBUS(CHIPS)':
 C_PATH='@s9s_mb_2u_lib.s9s_mb_2u(sch_1):page458_i137@pure_quanta.q_cap_diffbus(ch~
ips)';

PART_NAME
 C760 'Q_CAP_DIFFBUS_C0201-DIFF BUS_0A':;

SECTION_NUMBER 1
 '@S9S_MB_2U_LIB.S9S_MB_2U(SCH_1):PAGE458_I138@PURE_QUANTA.Q_CAP_DIFFBUS(CHIPS)':
 C_PATH='@s9s_mb_2u_lib.s9s_mb_2u(sch_1):page458_i138@pure_quanta.q_cap_diffbus(ch~
ips)';

PART_NAME
 C759 'Q_CAP_DIFFBUS_C0201-DIFF BUS_0A':;

SECTION_NUMBER 1
 '@S9S_MB_2U_LIB.S9S_MB_2U(SCH_1):PAGE458_I139@PURE_QUANTA.Q_CAP_DIFFBUS(CHIPS)':
 C_PATH='@s9s_mb_2u_lib.s9s_mb_2u(sch_1):page458_i139@pure_quanta.q_cap_diffbus(ch~
ips)';

PART_NAME
 C758 'Q_CAP_DIFFBUS_C0201-DIFF BUS_0A':;

SECTION_NUMBER 1
 '@S9S_MB_2U_LIB.S9S_MB_2U(SCH_1):PAGE458_I140@PURE_QUANTA.Q_CAP_DIFFBUS(CHIPS)':
 C_PATH='@s9s_mb_2u_lib.s9s_mb_2u(sch_1):page458_i140@pure_quanta.q_cap_diffbus(ch~
ips)';

PART_NAME
 C757 'Q_CAP_DIFFBUS_C0201-DIFF BUS_0A':;

SECTION_NUMBER 1
 '@S9S_MB_2U_LIB.S9S_MB_2U(SCH_1):PAGE458_I155@PURE_QUANTA.Q_CAP_DIFFBUS(CHIPS)':
 C_PATH='@s9s_mb_2u_lib.s9s_mb_2u(sch_1):page458_i155@pure_quanta.q_cap_diffbus(ch~
ips)';

PART_NAME
 C756 'Q_CAP_DIFFBUS_C0201-DIFF BUS_0A':;

SECTION_NUMBER 1
 '@S9S_MB_2U_LIB.S9S_MB_2U(SCH_1):PAGE458_I154@PURE_QUANTA.Q_CAP_DIFFBUS(CHIPS)':
 C_PATH='@s9s_mb_2u_lib.s9s_mb_2u(sch_1):page458_i154@pure_quanta.q_cap_diffbus(ch~
ips)';

PART_NAME
 C755 'Q_CAP_DIFFBUS_C0201-DIFF BUS_0A':;

SECTION_NUMBER 1
 '@S9S_MB_2U_LIB.S9S_MB_2U(SCH_1):PAGE458_I156@PURE_QUANTA.Q_CAP_DIFFBUS(CHIPS)':
 C_PATH='@s9s_mb_2u_lib.s9s_mb_2u(sch_1):page458_i156@pure_quanta.q_cap_diffbus(ch~
ips)';

PART_NAME
 C754 'Q_CAP_DIFFBUS_C0201-DIFF BUS_0A':;

SECTION_NUMBER 1
 '@S9S_MB_2U_LIB.S9S_MB_2U(SCH_1):PAGE458_I157@PURE_QUANTA.Q_CAP_DIFFBUS(CHIPS)':
 C_PATH='@s9s_mb_2u_lib.s9s_mb_2u(sch_1):page458_i157@pure_quanta.q_cap_diffbus(ch~
ips)';

PART_NAME
 C753 'Q_CAP_DIFFBUS_C0201-DIFF BUS_0A':;

SECTION_NUMBER 1
 '@S9S_MB_2U_LIB.S9S_MB_2U(SCH_1):PAGE458_I158@PURE_QUANTA.Q_CAP_DIFFBUS(CHIPS)':
 C_PATH='@s9s_mb_2u_lib.s9s_mb_2u(sch_1):page458_i158@pure_quanta.q_cap_diffbus(ch~
ips)';

PART_NAME
 C752 'Q_CAP_DIFFBUS_C0201-DIFF BUS_0A':;

SECTION_NUMBER 1
 '@S9S_MB_2U_LIB.S9S_MB_2U(SCH_1):PAGE458_I159@PURE_QUANTA.Q_CAP_DIFFBUS(CHIPS)':
 C_PATH='@s9s_mb_2u_lib.s9s_mb_2u(sch_1):page458_i159@pure_quanta.q_cap_diffbus(ch~
ips)';

PART_NAME
 C751 'Q_CAP_DIFFBUS_C0201-DIFF BUS_0A':;

SECTION_NUMBER 1
 '@S9S_MB_2U_LIB.S9S_MB_2U(SCH_1):PAGE458_I161@PURE_QUANTA.Q_CAP_DIFFBUS(CHIPS)':
 C_PATH='@s9s_mb_2u_lib.s9s_mb_2u(sch_1):page458_i161@pure_quanta.q_cap_diffbus(ch~
ips)';

PART_NAME
 C750 'Q_CAP_DIFFBUS_C0201-DIFF BUS_0A':;

SECTION_NUMBER 1
 '@S9S_MB_2U_LIB.S9S_MB_2U(SCH_1):PAGE458_I160@PURE_QUANTA.Q_CAP_DIFFBUS(CHIPS)':
 C_PATH='@s9s_mb_2u_lib.s9s_mb_2u(sch_1):page458_i160@pure_quanta.q_cap_diffbus(ch~
ips)';

PART_NAME
 C749 'Q_CAP_DIFFBUS_C0201-DIFF BUS_0A':;

SECTION_NUMBER 1
 '@S9S_MB_2U_LIB.S9S_MB_2U(SCH_1):PAGE458_I162@PURE_QUANTA.Q_CAP_DIFFBUS(CHIPS)':
 C_PATH='@s9s_mb_2u_lib.s9s_mb_2u(sch_1):page458_i162@pure_quanta.q_cap_diffbus(ch~
ips)';

PART_NAME
 C748 'Q_CAP_DIFFBUS_C0201-DIFF BUS_0A':;

SECTION_NUMBER 1
 '@S9S_MB_2U_LIB.S9S_MB_2U(SCH_1):PAGE458_I163@PURE_QUANTA.Q_CAP_DIFFBUS(CHIPS)':
 C_PATH='@s9s_mb_2u_lib.s9s_mb_2u(sch_1):page458_i163@pure_quanta.q_cap_diffbus(ch~
ips)';

PART_NAME
 C747 'Q_CAP_DIFFBUS_C0201-DIFF BUS_0A':;

SECTION_NUMBER 1
 '@S9S_MB_2U_LIB.S9S_MB_2U(SCH_1):PAGE458_I167@PURE_QUANTA.Q_CAP_DIFFBUS(CHIPS)':
 C_PATH='@s9s_mb_2u_lib.s9s_mb_2u(sch_1):page458_i167@pure_quanta.q_cap_diffbus(ch~
ips)';

PART_NAME
 C746 'Q_CAP_DIFFBUS_C0201-DIFF BUS_0A':;

SECTION_NUMBER 1
 '@S9S_MB_2U_LIB.S9S_MB_2U(SCH_1):PAGE458_I168@PURE_QUANTA.Q_CAP_DIFFBUS(CHIPS)':
 C_PATH='@s9s_mb_2u_lib.s9s_mb_2u(sch_1):page458_i168@pure_quanta.q_cap_diffbus(ch~
ips)';

PART_NAME
 C745 'Q_CAP_DIFFBUS_C0201-DIFF BUS_0A':;

SECTION_NUMBER 1
 '@S9S_MB_2U_LIB.S9S_MB_2U(SCH_1):PAGE458_I169@PURE_QUANTA.Q_CAP_DIFFBUS(CHIPS)':
 C_PATH='@s9s_mb_2u_lib.s9s_mb_2u(sch_1):page458_i169@pure_quanta.q_cap_diffbus(ch~
ips)';

PART_NAME
 C744 'Q_CAP_DIFFBUS_C0201-DIFF BUS_0A':;

SECTION_NUMBER 1
 '@S9S_MB_2U_LIB.S9S_MB_2U(SCH_1):PAGE458_I170@PURE_QUANTA.Q_CAP_DIFFBUS(CHIPS)':
 C_PATH='@s9s_mb_2u_lib.s9s_mb_2u(sch_1):page458_i170@pure_quanta.q_cap_diffbus(ch~
ips)';

PART_NAME
 C743 'Q_CAP_DIFFBUS_C0201-DIFF BUS_0A':;

SECTION_NUMBER 1
 '@S9S_MB_2U_LIB.S9S_MB_2U(SCH_1):PAGE458_I171@PURE_QUANTA.Q_CAP_DIFFBUS(CHIPS)':
 C_PATH='@s9s_mb_2u_lib.s9s_mb_2u(sch_1):page458_i171@pure_quanta.q_cap_diffbus(ch~
ips)';

PART_NAME
 C742 'Q_CAP_DIFFBUS_C0201-DIFF BUS_0A':;

SECTION_NUMBER 1
 '@S9S_MB_2U_LIB.S9S_MB_2U(SCH_1):PAGE458_I172@PURE_QUANTA.Q_CAP_DIFFBUS(CHIPS)':
 C_PATH='@s9s_mb_2u_lib.s9s_mb_2u(sch_1):page458_i172@pure_quanta.q_cap_diffbus(ch~
ips)';

PART_NAME
 C741 'Q_CAP_DIFFBUS_C0201-DIFF BUS_0A':;

SECTION_NUMBER 1
 '@S9S_MB_2U_LIB.S9S_MB_2U(SCH_1):PAGE458_I21@PURE_QUANTA.Q_CAP_DIFFBUS(CHIPS)':
 C_PATH='@s9s_mb_2u_lib.s9s_mb_2u(sch_1):page458_i21@pure_quanta.q_cap_diffbus(chi~
ps)';

PART_NAME
 C740 'Q_CAP_DIFFBUS_C0201-DIFF BUS_0A':;

SECTION_NUMBER 1
 '@S9S_MB_2U_LIB.S9S_MB_2U(SCH_1):PAGE458_I22@PURE_QUANTA.Q_CAP_DIFFBUS(CHIPS)':
 C_PATH='@s9s_mb_2u_lib.s9s_mb_2u(sch_1):page458_i22@pure_quanta.q_cap_diffbus(chi~
ps)';

PART_NAME
 C739 'Q_CAP_DIFFBUS_C0201-DIFF BUS_0A':;

SECTION_NUMBER 1
 '@S9S_MB_2U_LIB.S9S_MB_2U(SCH_1):PAGE458_I24@PURE_QUANTA.Q_CAP_DIFFBUS(CHIPS)':
 C_PATH='@s9s_mb_2u_lib.s9s_mb_2u(sch_1):page458_i24@pure_quanta.q_cap_diffbus(chi~
ps)';

PART_NAME
 C738 'Q_CAP_DIFFBUS_C0201-DIFF BUS_0A':;

SECTION_NUMBER 1
 '@S9S_MB_2U_LIB.S9S_MB_2U(SCH_1):PAGE458_I23@PURE_QUANTA.Q_CAP_DIFFBUS(CHIPS)':
 C_PATH='@s9s_mb_2u_lib.s9s_mb_2u(sch_1):page458_i23@pure_quanta.q_cap_diffbus(chi~
ps)';

PART_NAME
 C737 'Q_CAP_DIFFBUS_C0201-DIFF BUS_0A':;

SECTION_NUMBER 1
 '@S9S_MB_2U_LIB.S9S_MB_2U(SCH_1):PAGE458_I25@PURE_QUANTA.Q_CAP_DIFFBUS(CHIPS)':
 C_PATH='@s9s_mb_2u_lib.s9s_mb_2u(sch_1):page458_i25@pure_quanta.q_cap_diffbus(chi~
ps)';

PART_NAME
 C736 'Q_CAP_DIFFBUS_C0201-DIFF BUS_0A':;

SECTION_NUMBER 1
 '@S9S_MB_2U_LIB.S9S_MB_2U(SCH_1):PAGE458_I27@PURE_QUANTA.Q_CAP_DIFFBUS(CHIPS)':
 C_PATH='@s9s_mb_2u_lib.s9s_mb_2u(sch_1):page458_i27@pure_quanta.q_cap_diffbus(chi~
ps)';

PART_NAME
 C735 'Q_CAP_DIFFBUS_C0201-DIFF BUS_0A':;

SECTION_NUMBER 1
 '@S9S_MB_2U_LIB.S9S_MB_2U(SCH_1):PAGE458_I26@PURE_QUANTA.Q_CAP_DIFFBUS(CHIPS)':
 C_PATH='@s9s_mb_2u_lib.s9s_mb_2u(sch_1):page458_i26@pure_quanta.q_cap_diffbus(chi~
ps)';

PART_NAME
 C734 'Q_CAP_DIFFBUS_C0201-DIFF BUS_0A':;

SECTION_NUMBER 1
 '@S9S_MB_2U_LIB.S9S_MB_2U(SCH_1):PAGE458_I30@PURE_QUANTA.Q_CAP_DIFFBUS(CHIPS)':
 C_PATH='@s9s_mb_2u_lib.s9s_mb_2u(sch_1):page458_i30@pure_quanta.q_cap_diffbus(chi~
ps)';

PART_NAME
 C733 'Q_CAP_DIFFBUS_C0201-DIFF BUS_0A':;

SECTION_NUMBER 1
 '@S9S_MB_2U_LIB.S9S_MB_2U(SCH_1):PAGE458_I29@PURE_QUANTA.Q_CAP_DIFFBUS(CHIPS)':
 C_PATH='@s9s_mb_2u_lib.s9s_mb_2u(sch_1):page458_i29@pure_quanta.q_cap_diffbus(chi~
ps)';

PART_NAME
 C732 'Q_CAP_DIFFBUS_C0201-DIFF BUS_0A':;

SECTION_NUMBER 1
 '@S9S_MB_2U_LIB.S9S_MB_2U(SCH_1):PAGE458_I28@PURE_QUANTA.Q_CAP_DIFFBUS(CHIPS)':
 C_PATH='@s9s_mb_2u_lib.s9s_mb_2u(sch_1):page458_i28@pure_quanta.q_cap_diffbus(chi~
ps)';

PART_NAME
 C731 'Q_CAP_DIFFBUS_C0201-DIFF BUS_0A':;

SECTION_NUMBER 1
 '@S9S_MB_2U_LIB.S9S_MB_2U(SCH_1):PAGE458_I37@PURE_QUANTA.Q_CAP_DIFFBUS(CHIPS)':
 C_PATH='@s9s_mb_2u_lib.s9s_mb_2u(sch_1):page458_i37@pure_quanta.q_cap_diffbus(chi~
ps)';

PART_NAME
 C730 'Q_CAP_DIFFBUS_C0201-DIFF BUS_0A':;

SECTION_NUMBER 1
 '@S9S_MB_2U_LIB.S9S_MB_2U(SCH_1):PAGE458_I36@PURE_QUANTA.Q_CAP_DIFFBUS(CHIPS)':
 C_PATH='@s9s_mb_2u_lib.s9s_mb_2u(sch_1):page458_i36@pure_quanta.q_cap_diffbus(chi~
ps)';

PART_NAME
 C729 'Q_CAP_DIFFBUS_C0201-DIFF BUS_0A':;

SECTION_NUMBER 1
 '@S9S_MB_2U_LIB.S9S_MB_2U(SCH_1):PAGE458_I39@PURE_QUANTA.Q_CAP_DIFFBUS(CHIPS)':
 C_PATH='@s9s_mb_2u_lib.s9s_mb_2u(sch_1):page458_i39@pure_quanta.q_cap_diffbus(chi~
ps)';

PART_NAME
 C728 'Q_CAP_DIFFBUS_C0201-DIFF BUS_0A':;

SECTION_NUMBER 1
 '@S9S_MB_2U_LIB.S9S_MB_2U(SCH_1):PAGE458_I38@PURE_QUANTA.Q_CAP_DIFFBUS(CHIPS)':
 C_PATH='@s9s_mb_2u_lib.s9s_mb_2u(sch_1):page458_i38@pure_quanta.q_cap_diffbus(chi~
ps)';

PART_NAME
 C727 'Q_CAP_DIFFBUS_C0201-DIFF BUS_0A':;

SECTION_NUMBER 1
 '@S9S_MB_2U_LIB.S9S_MB_2U(SCH_1):PAGE458_I40@PURE_QUANTA.Q_CAP_DIFFBUS(CHIPS)':
 C_PATH='@s9s_mb_2u_lib.s9s_mb_2u(sch_1):page458_i40@pure_quanta.q_cap_diffbus(chi~
ps)';

PART_NAME
 C726 'Q_CAP_DIFFBUS_C0201-DIFF BUS_0A':;

SECTION_NUMBER 1
 '@S9S_MB_2U_LIB.S9S_MB_2U(SCH_1):PAGE458_I41@PURE_QUANTA.Q_CAP_DIFFBUS(CHIPS)':
 C_PATH='@s9s_mb_2u_lib.s9s_mb_2u(sch_1):page458_i41@pure_quanta.q_cap_diffbus(chi~
ps)';

PART_NAME
 C725 'Q_CAP_DIFFBUS_C0201-DIFF BUS_0A':;

SECTION_NUMBER 1
 '@S9S_MB_2U_LIB.S9S_MB_2U(SCH_1):PAGE458_I61@PURE_QUANTA.Q_CAP_DIFFBUS(CHIPS)':
 C_PATH='@s9s_mb_2u_lib.s9s_mb_2u(sch_1):page458_i61@pure_quanta.q_cap_diffbus(chi~
ps)';

PART_NAME
 C724 'Q_CAP_DIFFBUS_C0201-DIFF BUS_0A':;

SECTION_NUMBER 1
 '@S9S_MB_2U_LIB.S9S_MB_2U(SCH_1):PAGE458_I62@PURE_QUANTA.Q_CAP_DIFFBUS(CHIPS)':
 C_PATH='@s9s_mb_2u_lib.s9s_mb_2u(sch_1):page458_i62@pure_quanta.q_cap_diffbus(chi~
ps)';

PART_NAME
 C723 'Q_CAP_DIFFBUS_C0201-DIFF BUS_0A':;

SECTION_NUMBER 1
 '@S9S_MB_2U_LIB.S9S_MB_2U(SCH_1):PAGE458_I63@PURE_QUANTA.Q_CAP_DIFFBUS(CHIPS)':
 C_PATH='@s9s_mb_2u_lib.s9s_mb_2u(sch_1):page458_i63@pure_quanta.q_cap_diffbus(chi~
ps)';

PART_NAME
 C722 'Q_CAP_DIFFBUS_C0201-DIFF BUS_0A':;

SECTION_NUMBER 1
 '@S9S_MB_2U_LIB.S9S_MB_2U(SCH_1):PAGE458_I65@PURE_QUANTA.Q_CAP_DIFFBUS(CHIPS)':
 C_PATH='@s9s_mb_2u_lib.s9s_mb_2u(sch_1):page458_i65@pure_quanta.q_cap_diffbus(chi~
ps)';

PART_NAME
 C721 'Q_CAP_DIFFBUS_C0201-DIFF BUS_0A':;

SECTION_NUMBER 1
 '@S9S_MB_2U_LIB.S9S_MB_2U(SCH_1):PAGE458_I64@PURE_QUANTA.Q_CAP_DIFFBUS(CHIPS)':
 C_PATH='@s9s_mb_2u_lib.s9s_mb_2u(sch_1):page458_i64@pure_quanta.q_cap_diffbus(chi~
ps)';

PART_NAME
 C720 'Q_CAP_DIFFBUS_C0201-DIFF BUS_0A':;

SECTION_NUMBER 1
 '@S9S_MB_2U_LIB.S9S_MB_2U(SCH_1):PAGE458_I66@PURE_QUANTA.Q_CAP_DIFFBUS(CHIPS)':
 C_PATH='@s9s_mb_2u_lib.s9s_mb_2u(sch_1):page458_i66@pure_quanta.q_cap_diffbus(chi~
ps)';

PART_NAME
 C719 'Q_CAP_DIFFBUS_C0201-DIFF BUS_0A':;

SECTION_NUMBER 1
 '@S9S_MB_2U_LIB.S9S_MB_2U(SCH_1):PAGE458_I68@PURE_QUANTA.Q_CAP_DIFFBUS(CHIPS)':
 C_PATH='@s9s_mb_2u_lib.s9s_mb_2u(sch_1):page458_i68@pure_quanta.q_cap_diffbus(chi~
ps)';

PART_NAME
 C718 'Q_CAP_DIFFBUS_C0201-DIFF BUS_0A':;

SECTION_NUMBER 1
 '@S9S_MB_2U_LIB.S9S_MB_2U(SCH_1):PAGE458_I67@PURE_QUANTA.Q_CAP_DIFFBUS(CHIPS)':
 C_PATH='@s9s_mb_2u_lib.s9s_mb_2u(sch_1):page458_i67@pure_quanta.q_cap_diffbus(chi~
ps)';

PART_NAME
 C717 'Q_CAP_DIFFBUS_C0201-DIFF BUS_0A':;

SECTION_NUMBER 1
 '@S9S_MB_2U_LIB.S9S_MB_2U(SCH_1):PAGE458_I70@PURE_QUANTA.Q_CAP_DIFFBUS(CHIPS)':
 C_PATH='@s9s_mb_2u_lib.s9s_mb_2u(sch_1):page458_i70@pure_quanta.q_cap_diffbus(chi~
ps)';

PART_NAME
 C716 'Q_CAP_DIFFBUS_C0201-DIFF BUS_0A':;

SECTION_NUMBER 1
 '@S9S_MB_2U_LIB.S9S_MB_2U(SCH_1):PAGE458_I69@PURE_QUANTA.Q_CAP_DIFFBUS(CHIPS)':
 C_PATH='@s9s_mb_2u_lib.s9s_mb_2u(sch_1):page458_i69@pure_quanta.q_cap_diffbus(chi~
ps)';

PART_NAME
 C715 'Q_CAP_DIFFBUS_C0201-DIFF BUS_0A':;

SECTION_NUMBER 1
 '@S9S_MB_2U_LIB.S9S_MB_2U(SCH_1):PAGE458_I76@PURE_QUANTA.Q_CAP_DIFFBUS(CHIPS)':
 C_PATH='@s9s_mb_2u_lib.s9s_mb_2u(sch_1):page458_i76@pure_quanta.q_cap_diffbus(chi~
ps)';

PART_NAME
 C714 'Q_CAP_DIFFBUS_C0201-DIFF BUS_0A':;

SECTION_NUMBER 1
 '@S9S_MB_2U_LIB.S9S_MB_2U(SCH_1):PAGE458_I78@PURE_QUANTA.Q_CAP_DIFFBUS(CHIPS)':
 C_PATH='@s9s_mb_2u_lib.s9s_mb_2u(sch_1):page458_i78@pure_quanta.q_cap_diffbus(chi~
ps)';

PART_NAME
 C713 'Q_CAP_DIFFBUS_C0201-DIFF BUS_0A':;

SECTION_NUMBER 1
 '@S9S_MB_2U_LIB.S9S_MB_2U(SCH_1):PAGE458_I77@PURE_QUANTA.Q_CAP_DIFFBUS(CHIPS)':
 C_PATH='@s9s_mb_2u_lib.s9s_mb_2u(sch_1):page458_i77@pure_quanta.q_cap_diffbus(chi~
ps)';

PART_NAME
 C712 'Q_CAP_DIFFBUS_C0201-DIFF BUS_0A':;

SECTION_NUMBER 1
 '@S9S_MB_2U_LIB.S9S_MB_2U(SCH_1):PAGE458_I81@PURE_QUANTA.Q_CAP_DIFFBUS(CHIPS)':
 C_PATH='@s9s_mb_2u_lib.s9s_mb_2u(sch_1):page458_i81@pure_quanta.q_cap_diffbus(chi~
ps)';

PART_NAME
 C711 'Q_CAP_DIFFBUS_C0201-DIFF BUS_0A':;

SECTION_NUMBER 1
 '@S9S_MB_2U_LIB.S9S_MB_2U(SCH_1):PAGE458_I79@PURE_QUANTA.Q_CAP_DIFFBUS(CHIPS)':
 C_PATH='@s9s_mb_2u_lib.s9s_mb_2u(sch_1):page458_i79@pure_quanta.q_cap_diffbus(chi~
ps)';

PART_NAME
 C710 'Q_CAP_DIFFBUS_C0201-DIFF BUS_0A':;

SECTION_NUMBER 1
 '@S9S_MB_2U_LIB.S9S_MB_2U(SCH_1):PAGE458_I80@PURE_QUANTA.Q_CAP_DIFFBUS(CHIPS)':
 C_PATH='@s9s_mb_2u_lib.s9s_mb_2u(sch_1):page458_i80@pure_quanta.q_cap_diffbus(chi~
ps)';

PART_NAME
 C709 'Q_CAP_DIFFBUS_C0201-DIFF BUS_0A':;

SECTION_NUMBER 1
 '@S9S_MB_2U_LIB.S9S_MB_2U(SCH_1):PAGE457_I126@PURE_QUANTA.Q_CAP_DIFFBUS(CHIPS)':
 C_PATH='@s9s_mb_2u_lib.s9s_mb_2u(sch_1):page457_i126@pure_quanta.q_cap_diffbus(ch~
ips)';

PART_NAME
 C708 'Q_CAP_DIFFBUS_C0201-DIFF BUS_0A':;

SECTION_NUMBER 1
 '@S9S_MB_2U_LIB.S9S_MB_2U(SCH_1):PAGE457_I125@PURE_QUANTA.Q_CAP_DIFFBUS(CHIPS)':
 C_PATH='@s9s_mb_2u_lib.s9s_mb_2u(sch_1):page457_i125@pure_quanta.q_cap_diffbus(ch~
ips)';

PART_NAME
 C707 'Q_CAP_DIFFBUS_C0201-DIFF BUS_0A':;

SECTION_NUMBER 1
 '@S9S_MB_2U_LIB.S9S_MB_2U(SCH_1):PAGE457_I128@PURE_QUANTA.Q_CAP_DIFFBUS(CHIPS)':
 C_PATH='@s9s_mb_2u_lib.s9s_mb_2u(sch_1):page457_i128@pure_quanta.q_cap_diffbus(ch~
ips)';

PART_NAME
 C706 'Q_CAP_DIFFBUS_C0201-DIFF BUS_0A':;

SECTION_NUMBER 1
 '@S9S_MB_2U_LIB.S9S_MB_2U(SCH_1):PAGE457_I127@PURE_QUANTA.Q_CAP_DIFFBUS(CHIPS)':
 C_PATH='@s9s_mb_2u_lib.s9s_mb_2u(sch_1):page457_i127@pure_quanta.q_cap_diffbus(ch~
ips)';

PART_NAME
 C705 'Q_CAP_DIFFBUS_C0201-DIFF BUS_0A':;

SECTION_NUMBER 1
 '@S9S_MB_2U_LIB.S9S_MB_2U(SCH_1):PAGE457_I130@PURE_QUANTA.Q_CAP_DIFFBUS(CHIPS)':
 C_PATH='@s9s_mb_2u_lib.s9s_mb_2u(sch_1):page457_i130@pure_quanta.q_cap_diffbus(ch~
ips)';

PART_NAME
 C704 'Q_CAP_DIFFBUS_C0201-DIFF BUS_0A':;

SECTION_NUMBER 1
 '@S9S_MB_2U_LIB.S9S_MB_2U(SCH_1):PAGE457_I129@PURE_QUANTA.Q_CAP_DIFFBUS(CHIPS)':
 C_PATH='@s9s_mb_2u_lib.s9s_mb_2u(sch_1):page457_i129@pure_quanta.q_cap_diffbus(ch~
ips)';

PART_NAME
 C703 'Q_CAP_DIFFBUS_C0201-DIFF BUS_0A':;

SECTION_NUMBER 1
 '@S9S_MB_2U_LIB.S9S_MB_2U(SCH_1):PAGE457_I133@PURE_QUANTA.Q_CAP_DIFFBUS(CHIPS)':
 C_PATH='@s9s_mb_2u_lib.s9s_mb_2u(sch_1):page457_i133@pure_quanta.q_cap_diffbus(ch~
ips)';

PART_NAME
 C702 'Q_CAP_DIFFBUS_C0201-DIFF BUS_0A':;

SECTION_NUMBER 1
 '@S9S_MB_2U_LIB.S9S_MB_2U(SCH_1):PAGE457_I132@PURE_QUANTA.Q_CAP_DIFFBUS(CHIPS)':
 C_PATH='@s9s_mb_2u_lib.s9s_mb_2u(sch_1):page457_i132@pure_quanta.q_cap_diffbus(ch~
ips)';

PART_NAME
 C701 'Q_CAP_DIFFBUS_C0201-DIFF BUS_0A':;

SECTION_NUMBER 1
 '@S9S_MB_2U_LIB.S9S_MB_2U(SCH_1):PAGE457_I131@PURE_QUANTA.Q_CAP_DIFFBUS(CHIPS)':
 C_PATH='@s9s_mb_2u_lib.s9s_mb_2u(sch_1):page457_i131@pure_quanta.q_cap_diffbus(ch~
ips)';

PART_NAME
 C700 'Q_CAP_DIFFBUS_C0201-DIFF BUS_0A':;

SECTION_NUMBER 1
 '@S9S_MB_2U_LIB.S9S_MB_2U(SCH_1):PAGE457_I134@PURE_QUANTA.Q_CAP_DIFFBUS(CHIPS)':
 C_PATH='@s9s_mb_2u_lib.s9s_mb_2u(sch_1):page457_i134@pure_quanta.q_cap_diffbus(ch~
ips)';

PART_NAME
 C699 'Q_CAP_DIFFBUS_C0201-DIFF BUS_0A':;

SECTION_NUMBER 1
 '@S9S_MB_2U_LIB.S9S_MB_2U(SCH_1):PAGE457_I136@PURE_QUANTA.Q_CAP_DIFFBUS(CHIPS)':
 C_PATH='@s9s_mb_2u_lib.s9s_mb_2u(sch_1):page457_i136@pure_quanta.q_cap_diffbus(ch~
ips)';

PART_NAME
 C698 'Q_CAP_DIFFBUS_C0201-DIFF BUS_0A':;

SECTION_NUMBER 1
 '@S9S_MB_2U_LIB.S9S_MB_2U(SCH_1):PAGE457_I135@PURE_QUANTA.Q_CAP_DIFFBUS(CHIPS)':
 C_PATH='@s9s_mb_2u_lib.s9s_mb_2u(sch_1):page457_i135@pure_quanta.q_cap_diffbus(ch~
ips)';

PART_NAME
 C697 'Q_CAP_DIFFBUS_C0201-DIFF BUS_0A':;

SECTION_NUMBER 1
 '@S9S_MB_2U_LIB.S9S_MB_2U(SCH_1):PAGE457_I138@PURE_QUANTA.Q_CAP_DIFFBUS(CHIPS)':
 C_PATH='@s9s_mb_2u_lib.s9s_mb_2u(sch_1):page457_i138@pure_quanta.q_cap_diffbus(ch~
ips)';

PART_NAME
 C696 'Q_CAP_DIFFBUS_C0201-DIFF BUS_0A':;

SECTION_NUMBER 1
 '@S9S_MB_2U_LIB.S9S_MB_2U(SCH_1):PAGE457_I137@PURE_QUANTA.Q_CAP_DIFFBUS(CHIPS)':
 C_PATH='@s9s_mb_2u_lib.s9s_mb_2u(sch_1):page457_i137@pure_quanta.q_cap_diffbus(ch~
ips)';

PART_NAME
 C695 'Q_CAP_DIFFBUS_C0201-DIFF BUS_0A':;

SECTION_NUMBER 1
 '@S9S_MB_2U_LIB.S9S_MB_2U(SCH_1):PAGE457_I139@PURE_QUANTA.Q_CAP_DIFFBUS(CHIPS)':
 C_PATH='@s9s_mb_2u_lib.s9s_mb_2u(sch_1):page457_i139@pure_quanta.q_cap_diffbus(ch~
ips)';

PART_NAME
 C694 'Q_CAP_DIFFBUS_C0201-DIFF BUS_0A':;

SECTION_NUMBER 1
 '@S9S_MB_2U_LIB.S9S_MB_2U(SCH_1):PAGE457_I140@PURE_QUANTA.Q_CAP_DIFFBUS(CHIPS)':
 C_PATH='@s9s_mb_2u_lib.s9s_mb_2u(sch_1):page457_i140@pure_quanta.q_cap_diffbus(ch~
ips)';

PART_NAME
 C693 'Q_CAP_DIFFBUS_C0201-DIFF BUS_0A':;

SECTION_NUMBER 1
 '@S9S_MB_2U_LIB.S9S_MB_2U(SCH_1):PAGE457_I157@PURE_QUANTA.Q_CAP_DIFFBUS(CHIPS)':
 C_PATH='@s9s_mb_2u_lib.s9s_mb_2u(sch_1):page457_i157@pure_quanta.q_cap_diffbus(ch~
ips)';

PART_NAME
 C692 'Q_CAP_DIFFBUS_C0201-DIFF BUS_0A':;

SECTION_NUMBER 1
 '@S9S_MB_2U_LIB.S9S_MB_2U(SCH_1):PAGE457_I158@PURE_QUANTA.Q_CAP_DIFFBUS(CHIPS)':
 C_PATH='@s9s_mb_2u_lib.s9s_mb_2u(sch_1):page457_i158@pure_quanta.q_cap_diffbus(ch~
ips)';

PART_NAME
 C691 'Q_CAP_DIFFBUS_C0201-DIFF BUS_0A':;

SECTION_NUMBER 1
 '@S9S_MB_2U_LIB.S9S_MB_2U(SCH_1):PAGE457_I160@PURE_QUANTA.Q_CAP_DIFFBUS(CHIPS)':
 C_PATH='@s9s_mb_2u_lib.s9s_mb_2u(sch_1):page457_i160@pure_quanta.q_cap_diffbus(ch~
ips)';

PART_NAME
 C690 'Q_CAP_DIFFBUS_C0201-DIFF BUS_0A':;

SECTION_NUMBER 1
 '@S9S_MB_2U_LIB.S9S_MB_2U(SCH_1):PAGE457_I159@PURE_QUANTA.Q_CAP_DIFFBUS(CHIPS)':
 C_PATH='@s9s_mb_2u_lib.s9s_mb_2u(sch_1):page457_i159@pure_quanta.q_cap_diffbus(ch~
ips)';

PART_NAME
 C689 'Q_CAP_DIFFBUS_C0201-DIFF BUS_0A':;

SECTION_NUMBER 1
 '@S9S_MB_2U_LIB.S9S_MB_2U(SCH_1):PAGE457_I163@PURE_QUANTA.Q_CAP_DIFFBUS(CHIPS)':
 C_PATH='@s9s_mb_2u_lib.s9s_mb_2u(sch_1):page457_i163@pure_quanta.q_cap_diffbus(ch~
ips)';

PART_NAME
 C688 'Q_CAP_DIFFBUS_C0201-DIFF BUS_0A':;

SECTION_NUMBER 1
 '@S9S_MB_2U_LIB.S9S_MB_2U(SCH_1):PAGE457_I162@PURE_QUANTA.Q_CAP_DIFFBUS(CHIPS)':
 C_PATH='@s9s_mb_2u_lib.s9s_mb_2u(sch_1):page457_i162@pure_quanta.q_cap_diffbus(ch~
ips)';

PART_NAME
 C687 'Q_CAP_DIFFBUS_C0201-DIFF BUS_0A':;

SECTION_NUMBER 1
 '@S9S_MB_2U_LIB.S9S_MB_2U(SCH_1):PAGE457_I161@PURE_QUANTA.Q_CAP_DIFFBUS(CHIPS)':
 C_PATH='@s9s_mb_2u_lib.s9s_mb_2u(sch_1):page457_i161@pure_quanta.q_cap_diffbus(ch~
ips)';

PART_NAME
 C686 'Q_CAP_DIFFBUS_C0201-DIFF BUS_0A':;

SECTION_NUMBER 1
 '@S9S_MB_2U_LIB.S9S_MB_2U(SCH_1):PAGE457_I164@PURE_QUANTA.Q_CAP_DIFFBUS(CHIPS)':
 C_PATH='@s9s_mb_2u_lib.s9s_mb_2u(sch_1):page457_i164@pure_quanta.q_cap_diffbus(ch~
ips)';

PART_NAME
 C685 'Q_CAP_DIFFBUS_C0201-DIFF BUS_0A':;

SECTION_NUMBER 1
 '@S9S_MB_2U_LIB.S9S_MB_2U(SCH_1):PAGE457_I165@PURE_QUANTA.Q_CAP_DIFFBUS(CHIPS)':
 C_PATH='@s9s_mb_2u_lib.s9s_mb_2u(sch_1):page457_i165@pure_quanta.q_cap_diffbus(ch~
ips)';

PART_NAME
 C684 'Q_CAP_DIFFBUS_C0201-DIFF BUS_0A':;

SECTION_NUMBER 1
 '@S9S_MB_2U_LIB.S9S_MB_2U(SCH_1):PAGE457_I166@PURE_QUANTA.Q_CAP_DIFFBUS(CHIPS)':
 C_PATH='@s9s_mb_2u_lib.s9s_mb_2u(sch_1):page457_i166@pure_quanta.q_cap_diffbus(ch~
ips)';

PART_NAME
 C683 'Q_CAP_DIFFBUS_C0201-DIFF BUS_0A':;

SECTION_NUMBER 1
 '@S9S_MB_2U_LIB.S9S_MB_2U(SCH_1):PAGE457_I168@PURE_QUANTA.Q_CAP_DIFFBUS(CHIPS)':
 C_PATH='@s9s_mb_2u_lib.s9s_mb_2u(sch_1):page457_i168@pure_quanta.q_cap_diffbus(ch~
ips)';

PART_NAME
 C682 'Q_CAP_DIFFBUS_C0201-DIFF BUS_0A':;

SECTION_NUMBER 1
 '@S9S_MB_2U_LIB.S9S_MB_2U(SCH_1):PAGE457_I167@PURE_QUANTA.Q_CAP_DIFFBUS(CHIPS)':
 C_PATH='@s9s_mb_2u_lib.s9s_mb_2u(sch_1):page457_i167@pure_quanta.q_cap_diffbus(ch~
ips)';

PART_NAME
 C681 'Q_CAP_DIFFBUS_C0201-DIFF BUS_0A':;

SECTION_NUMBER 1
 '@S9S_MB_2U_LIB.S9S_MB_2U(SCH_1):PAGE457_I171@PURE_QUANTA.Q_CAP_DIFFBUS(CHIPS)':
 C_PATH='@s9s_mb_2u_lib.s9s_mb_2u(sch_1):page457_i171@pure_quanta.q_cap_diffbus(ch~
ips)';

PART_NAME
 C680 'Q_CAP_DIFFBUS_C0201-DIFF BUS_0A':;

SECTION_NUMBER 1
 '@S9S_MB_2U_LIB.S9S_MB_2U(SCH_1):PAGE457_I170@PURE_QUANTA.Q_CAP_DIFFBUS(CHIPS)':
 C_PATH='@s9s_mb_2u_lib.s9s_mb_2u(sch_1):page457_i170@pure_quanta.q_cap_diffbus(ch~
ips)';

PART_NAME
 C679 'Q_CAP_DIFFBUS_C0201-DIFF BUS_0A':;

SECTION_NUMBER 1
 '@S9S_MB_2U_LIB.S9S_MB_2U(SCH_1):PAGE457_I169@PURE_QUANTA.Q_CAP_DIFFBUS(CHIPS)':
 C_PATH='@s9s_mb_2u_lib.s9s_mb_2u(sch_1):page457_i169@pure_quanta.q_cap_diffbus(ch~
ips)';

PART_NAME
 C678 'Q_CAP_DIFFBUS_C0201-DIFF BUS_0A':;

SECTION_NUMBER 1
 '@S9S_MB_2U_LIB.S9S_MB_2U(SCH_1):PAGE457_I172@PURE_QUANTA.Q_CAP_DIFFBUS(CHIPS)':
 C_PATH='@s9s_mb_2u_lib.s9s_mb_2u(sch_1):page457_i172@pure_quanta.q_cap_diffbus(ch~
ips)';

PART_NAME
 C677 'Q_CAP_DIFFBUS_C0201-DIFF BUS_0A':;

SECTION_NUMBER 1
 '@S9S_MB_2U_LIB.S9S_MB_2U(SCH_1):PAGE457_I21@PURE_QUANTA.Q_CAP_DIFFBUS(CHIPS)':
 C_PATH='@s9s_mb_2u_lib.s9s_mb_2u(sch_1):page457_i21@pure_quanta.q_cap_diffbus(chi~
ps)';

PART_NAME
 C676 'Q_CAP_DIFFBUS_C0201-DIFF BUS_0A':;

SECTION_NUMBER 1
 '@S9S_MB_2U_LIB.S9S_MB_2U(SCH_1):PAGE457_I22@PURE_QUANTA.Q_CAP_DIFFBUS(CHIPS)':
 C_PATH='@s9s_mb_2u_lib.s9s_mb_2u(sch_1):page457_i22@pure_quanta.q_cap_diffbus(chi~
ps)';

PART_NAME
 C675 'Q_CAP_DIFFBUS_C0201-DIFF BUS_0A':;

SECTION_NUMBER 1
 '@S9S_MB_2U_LIB.S9S_MB_2U(SCH_1):PAGE457_I23@PURE_QUANTA.Q_CAP_DIFFBUS(CHIPS)':
 C_PATH='@s9s_mb_2u_lib.s9s_mb_2u(sch_1):page457_i23@pure_quanta.q_cap_diffbus(chi~
ps)';

PART_NAME
 C674 'Q_CAP_DIFFBUS_C0201-DIFF BUS_0A':;

SECTION_NUMBER 1
 '@S9S_MB_2U_LIB.S9S_MB_2U(SCH_1):PAGE457_I24@PURE_QUANTA.Q_CAP_DIFFBUS(CHIPS)':
 C_PATH='@s9s_mb_2u_lib.s9s_mb_2u(sch_1):page457_i24@pure_quanta.q_cap_diffbus(chi~
ps)';

PART_NAME
 C673 'Q_CAP_DIFFBUS_C0201-DIFF BUS_0A':;

SECTION_NUMBER 1
 '@S9S_MB_2U_LIB.S9S_MB_2U(SCH_1):PAGE457_I25@PURE_QUANTA.Q_CAP_DIFFBUS(CHIPS)':
 C_PATH='@s9s_mb_2u_lib.s9s_mb_2u(sch_1):page457_i25@pure_quanta.q_cap_diffbus(chi~
ps)';

PART_NAME
 C672 'Q_CAP_DIFFBUS_C0201-DIFF BUS_0A':;

SECTION_NUMBER 1
 '@S9S_MB_2U_LIB.S9S_MB_2U(SCH_1):PAGE457_I26@PURE_QUANTA.Q_CAP_DIFFBUS(CHIPS)':
 C_PATH='@s9s_mb_2u_lib.s9s_mb_2u(sch_1):page457_i26@pure_quanta.q_cap_diffbus(chi~
ps)';

PART_NAME
 C671 'Q_CAP_DIFFBUS_C0201-DIFF BUS_0A':;

SECTION_NUMBER 1
 '@S9S_MB_2U_LIB.S9S_MB_2U(SCH_1):PAGE457_I27@PURE_QUANTA.Q_CAP_DIFFBUS(CHIPS)':
 C_PATH='@s9s_mb_2u_lib.s9s_mb_2u(sch_1):page457_i27@pure_quanta.q_cap_diffbus(chi~
ps)';

PART_NAME
 C670 'Q_CAP_DIFFBUS_C0201-DIFF BUS_0A':;

SECTION_NUMBER 1
 '@S9S_MB_2U_LIB.S9S_MB_2U(SCH_1):PAGE457_I28@PURE_QUANTA.Q_CAP_DIFFBUS(CHIPS)':
 C_PATH='@s9s_mb_2u_lib.s9s_mb_2u(sch_1):page457_i28@pure_quanta.q_cap_diffbus(chi~
ps)';

PART_NAME
 C669 'Q_CAP_DIFFBUS_C0201-DIFF BUS_0A':;

SECTION_NUMBER 1
 '@S9S_MB_2U_LIB.S9S_MB_2U(SCH_1):PAGE457_I29@PURE_QUANTA.Q_CAP_DIFFBUS(CHIPS)':
 C_PATH='@s9s_mb_2u_lib.s9s_mb_2u(sch_1):page457_i29@pure_quanta.q_cap_diffbus(chi~
ps)';

PART_NAME
 C668 'Q_CAP_DIFFBUS_C0201-DIFF BUS_0A':;

SECTION_NUMBER 1
 '@S9S_MB_2U_LIB.S9S_MB_2U(SCH_1):PAGE457_I39@PURE_QUANTA.Q_CAP_DIFFBUS(CHIPS)':
 C_PATH='@s9s_mb_2u_lib.s9s_mb_2u(sch_1):page457_i39@pure_quanta.q_cap_diffbus(chi~
ps)';

PART_NAME
 C667 'Q_CAP_DIFFBUS_C0201-DIFF BUS_0A':;

SECTION_NUMBER 1
 '@S9S_MB_2U_LIB.S9S_MB_2U(SCH_1):PAGE457_I41@PURE_QUANTA.Q_CAP_DIFFBUS(CHIPS)':
 C_PATH='@s9s_mb_2u_lib.s9s_mb_2u(sch_1):page457_i41@pure_quanta.q_cap_diffbus(chi~
ps)';

PART_NAME
 C666 'Q_CAP_DIFFBUS_C0201-DIFF BUS_0A':;

SECTION_NUMBER 1
 '@S9S_MB_2U_LIB.S9S_MB_2U(SCH_1):PAGE457_I40@PURE_QUANTA.Q_CAP_DIFFBUS(CHIPS)':
 C_PATH='@s9s_mb_2u_lib.s9s_mb_2u(sch_1):page457_i40@pure_quanta.q_cap_diffbus(chi~
ps)';

PART_NAME
 C665 'Q_CAP_DIFFBUS_C0201-DIFF BUS_0A':;

SECTION_NUMBER 1
 '@S9S_MB_2U_LIB.S9S_MB_2U(SCH_1):PAGE457_I42@PURE_QUANTA.Q_CAP_DIFFBUS(CHIPS)':
 C_PATH='@s9s_mb_2u_lib.s9s_mb_2u(sch_1):page457_i42@pure_quanta.q_cap_diffbus(chi~
ps)';

PART_NAME
 C664 'Q_CAP_DIFFBUS_C0201-DIFF BUS_0A':;

SECTION_NUMBER 1
 '@S9S_MB_2U_LIB.S9S_MB_2U(SCH_1):PAGE457_I43@PURE_QUANTA.Q_CAP_DIFFBUS(CHIPS)':
 C_PATH='@s9s_mb_2u_lib.s9s_mb_2u(sch_1):page457_i43@pure_quanta.q_cap_diffbus(chi~
ps)';

PART_NAME
 C663 'Q_CAP_DIFFBUS_C0201-DIFF BUS_0A':;

SECTION_NUMBER 1
 '@S9S_MB_2U_LIB.S9S_MB_2U(SCH_1):PAGE457_I44@PURE_QUANTA.Q_CAP_DIFFBUS(CHIPS)':
 C_PATH='@s9s_mb_2u_lib.s9s_mb_2u(sch_1):page457_i44@pure_quanta.q_cap_diffbus(chi~
ps)';

PART_NAME
 C662 'Q_CAP_DIFFBUS_C0201-DIFF BUS_0A':;

SECTION_NUMBER 1
 '@S9S_MB_2U_LIB.S9S_MB_2U(SCH_1):PAGE457_I45@PURE_QUANTA.Q_CAP_DIFFBUS(CHIPS)':
 C_PATH='@s9s_mb_2u_lib.s9s_mb_2u(sch_1):page457_i45@pure_quanta.q_cap_diffbus(chi~
ps)';

PART_NAME
 C661 'Q_CAP_DIFFBUS_C0201-DIFF BUS_0A':;

SECTION_NUMBER 1
 '@S9S_MB_2U_LIB.S9S_MB_2U(SCH_1):PAGE457_I69@PURE_QUANTA.Q_CAP_DIFFBUS(CHIPS)':
 C_PATH='@s9s_mb_2u_lib.s9s_mb_2u(sch_1):page457_i69@pure_quanta.q_cap_diffbus(chi~
ps)';

PART_NAME
 C660 'Q_CAP_DIFFBUS_C0201-DIFF BUS_0A':;

SECTION_NUMBER 1
 '@S9S_MB_2U_LIB.S9S_MB_2U(SCH_1):PAGE457_I70@PURE_QUANTA.Q_CAP_DIFFBUS(CHIPS)':
 C_PATH='@s9s_mb_2u_lib.s9s_mb_2u(sch_1):page457_i70@pure_quanta.q_cap_diffbus(chi~
ps)';

PART_NAME
 C659 'Q_CAP_DIFFBUS_C0201-DIFF BUS_0A':;

SECTION_NUMBER 1
 '@S9S_MB_2U_LIB.S9S_MB_2U(SCH_1):PAGE457_I71@PURE_QUANTA.Q_CAP_DIFFBUS(CHIPS)':
 C_PATH='@s9s_mb_2u_lib.s9s_mb_2u(sch_1):page457_i71@pure_quanta.q_cap_diffbus(chi~
ps)';

PART_NAME
 C658 'Q_CAP_DIFFBUS_C0201-DIFF BUS_0A':;

SECTION_NUMBER 1
 '@S9S_MB_2U_LIB.S9S_MB_2U(SCH_1):PAGE457_I72@PURE_QUANTA.Q_CAP_DIFFBUS(CHIPS)':
 C_PATH='@s9s_mb_2u_lib.s9s_mb_2u(sch_1):page457_i72@pure_quanta.q_cap_diffbus(chi~
ps)';

PART_NAME
 C657 'Q_CAP_DIFFBUS_C0201-DIFF BUS_0A':;

SECTION_NUMBER 1
 '@S9S_MB_2U_LIB.S9S_MB_2U(SCH_1):PAGE457_I73@PURE_QUANTA.Q_CAP_DIFFBUS(CHIPS)':
 C_PATH='@s9s_mb_2u_lib.s9s_mb_2u(sch_1):page457_i73@pure_quanta.q_cap_diffbus(chi~
ps)';

PART_NAME
 C656 'Q_CAP_DIFFBUS_C0201-DIFF BUS_0A':;

SECTION_NUMBER 1
 '@S9S_MB_2U_LIB.S9S_MB_2U(SCH_1):PAGE457_I74@PURE_QUANTA.Q_CAP_DIFFBUS(CHIPS)':
 C_PATH='@s9s_mb_2u_lib.s9s_mb_2u(sch_1):page457_i74@pure_quanta.q_cap_diffbus(chi~
ps)';

PART_NAME
 C655 'Q_CAP_DIFFBUS_C0201-DIFF BUS_0A':;

SECTION_NUMBER 1
 '@S9S_MB_2U_LIB.S9S_MB_2U(SCH_1):PAGE457_I75@PURE_QUANTA.Q_CAP_DIFFBUS(CHIPS)':
 C_PATH='@s9s_mb_2u_lib.s9s_mb_2u(sch_1):page457_i75@pure_quanta.q_cap_diffbus(chi~
ps)';

PART_NAME
 C654 'Q_CAP_DIFFBUS_C0201-DIFF BUS_0A':;

SECTION_NUMBER 1
 '@S9S_MB_2U_LIB.S9S_MB_2U(SCH_1):PAGE457_I76@PURE_QUANTA.Q_CAP_DIFFBUS(CHIPS)':
 C_PATH='@s9s_mb_2u_lib.s9s_mb_2u(sch_1):page457_i76@pure_quanta.q_cap_diffbus(chi~
ps)';

PART_NAME
 C653 'Q_CAP_DIFFBUS_C0201-DIFF BUS_0A':;

SECTION_NUMBER 1
 '@S9S_MB_2U_LIB.S9S_MB_2U(SCH_1):PAGE457_I78@PURE_QUANTA.Q_CAP_DIFFBUS(CHIPS)':
 C_PATH='@s9s_mb_2u_lib.s9s_mb_2u(sch_1):page457_i78@pure_quanta.q_cap_diffbus(chi~
ps)';

PART_NAME
 C652 'Q_CAP_DIFFBUS_C0201-DIFF BUS_0A':;

SECTION_NUMBER 1
 '@S9S_MB_2U_LIB.S9S_MB_2U(SCH_1):PAGE457_I77@PURE_QUANTA.Q_CAP_DIFFBUS(CHIPS)':
 C_PATH='@s9s_mb_2u_lib.s9s_mb_2u(sch_1):page457_i77@pure_quanta.q_cap_diffbus(chi~
ps)';

PART_NAME
 C651 'Q_CAP_DIFFBUS_C0201-DIFF BUS_0A':;

SECTION_NUMBER 1
 '@S9S_MB_2U_LIB.S9S_MB_2U(SCH_1):PAGE457_I89@PURE_QUANTA.Q_CAP_DIFFBUS(CHIPS)':
 C_PATH='@s9s_mb_2u_lib.s9s_mb_2u(sch_1):page457_i89@pure_quanta.q_cap_diffbus(chi~
ps)';

PART_NAME
 C650 'Q_CAP_DIFFBUS_C0201-DIFF BUS_0A':;

SECTION_NUMBER 1
 '@S9S_MB_2U_LIB.S9S_MB_2U(SCH_1):PAGE457_I90@PURE_QUANTA.Q_CAP_DIFFBUS(CHIPS)':
 C_PATH='@s9s_mb_2u_lib.s9s_mb_2u(sch_1):page457_i90@pure_quanta.q_cap_diffbus(chi~
ps)';

PART_NAME
 C649 'Q_CAP_DIFFBUS_C0201-DIFF BUS_0A':;

SECTION_NUMBER 1
 '@S9S_MB_2U_LIB.S9S_MB_2U(SCH_1):PAGE457_I91@PURE_QUANTA.Q_CAP_DIFFBUS(CHIPS)':
 C_PATH='@s9s_mb_2u_lib.s9s_mb_2u(sch_1):page457_i91@pure_quanta.q_cap_diffbus(chi~
ps)';

PART_NAME
 C648 'Q_CAP_DIFFBUS_C0201-DIFF BUS_0A':;

SECTION_NUMBER 1
 '@S9S_MB_2U_LIB.S9S_MB_2U(SCH_1):PAGE457_I92@PURE_QUANTA.Q_CAP_DIFFBUS(CHIPS)':
 C_PATH='@s9s_mb_2u_lib.s9s_mb_2u(sch_1):page457_i92@pure_quanta.q_cap_diffbus(chi~
ps)';

PART_NAME
 C647 'Q_CAP_DIFFBUS_C0201-DIFF BUS_0A':;

SECTION_NUMBER 1
 '@S9S_MB_2U_LIB.S9S_MB_2U(SCH_1):PAGE457_I93@PURE_QUANTA.Q_CAP_DIFFBUS(CHIPS)':
 C_PATH='@s9s_mb_2u_lib.s9s_mb_2u(sch_1):page457_i93@pure_quanta.q_cap_diffbus(chi~
ps)';

PART_NAME
 C646 'Q_CAP_DIFFBUS_C0201-DIFF BUS_0A':;

SECTION_NUMBER 1
 '@S9S_MB_2U_LIB.S9S_MB_2U(SCH_1):PAGE457_I94@PURE_QUANTA.Q_CAP_DIFFBUS(CHIPS)':
 C_PATH='@s9s_mb_2u_lib.s9s_mb_2u(sch_1):page457_i94@pure_quanta.q_cap_diffbus(chi~
ps)';

PART_NAME
 R495 'Q_RES_0402LF-100,1%,1/16W,CHIPA':;

SECTION_NUMBER 1
 '@S9S_MB_2U_LIB.S9S_MB_2U(SCH_1):PAGE517_I118@PURE_QUANTA.Q_RES(CHIPS)':
 C_PATH='@s9s_mb_2u_lib.s9s_mb_2u(sch_1):page517_i118@pure_quanta.q_res(chips)';

PART_NAME
 C1105 'Q_CAP_DIFFBUS_C0201-DIFF BUS_0A':;

SECTION_NUMBER 1
 '@S9S_MB_2U_LIB.S9S_MB_2U(SCH_1):PAGE517_I169@PURE_QUANTA.Q_CAP_DIFFBUS(CHIPS)':
 C_PATH='@s9s_mb_2u_lib.s9s_mb_2u(sch_1):page517_i169@pure_quanta.q_cap_diffbus(ch~
ips)';

PART_NAME
 C1104 'Q_CAP_DIFFBUS_C0201-DIFF BUS_0A':;

SECTION_NUMBER 1
 '@S9S_MB_2U_LIB.S9S_MB_2U(SCH_1):PAGE517_I167@PURE_QUANTA.Q_CAP_DIFFBUS(CHIPS)':
 C_PATH='@s9s_mb_2u_lib.s9s_mb_2u(sch_1):page517_i167@pure_quanta.q_cap_diffbus(ch~
ips)';

PART_NAME
 C1103 'Q_CAP_DIFFBUS_C0201-DIFF BUS_0A':;

SECTION_NUMBER 1
 '@S9S_MB_2U_LIB.S9S_MB_2U(SCH_1):PAGE517_I166@PURE_QUANTA.Q_CAP_DIFFBUS(CHIPS)':
 C_PATH='@s9s_mb_2u_lib.s9s_mb_2u(sch_1):page517_i166@pure_quanta.q_cap_diffbus(ch~
ips)';

PART_NAME
 C1102 'Q_CAP_DIFFBUS_C0201-DIFF BUS_0A':;

SECTION_NUMBER 1
 '@S9S_MB_2U_LIB.S9S_MB_2U(SCH_1):PAGE517_I168@PURE_QUANTA.Q_CAP_DIFFBUS(CHIPS)':
 C_PATH='@s9s_mb_2u_lib.s9s_mb_2u(sch_1):page517_i168@pure_quanta.q_cap_diffbus(ch~
ips)';

PART_NAME
 C1101 'Q_CAP_DIFFBUS_C0201-DIFF BUS_0A':;

SECTION_NUMBER 1
 '@S9S_MB_2U_LIB.S9S_MB_2U(SCH_1):PAGE517_I164@PURE_QUANTA.Q_CAP_DIFFBUS(CHIPS)':
 C_PATH='@s9s_mb_2u_lib.s9s_mb_2u(sch_1):page517_i164@pure_quanta.q_cap_diffbus(ch~
ips)';

PART_NAME
 C1100 'Q_CAP_DIFFBUS_C0201-DIFF BUS_0A':;

SECTION_NUMBER 1
 '@S9S_MB_2U_LIB.S9S_MB_2U(SCH_1):PAGE517_I165@PURE_QUANTA.Q_CAP_DIFFBUS(CHIPS)':
 C_PATH='@s9s_mb_2u_lib.s9s_mb_2u(sch_1):page517_i165@pure_quanta.q_cap_diffbus(ch~
ips)';

PART_NAME
 C1099 'Q_CAP_DIFFBUS_C0201-DIFF BUS_0A':;

SECTION_NUMBER 1
 '@S9S_MB_2U_LIB.S9S_MB_2U(SCH_1):PAGE517_I163@PURE_QUANTA.Q_CAP_DIFFBUS(CHIPS)':
 C_PATH='@s9s_mb_2u_lib.s9s_mb_2u(sch_1):page517_i163@pure_quanta.q_cap_diffbus(ch~
ips)';

PART_NAME
 C1098 'Q_CAP_DIFFBUS_C0201-DIFF BUS_0A':;

SECTION_NUMBER 1
 '@S9S_MB_2U_LIB.S9S_MB_2U(SCH_1):PAGE517_I162@PURE_QUANTA.Q_CAP_DIFFBUS(CHIPS)':
 C_PATH='@s9s_mb_2u_lib.s9s_mb_2u(sch_1):page517_i162@pure_quanta.q_cap_diffbus(ch~
ips)';

PART_NAME
 C1097 'Q_CAP_DIFFBUS_C0201-DIFF BUS_0A':;

SECTION_NUMBER 1
 '@S9S_MB_2U_LIB.S9S_MB_2U(SCH_1):PAGE517_I161@PURE_QUANTA.Q_CAP_DIFFBUS(CHIPS)':
 C_PATH='@s9s_mb_2u_lib.s9s_mb_2u(sch_1):page517_i161@pure_quanta.q_cap_diffbus(ch~
ips)';

PART_NAME
 C1096 'Q_CAP_DIFFBUS_C0201-DIFF BUS_0A':;

SECTION_NUMBER 1
 '@S9S_MB_2U_LIB.S9S_MB_2U(SCH_1):PAGE517_I159@PURE_QUANTA.Q_CAP_DIFFBUS(CHIPS)':
 C_PATH='@s9s_mb_2u_lib.s9s_mb_2u(sch_1):page517_i159@pure_quanta.q_cap_diffbus(ch~
ips)';

PART_NAME
 C1095 'Q_CAP_DIFFBUS_C0201-DIFF BUS_0A':;

SECTION_NUMBER 1
 '@S9S_MB_2U_LIB.S9S_MB_2U(SCH_1):PAGE517_I160@PURE_QUANTA.Q_CAP_DIFFBUS(CHIPS)':
 C_PATH='@s9s_mb_2u_lib.s9s_mb_2u(sch_1):page517_i160@pure_quanta.q_cap_diffbus(ch~
ips)';

PART_NAME
 C1094 'Q_CAP_DIFFBUS_C0201-DIFF BUS_0A':;

SECTION_NUMBER 1
 '@S9S_MB_2U_LIB.S9S_MB_2U(SCH_1):PAGE517_I158@PURE_QUANTA.Q_CAP_DIFFBUS(CHIPS)':
 C_PATH='@s9s_mb_2u_lib.s9s_mb_2u(sch_1):page517_i158@pure_quanta.q_cap_diffbus(ch~
ips)';

PART_NAME
 C1093 'Q_CAP_DIFFBUS_C0201-DIFF BUS_0A':;

SECTION_NUMBER 1
 '@S9S_MB_2U_LIB.S9S_MB_2U(SCH_1):PAGE517_I156@PURE_QUANTA.Q_CAP_DIFFBUS(CHIPS)':
 C_PATH='@s9s_mb_2u_lib.s9s_mb_2u(sch_1):page517_i156@pure_quanta.q_cap_diffbus(ch~
ips)';

PART_NAME
 C1092 'Q_CAP_DIFFBUS_C0201-DIFF BUS_0A':;

SECTION_NUMBER 1
 '@S9S_MB_2U_LIB.S9S_MB_2U(SCH_1):PAGE517_I157@PURE_QUANTA.Q_CAP_DIFFBUS(CHIPS)':
 C_PATH='@s9s_mb_2u_lib.s9s_mb_2u(sch_1):page517_i157@pure_quanta.q_cap_diffbus(ch~
ips)';

PART_NAME
 C1091 'Q_CAP_DIFFBUS_C0201-DIFF BUS_0A':;

SECTION_NUMBER 1
 '@S9S_MB_2U_LIB.S9S_MB_2U(SCH_1):PAGE517_I154@PURE_QUANTA.Q_CAP_DIFFBUS(CHIPS)':
 C_PATH='@s9s_mb_2u_lib.s9s_mb_2u(sch_1):page517_i154@pure_quanta.q_cap_diffbus(ch~
ips)';

PART_NAME
 C1090 'Q_CAP_DIFFBUS_C0201-DIFF BUS_0A':;

SECTION_NUMBER 1
 '@S9S_MB_2U_LIB.S9S_MB_2U(SCH_1):PAGE517_I155@PURE_QUANTA.Q_CAP_DIFFBUS(CHIPS)':
 C_PATH='@s9s_mb_2u_lib.s9s_mb_2u(sch_1):page517_i155@pure_quanta.q_cap_diffbus(ch~
ips)';

PART_NAME
 C644 'Q_CAP_DIFFBUS_C0402-DIFF BUS_0A':;

SECTION_NUMBER 1
 '@S9S_MB_2U_LIB.S9S_MB_2U(SCH_1):PAGE517_I194@PURE_QUANTA.Q_CAP_DIFFBUS(CHIPS)':
 C_PATH='@s9s_mb_2u_lib.s9s_mb_2u(sch_1):page517_i194@pure_quanta.q_cap_diffbus(ch~
ips)';

PART_NAME
 C643 'Q_CAP_DIFFBUS_C0402-DIFF BUS_0A':;

SECTION_NUMBER 1
 '@S9S_MB_2U_LIB.S9S_MB_2U(SCH_1):PAGE517_I195@PURE_QUANTA.Q_CAP_DIFFBUS(CHIPS)':
 C_PATH='@s9s_mb_2u_lib.s9s_mb_2u(sch_1):page517_i195@pure_quanta.q_cap_diffbus(ch~
ips)';

PART_NAME
 U77 '74CBTLV3126PW-74CBTLV3126PW,SMB':;

SECTION_NUMBER 1
 '@S9S_MB_2U_LIB.S9S_MB_2U(SCH_1):PAGE501_I105@PURE_QUANTA.74CBTLV3126PW(CHIPS)':
 C_PATH='@s9s_mb_2u_lib.s9s_mb_2u(sch_1):page501_i105@pure_quanta.\74cbtlv3126pw\(~
chips)';

PART_NAME
 U68 '74CBTLV3126PW-74CBTLV3126PW,SMA':;

SECTION_NUMBER 1
 '@S9S_MB_2U_LIB.S9S_MB_2U(SCH_1):PAGE501_I2@PURE_QUANTA.74CBTLV3126PW(CHIPS)':
 C_PATH='@s9s_mb_2u_lib.s9s_mb_2u(sch_1):page501_i2@pure_quanta.\74cbtlv3126pw\(ch~
ips)';

PART_NAME
 U67 '74CBTLV3126PW-74CBTLV3126PW,SMA':;

SECTION_NUMBER 1
 '@S9S_MB_2U_LIB.S9S_MB_2U(SCH_1):PAGE501_I1@PURE_QUANTA.74CBTLV3126PW(CHIPS)':
 C_PATH='@s9s_mb_2u_lib.s9s_mb_2u(sch_1):page501_i1@pure_quanta.\74cbtlv3126pw\(ch~
ips)';

PART_NAME
 U66 '74HC1G126GW-74HC1G126GW,SMLF,IA':;

SECTION_NUMBER 1
 '@S9S_MB_2U_LIB.S9S_MB_2U(SCH_1):PAGE501_I53@PURE_QUANTA.74HC1G126GW(CHIPS)':
 C_PATH='@s9s_mb_2u_lib.s9s_mb_2u(sch_1):page501_i53@pure_quanta.\74hc1g126gw\(chi~
ps)';

PART_NAME
 R1898 'Q_RES_0402LF-100,1%,1/16W,CHIPA':;

SECTION_NUMBER 1
 '@S9S_MB_2U_LIB.S9S_MB_2U(SCH_1):PAGE501_I122@PURE_QUANTA.Q_RES(CHIPS)':
 C_PATH='@s9s_mb_2u_lib.s9s_mb_2u(sch_1):page501_i122@pure_quanta.q_res(chips)';

PART_NAME
 R1897 'Q_RES_0402LF-100,1%,1/16W,CHIPA':;

SECTION_NUMBER 1
 '@S9S_MB_2U_LIB.S9S_MB_2U(SCH_1):PAGE501_I124@PURE_QUANTA.Q_RES(CHIPS)':
 C_PATH='@s9s_mb_2u_lib.s9s_mb_2u(sch_1):page501_i124@pure_quanta.q_res(chips)';

PART_NAME
 R1896 'Q_RES_0402LF-100,1%,1/16W,CHIPA':;

SECTION_NUMBER 1
 '@S9S_MB_2U_LIB.S9S_MB_2U(SCH_1):PAGE501_I123@PURE_QUANTA.Q_RES(CHIPS)':
 C_PATH='@s9s_mb_2u_lib.s9s_mb_2u(sch_1):page501_i123@pure_quanta.q_res(chips)';

PART_NAME
 R1719 'Q_RES_0402LF-33.2,1%,1/16W,CHIA':;

SECTION_NUMBER 1
 '@S9S_MB_2U_LIB.S9S_MB_2U(SCH_1):PAGE501_I119@PURE_QUANTA.Q_RES(CHIPS)':
 C_PATH='@s9s_mb_2u_lib.s9s_mb_2u(sch_1):page501_i119@pure_quanta.q_res(chips)';

PART_NAME
 R1356 'Q_RES_0402LF-1K,1%,1/16W,CHIP,A':;

SECTION_NUMBER 1
 '@S9S_MB_2U_LIB.S9S_MB_2U(SCH_1):PAGE501_I96@PURE_QUANTA.Q_RES(CHIPS)':
 C_PATH='@s9s_mb_2u_lib.s9s_mb_2u(sch_1):page501_i96@pure_quanta.q_res(chips)';

PART_NAME
 R1355 'Q_RES_0402LF-100K,1%,1/16W,CHIA':;

SECTION_NUMBER 1
 '@S9S_MB_2U_LIB.S9S_MB_2U(SCH_1):PAGE501_I93@PURE_QUANTA.Q_RES(CHIPS)':
 C_PATH='@s9s_mb_2u_lib.s9s_mb_2u(sch_1):page501_i93@pure_quanta.q_res(chips)';

PART_NAME
 R1354 'Q_RES_0402LF-100K,1%,1/16W,CHIA':;

SECTION_NUMBER 1
 '@S9S_MB_2U_LIB.S9S_MB_2U(SCH_1):PAGE501_I91@PURE_QUANTA.Q_RES(CHIPS)':
 C_PATH='@s9s_mb_2u_lib.s9s_mb_2u(sch_1):page501_i91@pure_quanta.q_res(chips)';

PART_NAME
 R1353 'Q_RES_0402LF-100K,1%,1/16W,CHIA':;

SECTION_NUMBER 1
 '@S9S_MB_2U_LIB.S9S_MB_2U(SCH_1):PAGE501_I92@PURE_QUANTA.Q_RES(CHIPS)':
 C_PATH='@s9s_mb_2u_lib.s9s_mb_2u(sch_1):page501_i92@pure_quanta.q_res(chips)';

PART_NAME
 R1352 'Q_RES_0402LF-100K,1%,1/16W,CHIA':;

SECTION_NUMBER 1
 '@S9S_MB_2U_LIB.S9S_MB_2U(SCH_1):PAGE501_I87@PURE_QUANTA.Q_RES(CHIPS)':
 C_PATH='@s9s_mb_2u_lib.s9s_mb_2u(sch_1):page501_i87@pure_quanta.q_res(chips)';

PART_NAME
 R1351 'Q_RES_0402LF-100K,1%,1/16W,CHIA':;

SECTION_NUMBER 1
 '@S9S_MB_2U_LIB.S9S_MB_2U(SCH_1):PAGE501_I86@PURE_QUANTA.Q_RES(CHIPS)':
 C_PATH='@s9s_mb_2u_lib.s9s_mb_2u(sch_1):page501_i86@pure_quanta.q_res(chips)';

PART_NAME
 R1350 'Q_RES_0402LF-100K,1%,1/16W,CHIA':;

SECTION_NUMBER 1
 '@S9S_MB_2U_LIB.S9S_MB_2U(SCH_1):PAGE501_I82@PURE_QUANTA.Q_RES(CHIPS)':
 C_PATH='@s9s_mb_2u_lib.s9s_mb_2u(sch_1):page501_i82@pure_quanta.q_res(chips)';

PART_NAME
 R1296 'Q_RES_0402LF-22,1%,1/16W,CHIP,A':;

SECTION_NUMBER 1
 '@S9S_MB_2U_LIB.S9S_MB_2U(SCH_1):PAGE501_I104@PURE_QUANTA.Q_RES(CHIPS)':
 C_PATH='@s9s_mb_2u_lib.s9s_mb_2u(sch_1):page501_i104@pure_quanta.q_res(chips)';

PART_NAME
 R1295 'Q_RES_0402LF-22,1%,1/16W,CHIP,A':;

SECTION_NUMBER 1
 '@S9S_MB_2U_LIB.S9S_MB_2U(SCH_1):PAGE501_I103@PURE_QUANTA.Q_RES(CHIPS)':
 C_PATH='@s9s_mb_2u_lib.s9s_mb_2u(sch_1):page501_i103@pure_quanta.q_res(chips)';

PART_NAME
 R1294 'Q_RES_0402LF-22,1%,1/16W,CHIP,A':;

SECTION_NUMBER 1
 '@S9S_MB_2U_LIB.S9S_MB_2U(SCH_1):PAGE501_I102@PURE_QUANTA.Q_RES(CHIPS)':
 C_PATH='@s9s_mb_2u_lib.s9s_mb_2u(sch_1):page501_i102@pure_quanta.q_res(chips)';

PART_NAME
 R1293 'Q_RES_0402LF-22,1%,1/16W,CHIP,A':;

SECTION_NUMBER 1
 '@S9S_MB_2U_LIB.S9S_MB_2U(SCH_1):PAGE501_I101@PURE_QUANTA.Q_RES(CHIPS)':
 C_PATH='@s9s_mb_2u_lib.s9s_mb_2u(sch_1):page501_i101@pure_quanta.q_res(chips)';

PART_NAME
 R1292 'Q_RES_0402LF-22,1%,1/16W,CHIP,A':;

SECTION_NUMBER 1
 '@S9S_MB_2U_LIB.S9S_MB_2U(SCH_1):PAGE501_I100@PURE_QUANTA.Q_RES(CHIPS)':
 C_PATH='@s9s_mb_2u_lib.s9s_mb_2u(sch_1):page501_i100@pure_quanta.q_res(chips)';

PART_NAME
 R1291 'Q_RES_0402LF-22,1%,1/16W,CHIP,A':;

SECTION_NUMBER 1
 '@S9S_MB_2U_LIB.S9S_MB_2U(SCH_1):PAGE501_I99@PURE_QUANTA.Q_RES(CHIPS)':
 C_PATH='@s9s_mb_2u_lib.s9s_mb_2u(sch_1):page501_i99@pure_quanta.q_res(chips)';

PART_NAME
 R1290 'Q_RES_0402LF-22,1%,1/16W,CHIP,A':;

SECTION_NUMBER 1
 '@S9S_MB_2U_LIB.S9S_MB_2U(SCH_1):PAGE501_I98@PURE_QUANTA.Q_RES(CHIPS)':
 C_PATH='@s9s_mb_2u_lib.s9s_mb_2u(sch_1):page501_i98@pure_quanta.q_res(chips)';

PART_NAME
 R1289 'Q_RES_0402LF-100K,1%,1/16W,CHIA':;

SECTION_NUMBER 1
 '@S9S_MB_2U_LIB.S9S_MB_2U(SCH_1):PAGE501_I56@PURE_QUANTA.Q_RES(CHIPS)':
 C_PATH='@s9s_mb_2u_lib.s9s_mb_2u(sch_1):page501_i56@pure_quanta.q_res(chips)';

PART_NAME
 R923 'Q_RES_0402LF-33.2,1%,1/16W,CHIA':;

SECTION_NUMBER 1
 '@S9S_MB_2U_LIB.S9S_MB_2U(SCH_1):PAGE501_I118@PURE_QUANTA.Q_RES(CHIPS)':
 C_PATH='@s9s_mb_2u_lib.s9s_mb_2u(sch_1):page501_i118@pure_quanta.q_res(chips)';

PART_NAME
 C1241 'Q_CAP_0402-0.1UF,25V,10%,X7R,CA':;

SECTION_NUMBER 1
 '@S9S_MB_2U_LIB.S9S_MB_2U(SCH_1):PAGE501_I115@PURE_QUANTA.Q_CAP(CHIPS)':
 C_PATH='@s9s_mb_2u_lib.s9s_mb_2u(sch_1):page501_i115@pure_quanta.q_cap(chips)';

PART_NAME
 C641 'Q_CAP_0402-0.1UF,25V,10%,X7R,CA':;

SECTION_NUMBER 1
 '@S9S_MB_2U_LIB.S9S_MB_2U(SCH_1):PAGE501_I16@PURE_QUANTA.Q_CAP(CHIPS)':
 C_PATH='@s9s_mb_2u_lib.s9s_mb_2u(sch_1):page501_i16@pure_quanta.q_cap(chips)';

PART_NAME
 C640 'Q_CAP_0402-0.1UF,25V,10%,X7R,CA':;

SECTION_NUMBER 1
 '@S9S_MB_2U_LIB.S9S_MB_2U(SCH_1):PAGE501_I47@PURE_QUANTA.Q_CAP(CHIPS)':
 C_PATH='@s9s_mb_2u_lib.s9s_mb_2u(sch_1):page501_i47@pure_quanta.q_cap(chips)';

PART_NAME
 C639 'Q_CAP_0402-0.1UF,25V,10%,X7R,CA':;

SECTION_NUMBER 1
 '@S9S_MB_2U_LIB.S9S_MB_2U(SCH_1):PAGE501_I59@PURE_QUANTA.Q_CAP(CHIPS)':
 C_PATH='@s9s_mb_2u_lib.s9s_mb_2u(sch_1):page501_i59@pure_quanta.q_cap(chips)';

PART_NAME
 U98 'TXS0104EPWR-TXS0104EPWR,SMLF,IA':;

SECTION_NUMBER 1
 '@S9S_MB_2U_LIB.S9S_MB_2U(SCH_1):PAGE527_I27@PURE_QUANTA.TXS0104EPWR(CHIPS)':
 C_PATH='@s9s_mb_2u_lib.s9s_mb_2u(sch_1):page527_i27@pure_quanta.txs0104epwr(chips~
)';

PART_NAME
 R1705 'Q_RES_0402LF-4.7K,5%,1/16W,CHIA':;

SECTION_NUMBER 1
 '@S9S_MB_2U_LIB.S9S_MB_2U(SCH_1):PAGE527_I44@PURE_QUANTA.Q_RES(CHIPS)':
 C_PATH='@s9s_mb_2u_lib.s9s_mb_2u(sch_1):page527_i44@pure_quanta.q_res(chips)';

PART_NAME
 R1704 'Q_RES_0402LF-4.7K,5%,1/16W,CHIA':;

SECTION_NUMBER 1
 '@S9S_MB_2U_LIB.S9S_MB_2U(SCH_1):PAGE527_I46@PURE_QUANTA.Q_RES(CHIPS)':
 C_PATH='@s9s_mb_2u_lib.s9s_mb_2u(sch_1):page527_i46@pure_quanta.q_res(chips)';

PART_NAME
 R1703 'Q_RES_0402LF-4.7K,5%,1/16W,CHIA':;

SECTION_NUMBER 1
 '@S9S_MB_2U_LIB.S9S_MB_2U(SCH_1):PAGE527_I45@PURE_QUANTA.Q_RES(CHIPS)':
 C_PATH='@s9s_mb_2u_lib.s9s_mb_2u(sch_1):page527_i45@pure_quanta.q_res(chips)';

PART_NAME
 R1702 'Q_RES_0402LF-4.7K,5%,1/16W,CHIA':;

SECTION_NUMBER 1
 '@S9S_MB_2U_LIB.S9S_MB_2U(SCH_1):PAGE527_I43@PURE_QUANTA.Q_RES(CHIPS)':
 C_PATH='@s9s_mb_2u_lib.s9s_mb_2u(sch_1):page527_i43@pure_quanta.q_res(chips)';

PART_NAME
 R1701 'Q_RES_0402LF-100K,1%,1/16W,EMPA':;

SECTION_NUMBER 1
 '@S9S_MB_2U_LIB.S9S_MB_2U(SCH_1):PAGE527_I49@PURE_QUANTA.Q_RES(CHIPS)':
 C_PATH='@s9s_mb_2u_lib.s9s_mb_2u(sch_1):page527_i49@pure_quanta.q_res(chips)';

PART_NAME
 R1700 'Q_RES_0402LF-4.7K,5%,1/16W,CHIA':;

SECTION_NUMBER 1
 '@S9S_MB_2U_LIB.S9S_MB_2U(SCH_1):PAGE527_I48@PURE_QUANTA.Q_RES(CHIPS)':
 C_PATH='@s9s_mb_2u_lib.s9s_mb_2u(sch_1):page527_i48@pure_quanta.q_res(chips)';

PART_NAME
 R1272 'Q_RES_0402LF-33.2,1%,1/16W,CHIA':;

SECTION_NUMBER 1
 '@S9S_MB_2U_LIB.S9S_MB_2U(SCH_1):PAGE527_I6@PURE_QUANTA.Q_RES(CHIPS)':
 C_PATH='@s9s_mb_2u_lib.s9s_mb_2u(sch_1):page527_i6@pure_quanta.q_res(chips)';

PART_NAME
 R1271 'Q_RES_0402LF-2.21K    ,1%  ,1/A':;

SECTION_NUMBER 1
 '@S9S_MB_2U_LIB.S9S_MB_2U(SCH_1):PAGE527_I5@PURE_QUANTA.Q_RES(CHIPS)':
 C_PATH='@s9s_mb_2u_lib.s9s_mb_2u(sch_1):page527_i5@pure_quanta.q_res(chips)';

PART_NAME
 JP5 'CONN3_HFK1030G000LAF-CONN3_HFKA':;

SECTION_NUMBER 1
 '@S9S_MB_2U_LIB.S9S_MB_2U(SCH_1):PAGE527_I18@PURE_QUANTA.CONN3_HFK1030G000LAF(CHIPS)':
 C_PATH='@s9s_mb_2u_lib.s9s_mb_2u(sch_1):page527_i18@pure_quanta.conn3_hfk1030g000~
laf(chips)';

PART_NAME
 J54 'CONN7_ABASAT054KA1-CONN7_ABA-SA':;

SECTION_NUMBER 1
 '@S9S_MB_2U_LIB.S9S_MB_2U(SCH_1):PAGE527_I8@PURE_QUANTA.CONN7_ABASAT054KA1(CHIPS)':
 C_PATH='@s9s_mb_2u_lib.s9s_mb_2u(sch_1):page527_i8@pure_quanta.conn7_abasat054ka1~
(chips)';

PART_NAME
 C1323 'Q_CAP_0402-0.1UF,25V,10%,X7R,CA':;

SECTION_NUMBER 1
 '@S9S_MB_2U_LIB.S9S_MB_2U(SCH_1):PAGE527_I28@PURE_QUANTA.Q_CAP(CHIPS)':
 C_PATH='@s9s_mb_2u_lib.s9s_mb_2u(sch_1):page527_i28@pure_quanta.q_cap(chips)';

PART_NAME
 C1305 'Q_CAP_0402-0.1UF,25V,10%,X7R,CA':;

SECTION_NUMBER 1
 '@S9S_MB_2U_LIB.S9S_MB_2U(SCH_1):PAGE527_I36@PURE_QUANTA.Q_CAP(CHIPS)':
 C_PATH='@s9s_mb_2u_lib.s9s_mb_2u(sch_1):page527_i36@pure_quanta.q_cap(chips)';

PART_NAME
 C638 'Q_CAP_0402-0.1UF,25V,10%,X7R,CA':;

SECTION_NUMBER 1
 '@S9S_MB_2U_LIB.S9S_MB_2U(SCH_1):PAGE527_I25@PURE_QUANTA.Q_CAP(CHIPS)':
 C_PATH='@s9s_mb_2u_lib.s9s_mb_2u(sch_1):page527_i25@pure_quanta.q_cap(chips)';

PART_NAME
 C637 'Q_CAP_SATA6G_C0402-SATA6G_0.01A':;

SECTION_NUMBER 1
 '@S9S_MB_2U_LIB.S9S_MB_2U(SCH_1):PAGE527_I13@PURE_QUANTA.Q_CAP_SATA6G(CHIPS)':
 C_PATH='@s9s_mb_2u_lib.s9s_mb_2u(sch_1):page527_i13@pure_quanta.q_cap_sata6g(chip~
s)';

PART_NAME
 C636 'Q_CAP_SATA6G_C0402-SATA6G_0.01A':;

SECTION_NUMBER 1
 '@S9S_MB_2U_LIB.S9S_MB_2U(SCH_1):PAGE527_I12@PURE_QUANTA.Q_CAP_SATA6G(CHIPS)':
 C_PATH='@s9s_mb_2u_lib.s9s_mb_2u(sch_1):page527_i12@pure_quanta.q_cap_sata6g(chip~
s)';

PART_NAME
 C635 'Q_CAP_SATA6G_C0402-SATA6G_0.01A':;

SECTION_NUMBER 1
 '@S9S_MB_2U_LIB.S9S_MB_2U(SCH_1):PAGE527_I11@PURE_QUANTA.Q_CAP_SATA6G(CHIPS)':
 C_PATH='@s9s_mb_2u_lib.s9s_mb_2u(sch_1):page527_i11@pure_quanta.q_cap_sata6g(chip~
s)';

PART_NAME
 C634 'Q_CAP_SATA6G_C0402-SATA6G_0.01A':;

SECTION_NUMBER 1
 '@S9S_MB_2U_LIB.S9S_MB_2U(SCH_1):PAGE527_I10@PURE_QUANTA.Q_CAP_SATA6G(CHIPS)':
 C_PATH='@s9s_mb_2u_lib.s9s_mb_2u(sch_1):page527_i10@pure_quanta.q_cap_sata6g(chip~
s)';

PART_NAME
 C633 'Q_CAP_C0805-22UF,25V,20%,X5R,CA':;

SECTION_NUMBER 1
 '@S9S_MB_2U_LIB.S9S_MB_2U(SCH_1):PAGE527_I24@PURE_QUANTA.Q_CAP(CHIPS)':
 C_PATH='@s9s_mb_2u_lib.s9s_mb_2u(sch_1):page527_i24@pure_quanta.q_cap(chips)';

PART_NAME
 C632 'Q_CAP_C0805-10UF,25V,10%,X6S,CA':;

SECTION_NUMBER 1
 '@S9S_MB_2U_LIB.S9S_MB_2U(SCH_1):PAGE527_I20@PURE_QUANTA.Q_CAP(CHIPS)':
 C_PATH='@s9s_mb_2u_lib.s9s_mb_2u(sch_1):page527_i20@pure_quanta.q_cap(chips)';

PART_NAME
 U65 'TMP75AIDR-TMP75AIDR,SMLF,IC,ALA':;

SECTION_NUMBER 1
 '@S9S_MB_2U_LIB.S9S_MB_2U(SCH_1):PAGE566_I84@PURE_QUANTA.TMP75AIDR(CHIPS)':
 C_PATH='@s9s_mb_2u_lib.s9s_mb_2u(sch_1):page566_i84@pure_quanta.tmp75aidr(chips)';

PART_NAME
 U64 'M24128BWDW6TP-M24128-BWDW6TP,SA':;

SECTION_NUMBER 1
 '@S9S_MB_2U_LIB.S9S_MB_2U(SCH_1):PAGE566_I35@PURE_QUANTA.M24128BWDW6TP(CHIPS)':
 C_PATH='@s9s_mb_2u_lib.s9s_mb_2u(sch_1):page566_i35@pure_quanta.m24128bwdw6tp(chi~
ps)';

PART_NAME
 U63 'TMP75AIDR-TMP75AIDR,SMLF,IC,ALA':;

SECTION_NUMBER 1
 '@S9S_MB_2U_LIB.S9S_MB_2U(SCH_1):PAGE566_I1@PURE_QUANTA.TMP75AIDR(CHIPS)':
 C_PATH='@s9s_mb_2u_lib.s9s_mb_2u(sch_1):page566_i1@pure_quanta.tmp75aidr(chips)';

PART_NAME
 R1332 'Q_RES_0402LF-4.7K,5%,1/16W,EMPA':;

SECTION_NUMBER 1
 '@S9S_MB_2U_LIB.S9S_MB_2U(SCH_1):PAGE566_I93@PURE_QUANTA.Q_RES(CHIPS)':
 C_PATH='@s9s_mb_2u_lib.s9s_mb_2u(sch_1):page566_i93@pure_quanta.q_res(chips)';

PART_NAME
 R1331 'Q_RES_0402LF-4.7K,5%,1/16W,EMPA':;

SECTION_NUMBER 1
 '@S9S_MB_2U_LIB.S9S_MB_2U(SCH_1):PAGE566_I95@PURE_QUANTA.Q_RES(CHIPS)':
 C_PATH='@s9s_mb_2u_lib.s9s_mb_2u(sch_1):page566_i95@pure_quanta.q_res(chips)';

PART_NAME
 R733 'Q_RES_0402LF-1K,1%,1/16W,CHIP,A':;

SECTION_NUMBER 1
 '@S9S_MB_2U_LIB.S9S_MB_2U(SCH_1):PAGE566_I88@PURE_QUANTA.Q_RES(CHIPS)':
 C_PATH='@s9s_mb_2u_lib.s9s_mb_2u(sch_1):page566_i88@pure_quanta.q_res(chips)';

PART_NAME
 R732 'Q_RES_0402LF-10K,1%,1/16W,EMPTA':;

SECTION_NUMBER 1
 '@S9S_MB_2U_LIB.S9S_MB_2U(SCH_1):PAGE566_I85@PURE_QUANTA.Q_RES(CHIPS)':
 C_PATH='@s9s_mb_2u_lib.s9s_mb_2u(sch_1):page566_i85@pure_quanta.q_res(chips)';

PART_NAME
 R731 'Q_RES_0402LF-1K,1%,1/16W,EMPTYA':;

SECTION_NUMBER 1
 '@S9S_MB_2U_LIB.S9S_MB_2U(SCH_1):PAGE566_I89@PURE_QUANTA.Q_RES(CHIPS)':
 C_PATH='@s9s_mb_2u_lib.s9s_mb_2u(sch_1):page566_i89@pure_quanta.q_res(chips)';

PART_NAME
 R730 'Q_RES_0402LF-10K,1%,1/16W,CHIPA':;

SECTION_NUMBER 1
 '@S9S_MB_2U_LIB.S9S_MB_2U(SCH_1):PAGE566_I86@PURE_QUANTA.Q_RES(CHIPS)':
 C_PATH='@s9s_mb_2u_lib.s9s_mb_2u(sch_1):page566_i86@pure_quanta.q_res(chips)';

PART_NAME
 R729 'Q_RES_0402LF-1K,1%,1/16W,CHIP,A':;

SECTION_NUMBER 1
 '@S9S_MB_2U_LIB.S9S_MB_2U(SCH_1):PAGE566_I90@PURE_QUANTA.Q_RES(CHIPS)':
 C_PATH='@s9s_mb_2u_lib.s9s_mb_2u(sch_1):page566_i90@pure_quanta.q_res(chips)';

PART_NAME
 R728 'Q_RES_0402LF-10K,1%,1/16W,EMPTA':;

SECTION_NUMBER 1
 '@S9S_MB_2U_LIB.S9S_MB_2U(SCH_1):PAGE566_I87@PURE_QUANTA.Q_RES(CHIPS)':
 C_PATH='@s9s_mb_2u_lib.s9s_mb_2u(sch_1):page566_i87@pure_quanta.q_res(chips)';

PART_NAME
 R726 'Q_RES_0402LF-33.2,1%,1/16W,CHIA':;

SECTION_NUMBER 1
 '@S9S_MB_2U_LIB.S9S_MB_2U(SCH_1):PAGE566_I91@PURE_QUANTA.Q_RES(CHIPS)':
 C_PATH='@s9s_mb_2u_lib.s9s_mb_2u(sch_1):page566_i91@pure_quanta.q_res(chips)';

PART_NAME
 R725 'Q_RES_0402LF-33.2,1%,1/16W,CHIA':;

SECTION_NUMBER 1
 '@S9S_MB_2U_LIB.S9S_MB_2U(SCH_1):PAGE566_I92@PURE_QUANTA.Q_RES(CHIPS)':
 C_PATH='@s9s_mb_2u_lib.s9s_mb_2u(sch_1):page566_i92@pure_quanta.q_res(chips)';

PART_NAME
 R722 'Q_RES_0402LF-1K,1%,1/16W,EMPTYA':;

SECTION_NUMBER 1
 '@S9S_MB_2U_LIB.S9S_MB_2U(SCH_1):PAGE566_I61@PURE_QUANTA.Q_RES(CHIPS)':
 C_PATH='@s9s_mb_2u_lib.s9s_mb_2u(sch_1):page566_i61@pure_quanta.q_res(chips)';

PART_NAME
 R721 'Q_RES_0402LF-10K,1%,1/16W,CHIPA':;

SECTION_NUMBER 1
 '@S9S_MB_2U_LIB.S9S_MB_2U(SCH_1):PAGE566_I62@PURE_QUANTA.Q_RES(CHIPS)':
 C_PATH='@s9s_mb_2u_lib.s9s_mb_2u(sch_1):page566_i62@pure_quanta.q_res(chips)';

PART_NAME
 R720 'Q_RES_0402LF-1K,1%,1/16W,EMPTYA':;

SECTION_NUMBER 1
 '@S9S_MB_2U_LIB.S9S_MB_2U(SCH_1):PAGE566_I32@PURE_QUANTA.Q_RES(CHIPS)':
 C_PATH='@s9s_mb_2u_lib.s9s_mb_2u(sch_1):page566_i32@pure_quanta.q_res(chips)';

PART_NAME
 R719 'Q_RES_0402LF-10K,1%,1/16W,CHIPA':;

SECTION_NUMBER 1
 '@S9S_MB_2U_LIB.S9S_MB_2U(SCH_1):PAGE566_I29@PURE_QUANTA.Q_RES(CHIPS)':
 C_PATH='@s9s_mb_2u_lib.s9s_mb_2u(sch_1):page566_i29@pure_quanta.q_res(chips)';

PART_NAME
 R718 'Q_RES_0402LF-1K,1%,1/16W,CHIP,A':;

SECTION_NUMBER 1
 '@S9S_MB_2U_LIB.S9S_MB_2U(SCH_1):PAGE566_I50@PURE_QUANTA.Q_RES(CHIPS)':
 C_PATH='@s9s_mb_2u_lib.s9s_mb_2u(sch_1):page566_i50@pure_quanta.q_res(chips)';

PART_NAME
 R717 'Q_RES_0402LF-10K,1%,1/16W,EMPTA':;

SECTION_NUMBER 1
 '@S9S_MB_2U_LIB.S9S_MB_2U(SCH_1):PAGE566_I45@PURE_QUANTA.Q_RES(CHIPS)':
 C_PATH='@s9s_mb_2u_lib.s9s_mb_2u(sch_1):page566_i45@pure_quanta.q_res(chips)';

PART_NAME
 R716 'Q_RES_0402LF-1K,1%,1/16W,CHIP,A':;

SECTION_NUMBER 1
 '@S9S_MB_2U_LIB.S9S_MB_2U(SCH_1):PAGE566_I31@PURE_QUANTA.Q_RES(CHIPS)':
 C_PATH='@s9s_mb_2u_lib.s9s_mb_2u(sch_1):page566_i31@pure_quanta.q_res(chips)';

PART_NAME
 R715 'Q_RES_0402LF-10K,1%,1/16W,EMPTA':;

SECTION_NUMBER 1
 '@S9S_MB_2U_LIB.S9S_MB_2U(SCH_1):PAGE566_I28@PURE_QUANTA.Q_RES(CHIPS)':
 C_PATH='@s9s_mb_2u_lib.s9s_mb_2u(sch_1):page566_i28@pure_quanta.q_res(chips)';

PART_NAME
 R714 'Q_RES_0402LF-1K,1%,1/16W,CHIP,A':;

SECTION_NUMBER 1
 '@S9S_MB_2U_LIB.S9S_MB_2U(SCH_1):PAGE566_I52@PURE_QUANTA.Q_RES(CHIPS)':
 C_PATH='@s9s_mb_2u_lib.s9s_mb_2u(sch_1):page566_i52@pure_quanta.q_res(chips)';

PART_NAME
 R713 'Q_RES_0402LF-10K,1%,1/16W,EMPTA':;

SECTION_NUMBER 1
 '@S9S_MB_2U_LIB.S9S_MB_2U(SCH_1):PAGE566_I47@PURE_QUANTA.Q_RES(CHIPS)':
 C_PATH='@s9s_mb_2u_lib.s9s_mb_2u(sch_1):page566_i47@pure_quanta.q_res(chips)';

PART_NAME
 R712 'Q_RES_0402LF-1K,1%,1/16W,CHIP,A':;

SECTION_NUMBER 1
 '@S9S_MB_2U_LIB.S9S_MB_2U(SCH_1):PAGE566_I30@PURE_QUANTA.Q_RES(CHIPS)':
 C_PATH='@s9s_mb_2u_lib.s9s_mb_2u(sch_1):page566_i30@pure_quanta.q_res(chips)';

PART_NAME
 R711 'Q_RES_0402LF-10K,1%,1/16W,EMPTA':;

SECTION_NUMBER 1
 '@S9S_MB_2U_LIB.S9S_MB_2U(SCH_1):PAGE566_I27@PURE_QUANTA.Q_RES(CHIPS)':
 C_PATH='@s9s_mb_2u_lib.s9s_mb_2u(sch_1):page566_i27@pure_quanta.q_res(chips)';

PART_NAME
 R710 'Q_RES_0402LF-1K,1%,1/16W,CHIP,A':;

SECTION_NUMBER 1
 '@S9S_MB_2U_LIB.S9S_MB_2U(SCH_1):PAGE566_I57@PURE_QUANTA.Q_RES(CHIPS)':
 C_PATH='@s9s_mb_2u_lib.s9s_mb_2u(sch_1):page566_i57@pure_quanta.q_res(chips)';

PART_NAME
 R709 'Q_RES_0402LF-33.2,1%,1/16W,CHIA':;

SECTION_NUMBER 1
 '@S9S_MB_2U_LIB.S9S_MB_2U(SCH_1):PAGE566_I37@PURE_QUANTA.Q_RES(CHIPS)':
 C_PATH='@s9s_mb_2u_lib.s9s_mb_2u(sch_1):page566_i37@pure_quanta.q_res(chips)';

PART_NAME
 R475 'Q_RES_0402LF-33.2,1%,1/16W,CHIA':;

SECTION_NUMBER 1
 '@S9S_MB_2U_LIB.S9S_MB_2U(SCH_1):PAGE566_I39@PURE_QUANTA.Q_RES(CHIPS)':
 C_PATH='@s9s_mb_2u_lib.s9s_mb_2u(sch_1):page566_i39@pure_quanta.q_res(chips)';

PART_NAME
 R460 'Q_RES_0402LF-33.2,1%,1/16W,CHIA':;

SECTION_NUMBER 1
 '@S9S_MB_2U_LIB.S9S_MB_2U(SCH_1):PAGE566_I14@PURE_QUANTA.Q_RES(CHIPS)':
 C_PATH='@s9s_mb_2u_lib.s9s_mb_2u(sch_1):page566_i14@pure_quanta.q_res(chips)';

PART_NAME
 R459 'Q_RES_0402LF-33.2,1%,1/16W,CHIA':;

SECTION_NUMBER 1
 '@S9S_MB_2U_LIB.S9S_MB_2U(SCH_1):PAGE566_I15@PURE_QUANTA.Q_RES(CHIPS)':
 C_PATH='@s9s_mb_2u_lib.s9s_mb_2u(sch_1):page566_i15@pure_quanta.q_res(chips)';

PART_NAME
 C631 'Q_CAP_0402-0.1UF,25V,10%,X7R,CA':;

SECTION_NUMBER 1
 '@S9S_MB_2U_LIB.S9S_MB_2U(SCH_1):PAGE566_I75@PURE_QUANTA.Q_CAP(CHIPS)':
 C_PATH='@s9s_mb_2u_lib.s9s_mb_2u(sch_1):page566_i75@pure_quanta.q_cap(chips)';

PART_NAME
 C630 'Q_CAP_0402-0.1UF,25V,10%,X7R,CA':;

SECTION_NUMBER 1
 '@S9S_MB_2U_LIB.S9S_MB_2U(SCH_1):PAGE566_I10@PURE_QUANTA.Q_CAP(CHIPS)':
 C_PATH='@s9s_mb_2u_lib.s9s_mb_2u(sch_1):page566_i10@pure_quanta.q_cap(chips)';

PART_NAME
 C629 'Q_CAP_0402-0.1UF,25V,10%,X7R,CA':;

SECTION_NUMBER 1
 '@S9S_MB_2U_LIB.S9S_MB_2U(SCH_1):PAGE566_I55@PURE_QUANTA.Q_CAP(CHIPS)':
 C_PATH='@s9s_mb_2u_lib.s9s_mb_2u(sch_1):page566_i55@pure_quanta.q_cap(chips)';

PART_NAME
 R846 'Q_RES_0402LF-0,5%,1/16W,EMPTY,A':;

SECTION_NUMBER 1
 '@S9S_MB_2U_LIB.S9S_MB_2U(SCH_1):PAGE474_I67@PURE_QUANTA.Q_RES(CHIPS)':
 C_PATH='@s9s_mb_2u_lib.s9s_mb_2u(sch_1):page474_i67@pure_quanta.q_res(chips)';

PART_NAME
 R845 'Q_RES_0402LF-0,5%,1/16W,EMPTY,A':;

SECTION_NUMBER 1
 '@S9S_MB_2U_LIB.S9S_MB_2U(SCH_1):PAGE474_I53@PURE_QUANTA.Q_RES(CHIPS)':
 C_PATH='@s9s_mb_2u_lib.s9s_mb_2u(sch_1):page474_i53@pure_quanta.q_res(chips)';

PART_NAME
 R844 'Q_RES_0402LF-0,5%,1/16W,EMPTY,A':;

SECTION_NUMBER 1
 '@S9S_MB_2U_LIB.S9S_MB_2U(SCH_1):PAGE474_I50@PURE_QUANTA.Q_RES(CHIPS)':
 C_PATH='@s9s_mb_2u_lib.s9s_mb_2u(sch_1):page474_i50@pure_quanta.q_res(chips)';

PART_NAME
 R843 'Q_RES_0402LF-0,5%,1/16W,EMPTY,A':;

SECTION_NUMBER 1
 '@S9S_MB_2U_LIB.S9S_MB_2U(SCH_1):PAGE474_I68@PURE_QUANTA.Q_RES(CHIPS)':
 C_PATH='@s9s_mb_2u_lib.s9s_mb_2u(sch_1):page474_i68@pure_quanta.q_res(chips)';

PART_NAME
 R842 'Q_RES_0402LF-1K,1%,1/16W,CHIP,A':;

SECTION_NUMBER 1
 '@S9S_MB_2U_LIB.S9S_MB_2U(SCH_1):PAGE474_I71@PURE_QUANTA.Q_RES(CHIPS)':
 C_PATH='@s9s_mb_2u_lib.s9s_mb_2u(sch_1):page474_i71@pure_quanta.q_res(chips)';

PART_NAME
 R841 'Q_RES_0402LF-1K,1%,1/16W,CHIP,A':;

SECTION_NUMBER 1
 '@S9S_MB_2U_LIB.S9S_MB_2U(SCH_1):PAGE474_I56@PURE_QUANTA.Q_RES(CHIPS)':
 C_PATH='@s9s_mb_2u_lib.s9s_mb_2u(sch_1):page474_i56@pure_quanta.q_res(chips)';

PART_NAME
 R840 'Q_RES_0402LF-1K,1%,1/16W,CHIP,A':;

SECTION_NUMBER 1
 '@S9S_MB_2U_LIB.S9S_MB_2U(SCH_1):PAGE474_I49@PURE_QUANTA.Q_RES(CHIPS)':
 C_PATH='@s9s_mb_2u_lib.s9s_mb_2u(sch_1):page474_i49@pure_quanta.q_res(chips)';

PART_NAME
 R839 'Q_RES_0402LF-1K,1%,1/16W,CHIP,A':;

SECTION_NUMBER 1
 '@S9S_MB_2U_LIB.S9S_MB_2U(SCH_1):PAGE474_I75@PURE_QUANTA.Q_RES(CHIPS)':
 C_PATH='@s9s_mb_2u_lib.s9s_mb_2u(sch_1):page474_i75@pure_quanta.q_res(chips)';

PART_NAME
 R838 'Q_RES_0402LF-0,5%,1/16W,CHIP,CA':;

SECTION_NUMBER 1
 '@S9S_MB_2U_LIB.S9S_MB_2U(SCH_1):PAGE474_I76@PURE_QUANTA.Q_RES(CHIPS)':
 C_PATH='@s9s_mb_2u_lib.s9s_mb_2u(sch_1):page474_i76@pure_quanta.q_res(chips)';

PART_NAME
 R837 'Q_RES_0402LF-0,5%,1/16W,CHIP,CA':;

SECTION_NUMBER 1
 '@S9S_MB_2U_LIB.S9S_MB_2U(SCH_1):PAGE474_I59@PURE_QUANTA.Q_RES(CHIPS)':
 C_PATH='@s9s_mb_2u_lib.s9s_mb_2u(sch_1):page474_i59@pure_quanta.q_res(chips)';

PART_NAME
 R836 'Q_RES_0402LF-0,5%,1/16W,CHIP,CA':;

SECTION_NUMBER 1
 '@S9S_MB_2U_LIB.S9S_MB_2U(SCH_1):PAGE474_I26@PURE_QUANTA.Q_RES(CHIPS)':
 C_PATH='@s9s_mb_2u_lib.s9s_mb_2u(sch_1):page474_i26@pure_quanta.q_res(chips)';

PART_NAME
 R835 'Q_RES_0402LF-0,5%,1/16W,CHIP,CA':;

SECTION_NUMBER 1
 '@S9S_MB_2U_LIB.S9S_MB_2U(SCH_1):PAGE474_I86@PURE_QUANTA.Q_RES(CHIPS)':
 C_PATH='@s9s_mb_2u_lib.s9s_mb_2u(sch_1):page474_i86@pure_quanta.q_res(chips)';

PART_NAME
 R834 'Q_RES_0402LF-1K,1%,1/16W,CHIP,A':;

SECTION_NUMBER 1
 '@S9S_MB_2U_LIB.S9S_MB_2U(SCH_1):PAGE474_I77@PURE_QUANTA.Q_RES(CHIPS)':
 C_PATH='@s9s_mb_2u_lib.s9s_mb_2u(sch_1):page474_i77@pure_quanta.q_res(chips)';

PART_NAME
 R833 'Q_RES_0402LF-1K,1%,1/16W,CHIP,A':;

SECTION_NUMBER 1
 '@S9S_MB_2U_LIB.S9S_MB_2U(SCH_1):PAGE474_I60@PURE_QUANTA.Q_RES(CHIPS)':
 C_PATH='@s9s_mb_2u_lib.s9s_mb_2u(sch_1):page474_i60@pure_quanta.q_res(chips)';

PART_NAME
 R832 'Q_RES_0402LF-1K,1%,1/16W,CHIP,A':;

SECTION_NUMBER 1
 '@S9S_MB_2U_LIB.S9S_MB_2U(SCH_1):PAGE474_I27@PURE_QUANTA.Q_RES(CHIPS)':
 C_PATH='@s9s_mb_2u_lib.s9s_mb_2u(sch_1):page474_i27@pure_quanta.q_res(chips)';

PART_NAME
 R831 'Q_RES_0402LF-1K,1%,1/16W,CHIP,A':;

SECTION_NUMBER 1
 '@S9S_MB_2U_LIB.S9S_MB_2U(SCH_1):PAGE474_I81@PURE_QUANTA.Q_RES(CHIPS)':
 C_PATH='@s9s_mb_2u_lib.s9s_mb_2u(sch_1):page474_i81@pure_quanta.q_res(chips)';

PART_NAME
 R830 'Q_RES_0402LF-0,5%,1/16W,EMPTY,A':;

SECTION_NUMBER 1
 '@S9S_MB_2U_LIB.S9S_MB_2U(SCH_1):PAGE474_I82@PURE_QUANTA.Q_RES(CHIPS)':
 C_PATH='@s9s_mb_2u_lib.s9s_mb_2u(sch_1):page474_i82@pure_quanta.q_res(chips)';

PART_NAME
 R829 'Q_RES_0402LF-0,5%,1/16W,EMPTY,A':;

SECTION_NUMBER 1
 '@S9S_MB_2U_LIB.S9S_MB_2U(SCH_1):PAGE474_I63@PURE_QUANTA.Q_RES(CHIPS)':
 C_PATH='@s9s_mb_2u_lib.s9s_mb_2u(sch_1):page474_i63@pure_quanta.q_res(chips)';

PART_NAME
 R828 'Q_RES_0402LF-0,5%,1/16W,EMPTY,A':;

SECTION_NUMBER 1
 '@S9S_MB_2U_LIB.S9S_MB_2U(SCH_1):PAGE474_I23@PURE_QUANTA.Q_RES(CHIPS)':
 C_PATH='@s9s_mb_2u_lib.s9s_mb_2u(sch_1):page474_i23@pure_quanta.q_res(chips)';

PART_NAME
 R827 'Q_RES_0402LF-0,5%,1/16W,EMPTY,A':;

SECTION_NUMBER 1
 '@S9S_MB_2U_LIB.S9S_MB_2U(SCH_1):PAGE474_I89@PURE_QUANTA.Q_RES(CHIPS)':
 C_PATH='@s9s_mb_2u_lib.s9s_mb_2u(sch_1):page474_i89@pure_quanta.q_res(chips)';

PART_NAME
 R708 'Q_RES_0402LF-10K,1%,1/16W,EMPTA':;

SECTION_NUMBER 1
 '@S9S_MB_2U_LIB.S9S_MB_2U(SCH_1):PAGE474_I109@PURE_QUANTA.Q_RES(CHIPS)':
 C_PATH='@s9s_mb_2u_lib.s9s_mb_2u(sch_1):page474_i109@pure_quanta.q_res(chips)';

PART_NAME
 R707 'Q_RES_0402LF-10K,1%,1/16W,EMPTA':;

SECTION_NUMBER 1
 '@S9S_MB_2U_LIB.S9S_MB_2U(SCH_1):PAGE474_I106@PURE_QUANTA.Q_RES(CHIPS)':
 C_PATH='@s9s_mb_2u_lib.s9s_mb_2u(sch_1):page474_i106@pure_quanta.q_res(chips)';

PART_NAME
 R706 'Q_RES_0402LF-10K,1%,1/16W,EMPTA':;

SECTION_NUMBER 1
 '@S9S_MB_2U_LIB.S9S_MB_2U(SCH_1):PAGE474_I103@PURE_QUANTA.Q_RES(CHIPS)':
 C_PATH='@s9s_mb_2u_lib.s9s_mb_2u(sch_1):page474_i103@pure_quanta.q_res(chips)';

PART_NAME
 R705 'Q_RES_0402LF-10K,1%,1/16W,EMPTA':;

SECTION_NUMBER 1
 '@S9S_MB_2U_LIB.S9S_MB_2U(SCH_1):PAGE474_I112@PURE_QUANTA.Q_RES(CHIPS)':
 C_PATH='@s9s_mb_2u_lib.s9s_mb_2u(sch_1):page474_i112@pure_quanta.q_res(chips)';

PART_NAME
 Q12 'MOSFET_NCH_DUAL-2N7002KDW,SMLFA':;

SECTION_NUMBER 1
 '@S9S_MB_2U_LIB.S9S_MB_2U(SCH_1):PAGE474_I115@PURE_QUANTA.MOSFET_NCH_DUAL(CHIPS)':
 C_PATH='@s9s_mb_2u_lib.s9s_mb_2u(sch_1):page474_i115@pure_quanta.mosfet_nch_dual(~
chips)';

SECTION_NUMBER 2
 '@S9S_MB_2U_LIB.S9S_MB_2U(SCH_1):PAGE474_I85@PURE_QUANTA.MOSFET_NCH_DUAL(CHIPS)':
 C_PATH='@s9s_mb_2u_lib.s9s_mb_2u(sch_1):page474_i85@pure_quanta.mosfet_nch_dual(c~
hips)';

PART_NAME
 Q11 'MOSFET_NCH_DUAL-2N7002KDW,SMLFA':;

SECTION_NUMBER 1
 '@S9S_MB_2U_LIB.S9S_MB_2U(SCH_1):PAGE474_I116@PURE_QUANTA.MOSFET_NCH_DUAL(CHIPS)':
 C_PATH='@s9s_mb_2u_lib.s9s_mb_2u(sch_1):page474_i116@pure_quanta.mosfet_nch_dual(~
chips)';

SECTION_NUMBER 2
 '@S9S_MB_2U_LIB.S9S_MB_2U(SCH_1):PAGE474_I46@PURE_QUANTA.MOSFET_NCH_DUAL(CHIPS)':
 C_PATH='@s9s_mb_2u_lib.s9s_mb_2u(sch_1):page474_i46@pure_quanta.mosfet_nch_dual(c~
hips)';

PART_NAME
 Q10 'MOSFET_NCH_DUAL-2N7002KDW,SMLFA':;

SECTION_NUMBER 1
 '@S9S_MB_2U_LIB.S9S_MB_2U(SCH_1):PAGE474_I117@PURE_QUANTA.MOSFET_NCH_DUAL(CHIPS)':
 C_PATH='@s9s_mb_2u_lib.s9s_mb_2u(sch_1):page474_i117@pure_quanta.mosfet_nch_dual(~
chips)';

SECTION_NUMBER 2
 '@S9S_MB_2U_LIB.S9S_MB_2U(SCH_1):PAGE474_I58@PURE_QUANTA.MOSFET_NCH_DUAL(CHIPS)':
 C_PATH='@s9s_mb_2u_lib.s9s_mb_2u(sch_1):page474_i58@pure_quanta.mosfet_nch_dual(c~
hips)';

PART_NAME
 Q9 'MOSFET_NCH_DUAL-2N7002KDW,SMLFA':;

SECTION_NUMBER 1
 '@S9S_MB_2U_LIB.S9S_MB_2U(SCH_1):PAGE474_I118@PURE_QUANTA.MOSFET_NCH_DUAL(CHIPS)':
 C_PATH='@s9s_mb_2u_lib.s9s_mb_2u(sch_1):page474_i118@pure_quanta.mosfet_nch_dual(~
chips)';

SECTION_NUMBER 2
 '@S9S_MB_2U_LIB.S9S_MB_2U(SCH_1):PAGE474_I73@PURE_QUANTA.MOSFET_NCH_DUAL(CHIPS)':
 C_PATH='@s9s_mb_2u_lib.s9s_mb_2u(sch_1):page474_i73@pure_quanta.mosfet_nch_dual(c~
hips)';

PART_NAME
 C628 'Q_CAP_C0402-1UF,25V,10%,EMPTY,A':;

SECTION_NUMBER 1
 '@S9S_MB_2U_LIB.S9S_MB_2U(SCH_1):PAGE474_I110@PURE_QUANTA.Q_CAP(CHIPS)':
 C_PATH='@s9s_mb_2u_lib.s9s_mb_2u(sch_1):page474_i110@pure_quanta.q_cap(chips)';

PART_NAME
 C627 'Q_CAP_C0402-1UF,25V,10%,EMPTY,A':;

SECTION_NUMBER 1
 '@S9S_MB_2U_LIB.S9S_MB_2U(SCH_1):PAGE474_I107@PURE_QUANTA.Q_CAP(CHIPS)':
 C_PATH='@s9s_mb_2u_lib.s9s_mb_2u(sch_1):page474_i107@pure_quanta.q_cap(chips)';

PART_NAME
 C626 'Q_CAP_C0402-1UF,25V,10%,EMPTY,A':;

SECTION_NUMBER 1
 '@S9S_MB_2U_LIB.S9S_MB_2U(SCH_1):PAGE474_I104@PURE_QUANTA.Q_CAP(CHIPS)':
 C_PATH='@s9s_mb_2u_lib.s9s_mb_2u(sch_1):page474_i104@pure_quanta.q_cap(chips)';

PART_NAME
 C625 'Q_CAP_C0402-1UF,25V,10%,EMPTY,A':;

SECTION_NUMBER 1
 '@S9S_MB_2U_LIB.S9S_MB_2U(SCH_1):PAGE474_I113@PURE_QUANTA.Q_CAP(CHIPS)':
 C_PATH='@s9s_mb_2u_lib.s9s_mb_2u(sch_1):page474_i113@pure_quanta.q_cap(chips)';

PART_NAME
 C624 'Q_CAP_C0402-1UF,25V,10%,EMPTY,A':;

SECTION_NUMBER 1
 '@S9S_MB_2U_LIB.S9S_MB_2U(SCH_1):PAGE474_I99@PURE_QUANTA.Q_CAP(CHIPS)':
 C_PATH='@s9s_mb_2u_lib.s9s_mb_2u(sch_1):page474_i99@pure_quanta.q_cap(chips)';

PART_NAME
 C623 'Q_CAP_C0402-1UF,25V,10%,EMPTY,A':;

SECTION_NUMBER 1
 '@S9S_MB_2U_LIB.S9S_MB_2U(SCH_1):PAGE474_I94@PURE_QUANTA.Q_CAP(CHIPS)':
 C_PATH='@s9s_mb_2u_lib.s9s_mb_2u(sch_1):page474_i94@pure_quanta.q_cap(chips)';

PART_NAME
 C622 'Q_CAP_C0402-1UF,25V,10%,EMPTY,A':;

SECTION_NUMBER 1
 '@S9S_MB_2U_LIB.S9S_MB_2U(SCH_1):PAGE474_I91@PURE_QUANTA.Q_CAP(CHIPS)':
 C_PATH='@s9s_mb_2u_lib.s9s_mb_2u(sch_1):page474_i91@pure_quanta.q_cap(chips)';

PART_NAME
 C621 'Q_CAP_C0402-1UF,25V,10%,EMPTY,A':;

SECTION_NUMBER 1
 '@S9S_MB_2U_LIB.S9S_MB_2U(SCH_1):PAGE474_I102@PURE_QUANTA.Q_CAP(CHIPS)':
 C_PATH='@s9s_mb_2u_lib.s9s_mb_2u(sch_1):page474_i102@pure_quanta.q_cap(chips)';

PART_NAME
 R826 'Q_RES_0402LF-0,5%,1/16W,EMPTY,A':;

SECTION_NUMBER 1
 '@S9S_MB_2U_LIB.S9S_MB_2U(SCH_1):PAGE473_I47@PURE_QUANTA.Q_RES(CHIPS)':
 C_PATH='@s9s_mb_2u_lib.s9s_mb_2u(sch_1):page473_i47@pure_quanta.q_res(chips)';

PART_NAME
 R825 'Q_RES_0402LF-0,5%,1/16W,EMPTY,A':;

SECTION_NUMBER 1
 '@S9S_MB_2U_LIB.S9S_MB_2U(SCH_1):PAGE473_I49@PURE_QUANTA.Q_RES(CHIPS)':
 C_PATH='@s9s_mb_2u_lib.s9s_mb_2u(sch_1):page473_i49@pure_quanta.q_res(chips)';

PART_NAME
 R824 'Q_RES_0402LF-0,5%,1/16W,EMPTY,A':;

SECTION_NUMBER 1
 '@S9S_MB_2U_LIB.S9S_MB_2U(SCH_1):PAGE473_I50@PURE_QUANTA.Q_RES(CHIPS)':
 C_PATH='@s9s_mb_2u_lib.s9s_mb_2u(sch_1):page473_i50@pure_quanta.q_res(chips)';

PART_NAME
 R823 'Q_RES_0402LF-0,5%,1/16W,EMPTY,A':;

SECTION_NUMBER 1
 '@S9S_MB_2U_LIB.S9S_MB_2U(SCH_1):PAGE473_I45@PURE_QUANTA.Q_RES(CHIPS)':
 C_PATH='@s9s_mb_2u_lib.s9s_mb_2u(sch_1):page473_i45@pure_quanta.q_res(chips)';

PART_NAME
 R822 'Q_RES_0402LF-1K,1%,1/16W,CHIP,A':;

SECTION_NUMBER 1
 '@S9S_MB_2U_LIB.S9S_MB_2U(SCH_1):PAGE473_I25@PURE_QUANTA.Q_RES(CHIPS)':
 C_PATH='@s9s_mb_2u_lib.s9s_mb_2u(sch_1):page473_i25@pure_quanta.q_res(chips)';

PART_NAME
 R821 'Q_RES_0402LF-1K,1%,1/16W,CHIP,A':;

SECTION_NUMBER 1
 '@S9S_MB_2U_LIB.S9S_MB_2U(SCH_1):PAGE473_I38@PURE_QUANTA.Q_RES(CHIPS)':
 C_PATH='@s9s_mb_2u_lib.s9s_mb_2u(sch_1):page473_i38@pure_quanta.q_res(chips)';

PART_NAME
 R820 'Q_RES_0402LF-1K,1%,1/16W,CHIP,A':;

SECTION_NUMBER 1
 '@S9S_MB_2U_LIB.S9S_MB_2U(SCH_1):PAGE473_I42@PURE_QUANTA.Q_RES(CHIPS)':
 C_PATH='@s9s_mb_2u_lib.s9s_mb_2u(sch_1):page473_i42@pure_quanta.q_res(chips)';

PART_NAME
 R819 'Q_RES_0402LF-1K,1%,1/16W,CHIP,A':;

SECTION_NUMBER 1
 '@S9S_MB_2U_LIB.S9S_MB_2U(SCH_1):PAGE473_I14@PURE_QUANTA.Q_RES(CHIPS)':
 C_PATH='@s9s_mb_2u_lib.s9s_mb_2u(sch_1):page473_i14@pure_quanta.q_res(chips)';

PART_NAME
 R818 'Q_RES_0402LF-0,5%,1/16W,CHIP,CA':;

SECTION_NUMBER 1
 '@S9S_MB_2U_LIB.S9S_MB_2U(SCH_1):PAGE473_I22@PURE_QUANTA.Q_RES(CHIPS)':
 C_PATH='@s9s_mb_2u_lib.s9s_mb_2u(sch_1):page473_i22@pure_quanta.q_res(chips)';

PART_NAME
 R817 'Q_RES_0402LF-0,5%,1/16W,CHIP,CA':;

SECTION_NUMBER 1
 '@S9S_MB_2U_LIB.S9S_MB_2U(SCH_1):PAGE473_I26@PURE_QUANTA.Q_RES(CHIPS)':
 C_PATH='@s9s_mb_2u_lib.s9s_mb_2u(sch_1):page473_i26@pure_quanta.q_res(chips)';

PART_NAME
 R816 'Q_RES_0402LF-0,5%,1/16W,CHIP,CA':;

SECTION_NUMBER 1
 '@S9S_MB_2U_LIB.S9S_MB_2U(SCH_1):PAGE473_I37@PURE_QUANTA.Q_RES(CHIPS)':
 C_PATH='@s9s_mb_2u_lib.s9s_mb_2u(sch_1):page473_i37@pure_quanta.q_res(chips)';

PART_NAME
 R815 'Q_RES_0402LF-0,5%,1/16W,CHIP,CA':;

SECTION_NUMBER 1
 '@S9S_MB_2U_LIB.S9S_MB_2U(SCH_1):PAGE473_I11@PURE_QUANTA.Q_RES(CHIPS)':
 C_PATH='@s9s_mb_2u_lib.s9s_mb_2u(sch_1):page473_i11@pure_quanta.q_res(chips)';

PART_NAME
 R814 'Q_RES_0402LF-1K,1%,1/16W,CHIP,A':;

SECTION_NUMBER 1
 '@S9S_MB_2U_LIB.S9S_MB_2U(SCH_1):PAGE473_I18@PURE_QUANTA.Q_RES(CHIPS)':
 C_PATH='@s9s_mb_2u_lib.s9s_mb_2u(sch_1):page473_i18@pure_quanta.q_res(chips)';

PART_NAME
 R813 'Q_RES_0402LF-1K,1%,1/16W,CHIP,A':;

SECTION_NUMBER 1
 '@S9S_MB_2U_LIB.S9S_MB_2U(SCH_1):PAGE473_I32@PURE_QUANTA.Q_RES(CHIPS)':
 C_PATH='@s9s_mb_2u_lib.s9s_mb_2u(sch_1):page473_i32@pure_quanta.q_res(chips)';

PART_NAME
 R812 'Q_RES_0402LF-1K,1%,1/16W,CHIP,A':;

SECTION_NUMBER 1
 '@S9S_MB_2U_LIB.S9S_MB_2U(SCH_1):PAGE473_I36@PURE_QUANTA.Q_RES(CHIPS)':
 C_PATH='@s9s_mb_2u_lib.s9s_mb_2u(sch_1):page473_i36@pure_quanta.q_res(chips)';

PART_NAME
 R811 'Q_RES_0402LF-1K,1%,1/16W,CHIP,A':;

SECTION_NUMBER 1
 '@S9S_MB_2U_LIB.S9S_MB_2U(SCH_1):PAGE473_I9@PURE_QUANTA.Q_RES(CHIPS)':
 C_PATH='@s9s_mb_2u_lib.s9s_mb_2u(sch_1):page473_i9@pure_quanta.q_res(chips)';

PART_NAME
 R810 'Q_RES_0402LF-0,5%,1/16W,EMPTY,A':;

SECTION_NUMBER 1
 '@S9S_MB_2U_LIB.S9S_MB_2U(SCH_1):PAGE473_I5@PURE_QUANTA.Q_RES(CHIPS)':
 C_PATH='@s9s_mb_2u_lib.s9s_mb_2u(sch_1):page473_i5@pure_quanta.q_res(chips)';

PART_NAME
 R809 'Q_RES_0402LF-0,5%,1/16W,EMPTY,A':;

SECTION_NUMBER 1
 '@S9S_MB_2U_LIB.S9S_MB_2U(SCH_1):PAGE473_I6@PURE_QUANTA.Q_RES(CHIPS)':
 C_PATH='@s9s_mb_2u_lib.s9s_mb_2u(sch_1):page473_i6@pure_quanta.q_res(chips)';

PART_NAME
 R808 'Q_RES_0402LF-0,5%,1/16W,EMPTY,A':;

SECTION_NUMBER 1
 '@S9S_MB_2U_LIB.S9S_MB_2U(SCH_1):PAGE473_I31@PURE_QUANTA.Q_RES(CHIPS)':
 C_PATH='@s9s_mb_2u_lib.s9s_mb_2u(sch_1):page473_i31@pure_quanta.q_res(chips)';

PART_NAME
 R807 'Q_RES_0402LF-0,5%,1/16W,EMPTY,A':;

SECTION_NUMBER 1
 '@S9S_MB_2U_LIB.S9S_MB_2U(SCH_1):PAGE473_I2@PURE_QUANTA.Q_RES(CHIPS)':
 C_PATH='@s9s_mb_2u_lib.s9s_mb_2u(sch_1):page473_i2@pure_quanta.q_res(chips)';

PART_NAME
 R704 'Q_RES_0402LF-10K,1%,1/16W,EMPTA':;

SECTION_NUMBER 1
 '@S9S_MB_2U_LIB.S9S_MB_2U(SCH_1):PAGE473_I75@PURE_QUANTA.Q_RES(CHIPS)':
 C_PATH='@s9s_mb_2u_lib.s9s_mb_2u(sch_1):page473_i75@pure_quanta.q_res(chips)';

PART_NAME
 R703 'Q_RES_0402LF-10K,1%,1/16W,EMPTA':;

SECTION_NUMBER 1
 '@S9S_MB_2U_LIB.S9S_MB_2U(SCH_1):PAGE473_I79@PURE_QUANTA.Q_RES(CHIPS)':
 C_PATH='@s9s_mb_2u_lib.s9s_mb_2u(sch_1):page473_i79@pure_quanta.q_res(chips)';

PART_NAME
 R702 'Q_RES_0402LF-10K,1%,1/16W,EMPTA':;

SECTION_NUMBER 1
 '@S9S_MB_2U_LIB.S9S_MB_2U(SCH_1):PAGE473_I76@PURE_QUANTA.Q_RES(CHIPS)':
 C_PATH='@s9s_mb_2u_lib.s9s_mb_2u(sch_1):page473_i76@pure_quanta.q_res(chips)';

PART_NAME
 R701 'Q_RES_0402LF-10K,1%,1/16W,EMPTA':;

SECTION_NUMBER 1
 '@S9S_MB_2U_LIB.S9S_MB_2U(SCH_1):PAGE473_I63@PURE_QUANTA.Q_RES(CHIPS)':
 C_PATH='@s9s_mb_2u_lib.s9s_mb_2u(sch_1):page473_i63@pure_quanta.q_res(chips)';

PART_NAME
 Q14 'MOSFET_NCH_DUAL-2N7002KDW,SMLFA':;

SECTION_NUMBER 1
 '@S9S_MB_2U_LIB.S9S_MB_2U(SCH_1):PAGE473_I81@PURE_QUANTA.MOSFET_NCH_DUAL(CHIPS)':
 C_PATH='@s9s_mb_2u_lib.s9s_mb_2u(sch_1):page473_i81@pure_quanta.mosfet_nch_dual(c~
hips)';

SECTION_NUMBER 2
 '@S9S_MB_2U_LIB.S9S_MB_2U(SCH_1):PAGE473_I28@PURE_QUANTA.MOSFET_NCH_DUAL(CHIPS)':
 C_PATH='@s9s_mb_2u_lib.s9s_mb_2u(sch_1):page473_i28@pure_quanta.mosfet_nch_dual(c~
hips)';

PART_NAME
 Q13 'MOSFET_NCH_DUAL-2N7002KDW,SMLFA':;

SECTION_NUMBER 1
 '@S9S_MB_2U_LIB.S9S_MB_2U(SCH_1):PAGE473_I80@PURE_QUANTA.MOSFET_NCH_DUAL(CHIPS)':
 C_PATH='@s9s_mb_2u_lib.s9s_mb_2u(sch_1):page473_i80@pure_quanta.mosfet_nch_dual(c~
hips)';

SECTION_NUMBER 2
 '@S9S_MB_2U_LIB.S9S_MB_2U(SCH_1):PAGE473_I23@PURE_QUANTA.MOSFET_NCH_DUAL(CHIPS)':
 C_PATH='@s9s_mb_2u_lib.s9s_mb_2u(sch_1):page473_i23@pure_quanta.mosfet_nch_dual(c~
hips)';

PART_NAME
 Q2 'MOSFET_NCH_DUAL-2N7002KDW,SMLFA':;

SECTION_NUMBER 1
 '@S9S_MB_2U_LIB.S9S_MB_2U(SCH_1):PAGE473_I83@PURE_QUANTA.MOSFET_NCH_DUAL(CHIPS)':
 C_PATH='@s9s_mb_2u_lib.s9s_mb_2u(sch_1):page473_i83@pure_quanta.mosfet_nch_dual(c~
hips)';

SECTION_NUMBER 2
 '@S9S_MB_2U_LIB.S9S_MB_2U(SCH_1):PAGE473_I12@PURE_QUANTA.MOSFET_NCH_DUAL(CHIPS)':
 C_PATH='@s9s_mb_2u_lib.s9s_mb_2u(sch_1):page473_i12@pure_quanta.mosfet_nch_dual(c~
hips)';

PART_NAME
 Q1 'MOSFET_NCH_DUAL-2N7002KDW,SMLFA':;

SECTION_NUMBER 1
 '@S9S_MB_2U_LIB.S9S_MB_2U(SCH_1):PAGE473_I82@PURE_QUANTA.MOSFET_NCH_DUAL(CHIPS)':
 C_PATH='@s9s_mb_2u_lib.s9s_mb_2u(sch_1):page473_i82@pure_quanta.mosfet_nch_dual(c~
hips)';

SECTION_NUMBER 2
 '@S9S_MB_2U_LIB.S9S_MB_2U(SCH_1):PAGE473_I40@PURE_QUANTA.MOSFET_NCH_DUAL(CHIPS)':
 C_PATH='@s9s_mb_2u_lib.s9s_mb_2u(sch_1):page473_i40@pure_quanta.mosfet_nch_dual(c~
hips)';

PART_NAME
 C620 'Q_CAP_C0402-1UF,25V,10%,EMPTY,A':;

SECTION_NUMBER 1
 '@S9S_MB_2U_LIB.S9S_MB_2U(SCH_1):PAGE473_I74@PURE_QUANTA.Q_CAP(CHIPS)':
 C_PATH='@s9s_mb_2u_lib.s9s_mb_2u(sch_1):page473_i74@pure_quanta.q_cap(chips)';

PART_NAME
 C619 'Q_CAP_C0402-1UF,25V,10%,EMPTY,A':;

SECTION_NUMBER 1
 '@S9S_MB_2U_LIB.S9S_MB_2U(SCH_1):PAGE473_I71@PURE_QUANTA.Q_CAP(CHIPS)':
 C_PATH='@s9s_mb_2u_lib.s9s_mb_2u(sch_1):page473_i71@pure_quanta.q_cap(chips)';

PART_NAME
 C618 'Q_CAP_C0402-1UF,25V,10%,EMPTY,A':;

SECTION_NUMBER 1
 '@S9S_MB_2U_LIB.S9S_MB_2U(SCH_1):PAGE473_I70@PURE_QUANTA.Q_CAP(CHIPS)':
 C_PATH='@s9s_mb_2u_lib.s9s_mb_2u(sch_1):page473_i70@pure_quanta.q_cap(chips)';

PART_NAME
 C617 'Q_CAP_C0402-1UF,25V,10%,EMPTY,A':;

SECTION_NUMBER 1
 '@S9S_MB_2U_LIB.S9S_MB_2U(SCH_1):PAGE473_I77@PURE_QUANTA.Q_CAP(CHIPS)':
 C_PATH='@s9s_mb_2u_lib.s9s_mb_2u(sch_1):page473_i77@pure_quanta.q_cap(chips)';

PART_NAME
 C616 'Q_CAP_C0402-1UF,25V,10%,EMPTY,A':;

SECTION_NUMBER 1
 '@S9S_MB_2U_LIB.S9S_MB_2U(SCH_1):PAGE473_I59@PURE_QUANTA.Q_CAP(CHIPS)':
 C_PATH='@s9s_mb_2u_lib.s9s_mb_2u(sch_1):page473_i59@pure_quanta.q_cap(chips)';

PART_NAME
 C615 'Q_CAP_C0402-1UF,25V,10%,EMPTY,A':;

SECTION_NUMBER 1
 '@S9S_MB_2U_LIB.S9S_MB_2U(SCH_1):PAGE473_I62@PURE_QUANTA.Q_CAP(CHIPS)':
 C_PATH='@s9s_mb_2u_lib.s9s_mb_2u(sch_1):page473_i62@pure_quanta.q_cap(chips)';

PART_NAME
 C614 'Q_CAP_C0402-1UF,25V,10%,EMPTY,A':;

SECTION_NUMBER 1
 '@S9S_MB_2U_LIB.S9S_MB_2U(SCH_1):PAGE473_I65@PURE_QUANTA.Q_CAP(CHIPS)':
 C_PATH='@s9s_mb_2u_lib.s9s_mb_2u(sch_1):page473_i65@pure_quanta.q_cap(chips)';

PART_NAME
 C613 'Q_CAP_C0402-1UF,25V,10%,EMPTY,A':;

SECTION_NUMBER 1
 '@S9S_MB_2U_LIB.S9S_MB_2U(SCH_1):PAGE473_I68@PURE_QUANTA.Q_CAP(CHIPS)':
 C_PATH='@s9s_mb_2u_lib.s9s_mb_2u(sch_1):page473_i68@pure_quanta.q_cap(chips)';

PART_NAME
 U61 'NC7SB3157_SMLF-NC7SB3157P6X,NCA':;

SECTION_NUMBER 1
 '@S9S_MB_2U_LIB.S9S_MB_2U(SCH_1):PAGE465_I39@PURE_QUANTA.NC7SB3157(CHIPS)':
 C_PATH='@s9s_mb_2u_lib.s9s_mb_2u(sch_1):page465_i39@pure_quanta.nc7sb3157(chips)';

PART_NAME
 U60 'NC7SB3157_SMLF-NC7SB3157P6X,NCA':;

SECTION_NUMBER 1
 '@S9S_MB_2U_LIB.S9S_MB_2U(SCH_1):PAGE465_I34@PURE_QUANTA.NC7SB3157(CHIPS)':
 C_PATH='@s9s_mb_2u_lib.s9s_mb_2u(sch_1):page465_i34@pure_quanta.nc7sb3157(chips)';

PART_NAME
 R1876 'Q_RES_0402LF-220,1%,1/16W,CHIPA':;

SECTION_NUMBER 1
 '@S9S_MB_2U_LIB.S9S_MB_2U(SCH_1):PAGE465_I66@PURE_QUANTA.Q_RES(CHIPS)':
 C_PATH='@s9s_mb_2u_lib.s9s_mb_2u(sch_1):page465_i66@pure_quanta.q_res(chips)';

PART_NAME
 R1875 'Q_RES_0402LF-220,1%,1/16W,CHIPA':;

SECTION_NUMBER 1
 '@S9S_MB_2U_LIB.S9S_MB_2U(SCH_1):PAGE465_I67@PURE_QUANTA.Q_RES(CHIPS)':
 C_PATH='@s9s_mb_2u_lib.s9s_mb_2u(sch_1):page465_i67@pure_quanta.q_res(chips)';

PART_NAME
 R1874 'Q_RES_0402LF-220,1%,1/16W,CHIPA':;

SECTION_NUMBER 1
 '@S9S_MB_2U_LIB.S9S_MB_2U(SCH_1):PAGE465_I69@PURE_QUANTA.Q_RES(CHIPS)':
 C_PATH='@s9s_mb_2u_lib.s9s_mb_2u(sch_1):page465_i69@pure_quanta.q_res(chips)';

PART_NAME
 R1873 'Q_RES_0402LF-220,1%,1/16W,CHIPA':;

SECTION_NUMBER 1
 '@S9S_MB_2U_LIB.S9S_MB_2U(SCH_1):PAGE465_I68@PURE_QUANTA.Q_RES(CHIPS)':
 C_PATH='@s9s_mb_2u_lib.s9s_mb_2u(sch_1):page465_i68@pure_quanta.q_res(chips)';

PART_NAME
 R1872 'Q_RES_0402LF-56,1%,1/16W,CHIP,A':;

SECTION_NUMBER 1
 '@S9S_MB_2U_LIB.S9S_MB_2U(SCH_1):PAGE465_I65@PURE_QUANTA.Q_RES(CHIPS)':
 C_PATH='@s9s_mb_2u_lib.s9s_mb_2u(sch_1):page465_i65@pure_quanta.q_res(chips)';

PART_NAME
 R1871 'Q_RES_0402LF-56,1%,1/16W,CHIP,A':;

SECTION_NUMBER 1
 '@S9S_MB_2U_LIB.S9S_MB_2U(SCH_1):PAGE465_I64@PURE_QUANTA.Q_RES(CHIPS)':
 C_PATH='@s9s_mb_2u_lib.s9s_mb_2u(sch_1):page465_i64@pure_quanta.q_res(chips)';

PART_NAME
 R1870 'Q_RES_0402LF-56,1%,1/16W,CHIP,A':;

SECTION_NUMBER 1
 '@S9S_MB_2U_LIB.S9S_MB_2U(SCH_1):PAGE465_I63@PURE_QUANTA.Q_RES(CHIPS)':
 C_PATH='@s9s_mb_2u_lib.s9s_mb_2u(sch_1):page465_i63@pure_quanta.q_res(chips)';

PART_NAME
 R1869 'Q_RES_0402LF-56,1%,1/16W,CHIP,A':;

SECTION_NUMBER 1
 '@S9S_MB_2U_LIB.S9S_MB_2U(SCH_1):PAGE465_I62@PURE_QUANTA.Q_RES(CHIPS)':
 C_PATH='@s9s_mb_2u_lib.s9s_mb_2u(sch_1):page465_i62@pure_quanta.q_res(chips)';

PART_NAME
 R1868 'Q_RES_0402LF-56,1%,1/16W,CHIP,A':;

SECTION_NUMBER 1
 '@S9S_MB_2U_LIB.S9S_MB_2U(SCH_1):PAGE465_I61@PURE_QUANTA.Q_RES(CHIPS)':
 C_PATH='@s9s_mb_2u_lib.s9s_mb_2u(sch_1):page465_i61@pure_quanta.q_res(chips)';

PART_NAME
 R1750 'Q_RES_0402LF-1K,1%,1/16W,CHIP,A':;

SECTION_NUMBER 1
 '@S9S_MB_2U_LIB.S9S_MB_2U(SCH_1):PAGE465_I59@PURE_QUANTA.Q_RES(CHIPS)':
 C_PATH='@s9s_mb_2u_lib.s9s_mb_2u(sch_1):page465_i59@pure_quanta.q_res(chips)';

PART_NAME
 R1749 'Q_RES_0402LF-10K,1%,1/16W,EMPTA':;

SECTION_NUMBER 1
 '@S9S_MB_2U_LIB.S9S_MB_2U(SCH_1):PAGE465_I58@PURE_QUANTA.Q_RES(CHIPS)':
 C_PATH='@s9s_mb_2u_lib.s9s_mb_2u(sch_1):page465_i58@pure_quanta.q_res(chips)';

PART_NAME
 R1748 'Q_RES_0402LF-0,5%,1/16W,CHIP,CA':;

SECTION_NUMBER 1
 '@S9S_MB_2U_LIB.S9S_MB_2U(SCH_1):PAGE465_I54@PURE_QUANTA.Q_RES(CHIPS)':
 C_PATH='@s9s_mb_2u_lib.s9s_mb_2u(sch_1):page465_i54@pure_quanta.q_res(chips)';

PART_NAME
 R1479 'Q_RES_0402LF-33.2,1%,1/16W,CHIA':;

SECTION_NUMBER 1
 '@S9S_MB_2U_LIB.S9S_MB_2U(SCH_1):PAGE465_I52@PURE_QUANTA.Q_RES(CHIPS)':
 C_PATH='@s9s_mb_2u_lib.s9s_mb_2u(sch_1):page465_i52@pure_quanta.q_res(chips)';

PART_NAME
 R1215 'Q_RES_0402LF-49.9     ,1%  ,1/A':;

SECTION_NUMBER 1
 '@S9S_MB_2U_LIB.S9S_MB_2U(SCH_1):PAGE465_I38@PURE_QUANTA.Q_RES(CHIPS)':
 C_PATH='@s9s_mb_2u_lib.s9s_mb_2u(sch_1):page465_i38@pure_quanta.q_res(chips)';

PART_NAME
 R1214 'Q_RES_0402LF-0,5%,1/16W,CHIP,CA':;

SECTION_NUMBER 1
 '@S9S_MB_2U_LIB.S9S_MB_2U(SCH_1):PAGE465_I33@PURE_QUANTA.Q_RES(CHIPS)':
 C_PATH='@s9s_mb_2u_lib.s9s_mb_2u(sch_1):page465_i33@pure_quanta.q_res(chips)';

PART_NAME
 R1213 'Q_RES_0402LF-33,5%,1/16W,CHIP,A':;

SECTION_NUMBER 1
 '@S9S_MB_2U_LIB.S9S_MB_2U(SCH_1):PAGE465_I13@PURE_QUANTA.Q_RES(CHIPS)':
 C_PATH='@s9s_mb_2u_lib.s9s_mb_2u(sch_1):page465_i13@pure_quanta.q_res(chips)';

PART_NAME
 R1212 'Q_RES_0402LF-33,5%,1/16W,CHIP,A':;

SECTION_NUMBER 1
 '@S9S_MB_2U_LIB.S9S_MB_2U(SCH_1):PAGE465_I4@PURE_QUANTA.Q_RES(CHIPS)':
 C_PATH='@s9s_mb_2u_lib.s9s_mb_2u(sch_1):page465_i4@pure_quanta.q_res(chips)';

PART_NAME
 R1211 'Q_RES_0402LF-33,5%,1/16W,CHIP,A':;

SECTION_NUMBER 1
 '@S9S_MB_2U_LIB.S9S_MB_2U(SCH_1):PAGE465_I3@PURE_QUANTA.Q_RES(CHIPS)':
 C_PATH='@s9s_mb_2u_lib.s9s_mb_2u(sch_1):page465_i3@pure_quanta.q_res(chips)';

PART_NAME
 R1210 'Q_RES_0402LF-33,5%,1/16W,CHIP,A':;

SECTION_NUMBER 1
 '@S9S_MB_2U_LIB.S9S_MB_2U(SCH_1):PAGE465_I1@PURE_QUANTA.Q_RES(CHIPS)':
 C_PATH='@s9s_mb_2u_lib.s9s_mb_2u(sch_1):page465_i1@pure_quanta.q_res(chips)';

PART_NAME
 R1209 'Q_RES_0402LF-33,5%,1/16W,CHIP,A':;

SECTION_NUMBER 1
 '@S9S_MB_2U_LIB.S9S_MB_2U(SCH_1):PAGE465_I2@PURE_QUANTA.Q_RES(CHIPS)':
 C_PATH='@s9s_mb_2u_lib.s9s_mb_2u(sch_1):page465_i2@pure_quanta.q_res(chips)';

PART_NAME
 R1208 'Q_RES_0402LF-220,1%,1/16W,CHIPA':;

SECTION_NUMBER 1
 '@S9S_MB_2U_LIB.S9S_MB_2U(SCH_1):PAGE465_I16@PURE_QUANTA.Q_RES(CHIPS)':
 C_PATH='@s9s_mb_2u_lib.s9s_mb_2u(sch_1):page465_i16@pure_quanta.q_res(chips)';

PART_NAME
 C608 'Q_CAP_0402-0.1UF,25V,10%,X7R,CA':;

SECTION_NUMBER 1
 '@S9S_MB_2U_LIB.S9S_MB_2U(SCH_1):PAGE465_I43@PURE_QUANTA.Q_CAP(CHIPS)':
 C_PATH='@s9s_mb_2u_lib.s9s_mb_2u(sch_1):page465_i43@pure_quanta.q_cap(chips)';

PART_NAME
 C607 'Q_CAP_0402-0.1UF,25V,10%,X7R,CA':;

SECTION_NUMBER 1
 '@S9S_MB_2U_LIB.S9S_MB_2U(SCH_1):PAGE465_I36@PURE_QUANTA.Q_CAP(CHIPS)':
 C_PATH='@s9s_mb_2u_lib.s9s_mb_2u(sch_1):page465_i36@pure_quanta.q_cap(chips)';

PART_NAME
 C606 'Q_CAP_C0402-1UF,25V,10%,X6S,CHA':;

SECTION_NUMBER 1
 '@S9S_MB_2U_LIB.S9S_MB_2U(SCH_1):PAGE465_I45@PURE_QUANTA.Q_CAP(CHIPS)':
 C_PATH='@s9s_mb_2u_lib.s9s_mb_2u(sch_1):page465_i45@pure_quanta.q_cap(chips)';

PART_NAME
 C605 'Q_CAP_C0402-1UF,25V,10%,X6S,CHA':;

SECTION_NUMBER 1
 '@S9S_MB_2U_LIB.S9S_MB_2U(SCH_1):PAGE465_I37@PURE_QUANTA.Q_CAP(CHIPS)':
 C_PATH='@s9s_mb_2u_lib.s9s_mb_2u(sch_1):page465_i37@pure_quanta.q_cap(chips)';

PART_NAME
 U92 '74CBTLV3126PW-74CBTLV3126PW,SMB':;

SECTION_NUMBER 1
 '@S9S_MB_2U_LIB.S9S_MB_2U(SCH_1):PAGE505_I63@PURE_QUANTA.74CBTLV3126PW(CHIPS)':
 C_PATH='@s9s_mb_2u_lib.s9s_mb_2u(sch_1):page505_i63@pure_quanta.\74cbtlv3126pw\(c~
hips)';

PART_NAME
 U91 '74CBTLV3126PW-74CBTLV3126PW,SMB':;

SECTION_NUMBER 1
 '@S9S_MB_2U_LIB.S9S_MB_2U(SCH_1):PAGE505_I50@PURE_QUANTA.74CBTLV3126PW(CHIPS)':
 C_PATH='@s9s_mb_2u_lib.s9s_mb_2u(sch_1):page505_i50@pure_quanta.\74cbtlv3126pw\(c~
hips)';

PART_NAME
 U88 '74LVC1G126GW_SMLF-74LVC1G126GWA':;

SECTION_NUMBER 1
 '@S9S_MB_2U_LIB.S9S_MB_2U(SCH_1):PAGE505_I29@PURE_QUANTA.74LVC1G126GW(CHIPS)':
 C_PATH='@s9s_mb_2u_lib.s9s_mb_2u(sch_1):page505_i29@pure_quanta.\74lvc1g126gw\(ch~
ips)';

PART_NAME
 U78 '74LVC1G07GV-74LVC1G07GV,SMLF,IA':;

SECTION_NUMBER 1
 '@S9S_MB_2U_LIB.S9S_MB_2U(SCH_1):PAGE505_I69@PURE_QUANTA.74LVC1G07GV(CHIPS)':
 C_PATH='@s9s_mb_2u_lib.s9s_mb_2u(sch_1):page505_i69@pure_quanta.\74lvc1g07gv\(chi~
ps)';

PART_NAME
 U76 'SN74LVC1G17DCKR-SN74LVC1G17DCKA':;

SECTION_NUMBER 1
 '@S9S_MB_2U_LIB.S9S_MB_2U(SCH_1):PAGE505_I5@PURE_QUANTA.SN74LVC1G17DCKR(CHIPS)':
 C_PATH='@s9s_mb_2u_lib.s9s_mb_2u(sch_1):page505_i5@pure_quanta.sn74lvc1g17dckr(ch~
ips)';

PART_NAME
 R1904 'Q_RES_0402LF-100,1%,1/16W,CHIPA':;

SECTION_NUMBER 1
 '@S9S_MB_2U_LIB.S9S_MB_2U(SCH_1):PAGE505_I74@PURE_QUANTA.Q_RES(CHIPS)':
 C_PATH='@s9s_mb_2u_lib.s9s_mb_2u(sch_1):page505_i74@pure_quanta.q_res(chips)';

PART_NAME
 R1903 'Q_RES_0402LF-100,1%,1/16W,CHIPA':;

SECTION_NUMBER 1
 '@S9S_MB_2U_LIB.S9S_MB_2U(SCH_1):PAGE505_I76@PURE_QUANTA.Q_RES(CHIPS)':
 C_PATH='@s9s_mb_2u_lib.s9s_mb_2u(sch_1):page505_i76@pure_quanta.q_res(chips)';

PART_NAME
 R1902 'Q_RES_0402LF-100,1%,1/16W,CHIPA':;

SECTION_NUMBER 1
 '@S9S_MB_2U_LIB.S9S_MB_2U(SCH_1):PAGE505_I75@PURE_QUANTA.Q_RES(CHIPS)':
 C_PATH='@s9s_mb_2u_lib.s9s_mb_2u(sch_1):page505_i75@pure_quanta.q_res(chips)';

PART_NAME
 R1901 'Q_RES_0402LF-100,1%,1/16W,CHIPA':;

SECTION_NUMBER 1
 '@S9S_MB_2U_LIB.S9S_MB_2U(SCH_1):PAGE505_I72@PURE_QUANTA.Q_RES(CHIPS)':
 C_PATH='@s9s_mb_2u_lib.s9s_mb_2u(sch_1):page505_i72@pure_quanta.q_res(chips)';

PART_NAME
 R1900 'Q_RES_0402LF-100,1%,1/16W,CHIPA':;

SECTION_NUMBER 1
 '@S9S_MB_2U_LIB.S9S_MB_2U(SCH_1):PAGE505_I71@PURE_QUANTA.Q_RES(CHIPS)':
 C_PATH='@s9s_mb_2u_lib.s9s_mb_2u(sch_1):page505_i71@pure_quanta.q_res(chips)';

PART_NAME
 R1899 'Q_RES_0402LF-100,1%,1/16W,CHIPA':;

SECTION_NUMBER 1
 '@S9S_MB_2U_LIB.S9S_MB_2U(SCH_1):PAGE505_I70@PURE_QUANTA.Q_RES(CHIPS)':
 C_PATH='@s9s_mb_2u_lib.s9s_mb_2u(sch_1):page505_i70@pure_quanta.q_res(chips)';

PART_NAME
 R1825 'Q_RES_0402LF-10K,1%,1/16W,EMPTA':;

SECTION_NUMBER 1
 '@S9S_MB_2U_LIB.S9S_MB_2U(SCH_1):PAGE505_I68@PURE_QUANTA.Q_RES(CHIPS)':
 C_PATH='@s9s_mb_2u_lib.s9s_mb_2u(sch_1):page505_i68@pure_quanta.q_res(chips)';

PART_NAME
 R1699 'Q_RES_0402LF-33.2,1%,1/16W,CHIA':;

SECTION_NUMBER 1
 '@S9S_MB_2U_LIB.S9S_MB_2U(SCH_1):PAGE505_I67@PURE_QUANTA.Q_RES(CHIPS)':
 C_PATH='@s9s_mb_2u_lib.s9s_mb_2u(sch_1):page505_i67@pure_quanta.q_res(chips)';

PART_NAME
 R1599 'Q_RES_0402LF-33.2,1%,1/16W,CHIA':;

SECTION_NUMBER 1
 '@S9S_MB_2U_LIB.S9S_MB_2U(SCH_1):PAGE505_I23@PURE_QUANTA.Q_RES(CHIPS)':
 C_PATH='@s9s_mb_2u_lib.s9s_mb_2u(sch_1):page505_i23@pure_quanta.q_res(chips)';

PART_NAME
 R1598 'Q_RES_0402LF-33.2,1%,1/16W,CHIA':;

SECTION_NUMBER 1
 '@S9S_MB_2U_LIB.S9S_MB_2U(SCH_1):PAGE505_I33@PURE_QUANTA.Q_RES(CHIPS)':
 C_PATH='@s9s_mb_2u_lib.s9s_mb_2u(sch_1):page505_i33@pure_quanta.q_res(chips)';

PART_NAME
 R1597 'Q_RES_0402LF-4.7K,1%,1/16W,EMPA':;

SECTION_NUMBER 1
 '@S9S_MB_2U_LIB.S9S_MB_2U(SCH_1):PAGE505_I21@PURE_QUANTA.Q_RES(CHIPS)':
 C_PATH='@s9s_mb_2u_lib.s9s_mb_2u(sch_1):page505_i21@pure_quanta.q_res(chips)';

PART_NAME
 R1596 'Q_RES_0402LF-10K,1%,1/16W,CHIPA':;

SECTION_NUMBER 1
 '@S9S_MB_2U_LIB.S9S_MB_2U(SCH_1):PAGE505_I27@PURE_QUANTA.Q_RES(CHIPS)':
 C_PATH='@s9s_mb_2u_lib.s9s_mb_2u(sch_1):page505_i27@pure_quanta.q_res(chips)';

PART_NAME
 R1511 'Q_RES_0402LF-33.2,1%,1/16W,CHIA':;

SECTION_NUMBER 1
 '@S9S_MB_2U_LIB.S9S_MB_2U(SCH_1):PAGE505_I18@PURE_QUANTA.Q_RES(CHIPS)':
 C_PATH='@s9s_mb_2u_lib.s9s_mb_2u(sch_1):page505_i18@pure_quanta.q_res(chips)';

PART_NAME
 R1510 'Q_RES_0402LF-33.2,1%,1/16W,CHIA':;

SECTION_NUMBER 1
 '@S9S_MB_2U_LIB.S9S_MB_2U(SCH_1):PAGE505_I15@PURE_QUANTA.Q_RES(CHIPS)':
 C_PATH='@s9s_mb_2u_lib.s9s_mb_2u(sch_1):page505_i15@pure_quanta.q_res(chips)';

PART_NAME
 R1509 'Q_RES_0402LF-33.2,1%,1/16W,CHIA':;

SECTION_NUMBER 1
 '@S9S_MB_2U_LIB.S9S_MB_2U(SCH_1):PAGE505_I4@PURE_QUANTA.Q_RES(CHIPS)':
 C_PATH='@s9s_mb_2u_lib.s9s_mb_2u(sch_1):page505_i4@pure_quanta.q_res(chips)';

PART_NAME
 R1508 'Q_RES_0402LF-33.2,1%,1/16W,CHIA':;

SECTION_NUMBER 1
 '@S9S_MB_2U_LIB.S9S_MB_2U(SCH_1):PAGE505_I7@PURE_QUANTA.Q_RES(CHIPS)':
 C_PATH='@s9s_mb_2u_lib.s9s_mb_2u(sch_1):page505_i7@pure_quanta.q_res(chips)';

PART_NAME
 R1507 'Q_RES_0402LF-33.2,1%,1/16W,CHIA':;

SECTION_NUMBER 1
 '@S9S_MB_2U_LIB.S9S_MB_2U(SCH_1):PAGE505_I8@PURE_QUANTA.Q_RES(CHIPS)':
 C_PATH='@s9s_mb_2u_lib.s9s_mb_2u(sch_1):page505_i8@pure_quanta.q_res(chips)';

PART_NAME
 R1506 'Q_RES_0402LF-33.2,1%,1/16W,CHIA':;

SECTION_NUMBER 1
 '@S9S_MB_2U_LIB.S9S_MB_2U(SCH_1):PAGE505_I9@PURE_QUANTA.Q_RES(CHIPS)':
 C_PATH='@s9s_mb_2u_lib.s9s_mb_2u(sch_1):page505_i9@pure_quanta.q_res(chips)';

PART_NAME
 R1501 'Q_RES_0402LF-33.2,1%,1/16W,CHIA':;

SECTION_NUMBER 1
 '@S9S_MB_2U_LIB.S9S_MB_2U(SCH_1):PAGE505_I64@PURE_QUANTA.Q_RES(CHIPS)':
 C_PATH='@s9s_mb_2u_lib.s9s_mb_2u(sch_1):page505_i64@pure_quanta.q_res(chips)';

PART_NAME
 C1299 'Q_CAP_0402-0.1UF,25V,10%,X7R,CA':;

SECTION_NUMBER 1
 '@S9S_MB_2U_LIB.S9S_MB_2U(SCH_1):PAGE505_I60@PURE_QUANTA.Q_CAP(CHIPS)':
 C_PATH='@s9s_mb_2u_lib.s9s_mb_2u(sch_1):page505_i60@pure_quanta.q_cap(chips)';

PART_NAME
 C1298 'Q_CAP_0402-0.1UF,25V,10%,X7R,CA':;

SECTION_NUMBER 1
 '@S9S_MB_2U_LIB.S9S_MB_2U(SCH_1):PAGE505_I51@PURE_QUANTA.Q_CAP(CHIPS)':
 C_PATH='@s9s_mb_2u_lib.s9s_mb_2u(sch_1):page505_i51@pure_quanta.q_cap(chips)';

PART_NAME
 C1176 'Q_CAP_0402-0.1UF,25V,10%,X7R,CA':;

SECTION_NUMBER 1
 '@S9S_MB_2U_LIB.S9S_MB_2U(SCH_1):PAGE505_I32@PURE_QUANTA.Q_CAP(CHIPS)':
 C_PATH='@s9s_mb_2u_lib.s9s_mb_2u(sch_1):page505_i32@pure_quanta.q_cap(chips)';

PART_NAME
 C1174 'Q_CAP_0402-0.1UF,25V,10%,X7R,CA':;

SECTION_NUMBER 1
 '@S9S_MB_2U_LIB.S9S_MB_2U(SCH_1):PAGE505_I3@PURE_QUANTA.Q_CAP(CHIPS)':
 C_PATH='@s9s_mb_2u_lib.s9s_mb_2u(sch_1):page505_i3@pure_quanta.q_cap(chips)';

PART_NAME
 C584 'Q_CAP_0402-0.1UF,25V,10%,X7R,CA':;

SECTION_NUMBER 1
 '@S9S_MB_2U_LIB.S9S_MB_2U(SCH_1):PAGE505_I38@PURE_QUANTA.Q_CAP(CHIPS)':
 C_PATH='@s9s_mb_2u_lib.s9s_mb_2u(sch_1):page505_i38@pure_quanta.q_cap(chips)';

PART_NAME
 U53 'SN74LVC1G08DBVR_SMLF-SN74LVC1GA':;

SECTION_NUMBER 1
 '@S9S_MB_2U_LIB.S9S_MB_2U(SCH_1):PAGE508_I12@PURE_QUANTA.SN74LVC1G08DBVR(CHIPS)':
 C_PATH='@s9s_mb_2u_lib.s9s_mb_2u(sch_1):page508_i12@pure_quanta.sn74lvc1g08dbvr(c~
hips)';

PART_NAME
 U52 'APX80929SAG7-APX809-29SAG-7,SMA':;

SECTION_NUMBER 1
 '@S9S_MB_2U_LIB.S9S_MB_2U(SCH_1):PAGE508_I46@PURE_QUANTA.APX80929SAG7(CHIPS)':
 C_PATH='@s9s_mb_2u_lib.s9s_mb_2u(sch_1):page508_i46@pure_quanta.apx80929sag7(chip~
s)';

PART_NAME
 U51 'PCA9555PW_SMLF-PCA9555PW,IC,TMA':;

SECTION_NUMBER 1
 '@S9S_MB_2U_LIB.S9S_MB_2U(SCH_1):PAGE508_I28@PURE_QUANTA.PCA9555PW(CHIPS)':
 C_PATH='@s9s_mb_2u_lib.s9s_mb_2u(sch_1):page508_i28@pure_quanta.pca9555pw(chips)';

PART_NAME
 U50 'SN74LVC1G08DBVR_SMLF-SN74LVC1GA':;

SECTION_NUMBER 1
 '@S9S_MB_2U_LIB.S9S_MB_2U(SCH_1):PAGE508_I73@PURE_QUANTA.SN74LVC1G08DBVR(CHIPS)':
 C_PATH='@s9s_mb_2u_lib.s9s_mb_2u(sch_1):page508_i73@pure_quanta.sn74lvc1g08dbvr(c~
hips)';

PART_NAME
 U49 'MOSFET_N_SMLF-BSS138K,BSS138K,A':;

SECTION_NUMBER 1
 '@S9S_MB_2U_LIB.S9S_MB_2U(SCH_1):PAGE508_I76@PURE_QUANTA.MOSFET_N(CHIPS)':
 C_PATH='@s9s_mb_2u_lib.s9s_mb_2u(sch_1):page508_i76@pure_quanta.mosfet_n(chips)';

PART_NAME
 R1921 'Q_RES_0402LF-33,5%,1/16W,CHIP,A':;

SECTION_NUMBER 1
 '@S9S_MB_2U_LIB.S9S_MB_2U(SCH_1):PAGE508_I64@PURE_QUANTA.Q_RES(CHIPS)':
 C_PATH='@s9s_mb_2u_lib.s9s_mb_2u(sch_1):page508_i64@pure_quanta.q_res(chips)';

PART_NAME
 R1133 'Q_RES_0402LF-10K,1%,1/16W,CHIPA':;

SECTION_NUMBER 1
 '@S9S_MB_2U_LIB.S9S_MB_2U(SCH_1):PAGE508_I21@PURE_QUANTA.Q_RES(CHIPS)':
 C_PATH='@s9s_mb_2u_lib.s9s_mb_2u(sch_1):page508_i21@pure_quanta.q_res(chips)';

PART_NAME
 R1132 'Q_RES_0402LF-1K,5%,1/16W,EMPTYA':;

SECTION_NUMBER 1
 '@S9S_MB_2U_LIB.S9S_MB_2U(SCH_1):PAGE508_I18@PURE_QUANTA.Q_RES(CHIPS)':
 C_PATH='@s9s_mb_2u_lib.s9s_mb_2u(sch_1):page508_i18@pure_quanta.q_res(chips)';

PART_NAME
 R1131 'Q_RES_0402LF-33,5%,1/16W,CHIP,A':;

SECTION_NUMBER 1
 '@S9S_MB_2U_LIB.S9S_MB_2U(SCH_1):PAGE508_I31@PURE_QUANTA.Q_RES(CHIPS)':
 C_PATH='@s9s_mb_2u_lib.s9s_mb_2u(sch_1):page508_i31@pure_quanta.q_res(chips)';

PART_NAME
 R1130 'Q_RES_0402LF-33,5%,1/16W,CHIP,A':;

SECTION_NUMBER 1
 '@S9S_MB_2U_LIB.S9S_MB_2U(SCH_1):PAGE508_I30@PURE_QUANTA.Q_RES(CHIPS)':
 C_PATH='@s9s_mb_2u_lib.s9s_mb_2u(sch_1):page508_i30@pure_quanta.q_res(chips)';

PART_NAME
 R1129 'Q_RES_0402LF-1K,5%,1/16W,CHIP,A':;

SECTION_NUMBER 1
 '@S9S_MB_2U_LIB.S9S_MB_2U(SCH_1):PAGE508_I72@PURE_QUANTA.Q_RES(CHIPS)':
 C_PATH='@s9s_mb_2u_lib.s9s_mb_2u(sch_1):page508_i72@pure_quanta.q_res(chips)';

PART_NAME
 R1128 'Q_RES_0402LF-1K,5%,1/16W,CHIP,A':;

SECTION_NUMBER 1
 '@S9S_MB_2U_LIB.S9S_MB_2U(SCH_1):PAGE508_I40@PURE_QUANTA.Q_RES(CHIPS)':
 C_PATH='@s9s_mb_2u_lib.s9s_mb_2u(sch_1):page508_i40@pure_quanta.q_res(chips)';

PART_NAME
 R1127 'Q_RES_0402LF-1K,5%,1/16W,EMPTYA':;

SECTION_NUMBER 1
 '@S9S_MB_2U_LIB.S9S_MB_2U(SCH_1):PAGE508_I36@PURE_QUANTA.Q_RES(CHIPS)':
 C_PATH='@s9s_mb_2u_lib.s9s_mb_2u(sch_1):page508_i36@pure_quanta.q_res(chips)';

PART_NAME
 R1126 'Q_RES_0402LF-1K,5%,1/16W,CHIP,A':;

SECTION_NUMBER 1
 '@S9S_MB_2U_LIB.S9S_MB_2U(SCH_1):PAGE508_I42@PURE_QUANTA.Q_RES(CHIPS)':
 C_PATH='@s9s_mb_2u_lib.s9s_mb_2u(sch_1):page508_i42@pure_quanta.q_res(chips)';

PART_NAME
 R1125 'Q_RES_0402LF-1K,5%,1/16W,EMPTYA':;

SECTION_NUMBER 1
 '@S9S_MB_2U_LIB.S9S_MB_2U(SCH_1):PAGE508_I37@PURE_QUANTA.Q_RES(CHIPS)':
 C_PATH='@s9s_mb_2u_lib.s9s_mb_2u(sch_1):page508_i37@pure_quanta.q_res(chips)';

PART_NAME
 R1124 'Q_RES_0402LF-1K,5%,1/16W,CHIP,A':;

SECTION_NUMBER 1
 '@S9S_MB_2U_LIB.S9S_MB_2U(SCH_1):PAGE508_I45@PURE_QUANTA.Q_RES(CHIPS)':
 C_PATH='@s9s_mb_2u_lib.s9s_mb_2u(sch_1):page508_i45@pure_quanta.q_res(chips)';

PART_NAME
 R1123 'Q_RES_0402LF-1K,5%,1/16W,EMPTYA':;

SECTION_NUMBER 1
 '@S9S_MB_2U_LIB.S9S_MB_2U(SCH_1):PAGE508_I39@PURE_QUANTA.Q_RES(CHIPS)':
 C_PATH='@s9s_mb_2u_lib.s9s_mb_2u(sch_1):page508_i39@pure_quanta.q_res(chips)';

PART_NAME
 Q24 '2N7002A7-2N7002A-7,SMLF,IC,BAMA':;

SECTION_NUMBER 1
 '@S9S_MB_2U_LIB.S9S_MB_2U(SCH_1):PAGE508_I15@PURE_QUANTA.2N7002A7(CHIPS)':
 C_PATH='@s9s_mb_a_lib.s9s_mb_a(sch_1):page508_i15@pure_quanta.\2n7002a7\(chips)~
';

PART_NAME
 Q23 '2N7002A7-2N7002A-7,SMLF,IC,BAMA':;

SECTION_NUMBER 1
 '@S9S_MB_2U_LIB.S9S_MB_2U(SCH_1):PAGE508_I23@PURE_QUANTA.2N7002A7(CHIPS)':
 C_PATH='@s9s_mb_a_lib.s9s_mb_a(sch_1):page508_i23@pure_quanta.\2n7002a7\(chips)~
';

PART_NAME
 C581 'Q_CAP_0402-0.1UF,25V,10%,X7R,CA':;

SECTION_NUMBER 1
 '@S9S_MB_2U_LIB.S9S_MB_2U(SCH_1):PAGE508_I10@PURE_QUANTA.Q_CAP(CHIPS)':
 C_PATH='@s9s_mb_2u_lib.s9s_mb_2u(sch_1):page508_i10@pure_quanta.q_cap(chips)';

PART_NAME
 C580 'Q_CAP_0402-0.1UF,25V,10%,X7R,CA':;

SECTION_NUMBER 1
 '@S9S_MB_2U_LIB.S9S_MB_2U(SCH_1):PAGE508_I48@PURE_QUANTA.Q_CAP(CHIPS)':
 C_PATH='@s9s_mb_2u_lib.s9s_mb_2u(sch_1):page508_i48@pure_quanta.q_cap(chips)';

PART_NAME
 C579 'Q_CAP_0402-0.1UF,25V,10%,X7R,CA':;

SECTION_NUMBER 1
 '@S9S_MB_2U_LIB.S9S_MB_2U(SCH_1):PAGE508_I26@PURE_QUANTA.Q_CAP(CHIPS)':
 C_PATH='@s9s_mb_2u_lib.s9s_mb_2u(sch_1):page508_i26@pure_quanta.q_cap(chips)';

PART_NAME
 C578 'Q_CAP_0402-0.1UF,25V,10%,X7R,CA':;

SECTION_NUMBER 1
 '@S9S_MB_2U_LIB.S9S_MB_2U(SCH_1):PAGE508_I68@PURE_QUANTA.Q_CAP(CHIPS)':
 C_PATH='@s9s_mb_2u_lib.s9s_mb_2u(sch_1):page508_i68@pure_quanta.q_cap(chips)';

PART_NAME
 U48 'SN74LVC1G08DBVR_SMLF-SN74LVC1GA':;

SECTION_NUMBER 1
 '@S9S_MB_2U_LIB.S9S_MB_2U(SCH_1):PAGE456_I14@PURE_QUANTA.SN74LVC1G08DBVR(CHIPS)':
 C_PATH='@s9s_mb_2u_lib.s9s_mb_2u(sch_1):page456_i14@pure_quanta.sn74lvc1g08dbvr(c~
hips)';

PART_NAME
 U47 'APX80929SAG7-APX809-29SAG-7,SMA':;

SECTION_NUMBER 1
 '@S9S_MB_2U_LIB.S9S_MB_2U(SCH_1):PAGE456_I26@PURE_QUANTA.APX80929SAG7(CHIPS)':
 C_PATH='@s9s_mb_2u_lib.s9s_mb_2u(sch_1):page456_i26@pure_quanta.apx80929sag7(chip~
s)';

PART_NAME
 U46 'PCA9555PW_SMLF-PCA9555PW,IC,TMA':;

SECTION_NUMBER 1
 '@S9S_MB_2U_LIB.S9S_MB_2U(SCH_1):PAGE456_I21@PURE_QUANTA.PCA9555PW(CHIPS)':
 C_PATH='@s9s_mb_2u_lib.s9s_mb_2u(sch_1):page456_i21@pure_quanta.pca9555pw(chips)';

PART_NAME
 U45 'SN74LVC1G08DBVR_SMLF-SN74LVC1GA':;

SECTION_NUMBER 1
 '@S9S_MB_2U_LIB.S9S_MB_2U(SCH_1):PAGE456_I73@PURE_QUANTA.SN74LVC1G08DBVR(CHIPS)':
 C_PATH='@s9s_mb_2u_lib.s9s_mb_2u(sch_1):page456_i73@pure_quanta.sn74lvc1g08dbvr(c~
hips)';

PART_NAME
 U44 'MOSFET_N_SMLF-BSS138K,BSS138K,A':;

SECTION_NUMBER 1
 '@S9S_MB_2U_LIB.S9S_MB_2U(SCH_1):PAGE456_I82@PURE_QUANTA.MOSFET_N(CHIPS)':
 C_PATH='@s9s_mb_2u_lib.s9s_mb_2u(sch_1):page456_i82@pure_quanta.mosfet_n(chips)';

PART_NAME
 R1920 'Q_RES_0402LF-33,5%,1/16W,CHIP,A':;

SECTION_NUMBER 1
 '@S9S_MB_2U_LIB.S9S_MB_2U(SCH_1):PAGE456_I62@PURE_QUANTA.Q_RES(CHIPS)':
 C_PATH='@s9s_mb_2u_lib.s9s_mb_2u(sch_1):page456_i62@pure_quanta.q_res(chips)';

PART_NAME
 R1122 'Q_RES_0402LF-10K,1%,1/16W,CHIPA':;

SECTION_NUMBER 1
 '@S9S_MB_2U_LIB.S9S_MB_2U(SCH_1):PAGE456_I35@PURE_QUANTA.Q_RES(CHIPS)':
 C_PATH='@s9s_mb_2u_lib.s9s_mb_2u(sch_1):page456_i35@pure_quanta.q_res(chips)';

PART_NAME
 R1121 'Q_RES_0402LF-1K,5%,1/16W,EMPTYA':;

SECTION_NUMBER 1
 '@S9S_MB_2U_LIB.S9S_MB_2U(SCH_1):PAGE456_I16@PURE_QUANTA.Q_RES(CHIPS)':
 C_PATH='@s9s_mb_2u_lib.s9s_mb_2u(sch_1):page456_i16@pure_quanta.q_res(chips)';

PART_NAME
 R1120 'Q_RES_0402LF-33,5%,1/16W,CHIP,A':;

SECTION_NUMBER 1
 '@S9S_MB_2U_LIB.S9S_MB_2U(SCH_1):PAGE456_I22@PURE_QUANTA.Q_RES(CHIPS)':
 C_PATH='@s9s_mb_2u_lib.s9s_mb_2u(sch_1):page456_i22@pure_quanta.q_res(chips)';

PART_NAME
 R1119 'Q_RES_0402LF-33,5%,1/16W,CHIP,A':;

SECTION_NUMBER 1
 '@S9S_MB_2U_LIB.S9S_MB_2U(SCH_1):PAGE456_I23@PURE_QUANTA.Q_RES(CHIPS)':
 C_PATH='@s9s_mb_2u_lib.s9s_mb_2u(sch_1):page456_i23@pure_quanta.q_res(chips)';

PART_NAME
 R1118 'Q_RES_0402LF-1K,5%,1/16W,CHIP,A':;

SECTION_NUMBER 1
 '@S9S_MB_2U_LIB.S9S_MB_2U(SCH_1):PAGE456_I79@PURE_QUANTA.Q_RES(CHIPS)':
 C_PATH='@s9s_mb_2u_lib.s9s_mb_2u(sch_1):page456_i79@pure_quanta.q_res(chips)';

PART_NAME
 R1117 'Q_RES_0402LF-1K,5%,1/16W,CHIP,A':;

SECTION_NUMBER 1
 '@S9S_MB_2U_LIB.S9S_MB_2U(SCH_1):PAGE456_I46@PURE_QUANTA.Q_RES(CHIPS)':
 C_PATH='@s9s_mb_2u_lib.s9s_mb_2u(sch_1):page456_i46@pure_quanta.q_res(chips)';

PART_NAME
 R1116 'Q_RES_0402LF-1K,5%,1/16W,EMPTYA':;

SECTION_NUMBER 1
 '@S9S_MB_2U_LIB.S9S_MB_2U(SCH_1):PAGE456_I45@PURE_QUANTA.Q_RES(CHIPS)':
 C_PATH='@s9s_mb_2u_lib.s9s_mb_2u(sch_1):page456_i45@pure_quanta.q_res(chips)';

PART_NAME
 R1115 'Q_RES_0402LF-1K,5%,1/16W,CHIP,A':;

SECTION_NUMBER 1
 '@S9S_MB_2U_LIB.S9S_MB_2U(SCH_1):PAGE456_I49@PURE_QUANTA.Q_RES(CHIPS)':
 C_PATH='@s9s_mb_2u_lib.s9s_mb_2u(sch_1):page456_i49@pure_quanta.q_res(chips)';

PART_NAME
 R1114 'Q_RES_0402LF-1K,5%,1/16W,EMPTYA':;

SECTION_NUMBER 1
 '@S9S_MB_2U_LIB.S9S_MB_2U(SCH_1):PAGE456_I47@PURE_QUANTA.Q_RES(CHIPS)':
 C_PATH='@s9s_mb_2u_lib.s9s_mb_2u(sch_1):page456_i47@pure_quanta.q_res(chips)';

PART_NAME
 R1113 'Q_RES_0402LF-1K,5%,1/16W,CHIP,A':;

SECTION_NUMBER 1
 '@S9S_MB_2U_LIB.S9S_MB_2U(SCH_1):PAGE456_I50@PURE_QUANTA.Q_RES(CHIPS)':
 C_PATH='@s9s_mb_2u_lib.s9s_mb_2u(sch_1):page456_i50@pure_quanta.q_res(chips)';

PART_NAME
 R1112 'Q_RES_0402LF-1K,5%,1/16W,EMPTYA':;

SECTION_NUMBER 1
 '@S9S_MB_2U_LIB.S9S_MB_2U(SCH_1):PAGE456_I48@PURE_QUANTA.Q_RES(CHIPS)':
 C_PATH='@s9s_mb_2u_lib.s9s_mb_2u(sch_1):page456_i48@pure_quanta.q_res(chips)';

PART_NAME
 Q22 '2N7002A7-2N7002A-7,SMLF,IC,BAMA':;

SECTION_NUMBER 1
 '@S9S_MB_2U_LIB.S9S_MB_2U(SCH_1):PAGE456_I33@PURE_QUANTA.2N7002A7(CHIPS)':
 C_PATH='@s9s_mb_a_lib.s9s_mb_a(sch_1):page456_i33@pure_quanta.\2n7002a7\(chips)~
';

PART_NAME
 Q21 '2N7002A7-2N7002A-7,SMLF,IC,BAMA':;

SECTION_NUMBER 1
 '@S9S_MB_2U_LIB.S9S_MB_2U(SCH_1):PAGE456_I36@PURE_QUANTA.2N7002A7(CHIPS)':
 C_PATH='@s9s_mb_a_lib.s9s_mb_a(sch_1):page456_i36@pure_quanta.\2n7002a7\(chips)~
';

PART_NAME
 C577 'Q_CAP_0402-0.1UF,25V,10%,X7R,CA':;

SECTION_NUMBER 1
 '@S9S_MB_2U_LIB.S9S_MB_2U(SCH_1):PAGE456_I11@PURE_QUANTA.Q_CAP(CHIPS)':
 C_PATH='@s9s_mb_2u_lib.s9s_mb_2u(sch_1):page456_i11@pure_quanta.q_cap(chips)';

PART_NAME
 C576 'Q_CAP_0402-0.1UF,25V,10%,X7R,CA':;

SECTION_NUMBER 1
 '@S9S_MB_2U_LIB.S9S_MB_2U(SCH_1):PAGE456_I28@PURE_QUANTA.Q_CAP(CHIPS)':
 C_PATH='@s9s_mb_2u_lib.s9s_mb_2u(sch_1):page456_i28@pure_quanta.q_cap(chips)';

PART_NAME
 C575 'Q_CAP_0402-0.1UF,25V,10%,X7R,CA':;

SECTION_NUMBER 1
 '@S9S_MB_2U_LIB.S9S_MB_2U(SCH_1):PAGE456_I19@PURE_QUANTA.Q_CAP(CHIPS)':
 C_PATH='@s9s_mb_2u_lib.s9s_mb_2u(sch_1):page456_i19@pure_quanta.q_cap(chips)';

PART_NAME
 C574 'Q_CAP_0402-0.1UF,25V,10%,X7R,CA':;

SECTION_NUMBER 1
 '@S9S_MB_2U_LIB.S9S_MB_2U(SCH_1):PAGE456_I77@PURE_QUANTA.Q_CAP(CHIPS)':
 C_PATH='@s9s_mb_2u_lib.s9s_mb_2u(sch_1):page456_i77@pure_quanta.q_cap(chips)';

PART_NAME
 U31 'PCA9617ADP-PCA9617ADP,SMLF,IC,A':;

SECTION_NUMBER 1
 '@S9S_MB_2U_LIB.S9S_MB_2U(SCH_1):PAGE558_I46@PURE_QUANTA.PCA9617ADP(CHIPS)':
 C_PATH='@s9s_mb_a_lib.s9s_mb_a(sch_1):page558_i46@pure_quanta.pca9617adp(chips)~
';

PART_NAME
 U30 'PCA9617ADP-PCA9617ADP,SMLF,IC,A':;

SECTION_NUMBER 1
 '@S9S_MB_2U_LIB.S9S_MB_2U(SCH_1):PAGE558_I16@PURE_QUANTA.PCA9617ADP(CHIPS)':
 C_PATH='@s9s_mb_a_lib.s9s_mb_a(sch_1):page558_i16@pure_quanta.pca9617adp(chips)~
';

PART_NAME
 R1830 'Q_RES_0402LF-0,5%,1/16W,EMPTY,A':;

SECTION_NUMBER 1
 '@S9S_MB_2U_LIB.S9S_MB_2U(SCH_1):PAGE558_I77@PURE_QUANTA.Q_RES(CHIPS)':
 C_PATH='@s9s_mb_2u_lib.s9s_mb_2u(sch_1):page558_i77@pure_quanta.q_res(chips)';

PART_NAME
 R1829 'Q_RES_0402LF-0,5%,1/16W,EMPTY,A':;

SECTION_NUMBER 1
 '@S9S_MB_2U_LIB.S9S_MB_2U(SCH_1):PAGE558_I76@PURE_QUANTA.Q_RES(CHIPS)':
 C_PATH='@s9s_mb_2u_lib.s9s_mb_2u(sch_1):page558_i76@pure_quanta.q_res(chips)';

PART_NAME
 R1760 'Q_RES_0402LF-0,5%,1/16W,EMPTY,A':;

SECTION_NUMBER 1
 '@S9S_MB_2U_LIB.S9S_MB_2U(SCH_1):PAGE558_I74@PURE_QUANTA.Q_RES(CHIPS)':
 C_PATH='@s9s_mb_2u_lib.s9s_mb_2u(sch_1):page558_i74@pure_quanta.q_res(chips)';

PART_NAME
 R1759 'Q_RES_0402LF-0,5%,1/16W,EMPTY,A':;

SECTION_NUMBER 1
 '@S9S_MB_2U_LIB.S9S_MB_2U(SCH_1):PAGE558_I75@PURE_QUANTA.Q_RES(CHIPS)':
 C_PATH='@s9s_mb_2u_lib.s9s_mb_2u(sch_1):page558_i75@pure_quanta.q_res(chips)';

PART_NAME
 R1648 'Q_RES_0402LF-0,5%,1/16W,EMPTY,A':;

SECTION_NUMBER 1
 '@S9S_MB_2U_LIB.S9S_MB_2U(SCH_1):PAGE558_I68@PURE_QUANTA.Q_RES(CHIPS)':
 C_PATH='@s9s_mb_2u_lib.s9s_mb_2u(sch_1):page558_i68@pure_quanta.q_res(chips)';

PART_NAME
 R996 'Q_RES_0402LF-33.2,1%,1/16W,CHIA':;

SECTION_NUMBER 1
 '@S9S_MB_2U_LIB.S9S_MB_2U(SCH_1):PAGE558_I65@PURE_QUANTA.Q_RES(CHIPS)':
 C_PATH='@s9s_mb_2u_lib.s9s_mb_2u(sch_1):page558_i65@pure_quanta.q_res(chips)';

PART_NAME
 R995 'Q_RES_0402LF-33.2,1%,1/16W,CHIA':;

SECTION_NUMBER 1
 '@S9S_MB_2U_LIB.S9S_MB_2U(SCH_1):PAGE558_I64@PURE_QUANTA.Q_RES(CHIPS)':
 C_PATH='@s9s_mb_2u_lib.s9s_mb_2u(sch_1):page558_i64@pure_quanta.q_res(chips)';

PART_NAME
 R994 'Q_RES_0402LF-33.2,1%,1/16W,CHIA':;

SECTION_NUMBER 1
 '@S9S_MB_2U_LIB.S9S_MB_2U(SCH_1):PAGE558_I44@PURE_QUANTA.Q_RES(CHIPS)':
 C_PATH='@s9s_mb_2u_lib.s9s_mb_2u(sch_1):page558_i44@pure_quanta.q_res(chips)';

PART_NAME
 R993 'Q_RES_0402LF-33.2,1%,1/16W,CHIA':;

SECTION_NUMBER 1
 '@S9S_MB_2U_LIB.S9S_MB_2U(SCH_1):PAGE558_I45@PURE_QUANTA.Q_RES(CHIPS)':
 C_PATH='@s9s_mb_2u_lib.s9s_mb_2u(sch_1):page558_i45@pure_quanta.q_res(chips)';

PART_NAME
 R980 'Q_RES_0402LF-412,1%,1/16W,CHIPA':;

SECTION_NUMBER 1
 '@S9S_MB_2U_LIB.S9S_MB_2U(SCH_1):PAGE558_I49@PURE_QUANTA.Q_RES(CHIPS)':
 C_PATH='@s9s_mb_2u_lib.s9s_mb_2u(sch_1):page558_i49@pure_quanta.q_res(chips)';

PART_NAME
 R979 'Q_RES_0402LF-412,1%,1/16W,CHIPA':;

SECTION_NUMBER 1
 '@S9S_MB_2U_LIB.S9S_MB_2U(SCH_1):PAGE558_I35@PURE_QUANTA.Q_RES(CHIPS)':
 C_PATH='@s9s_mb_2u_lib.s9s_mb_2u(sch_1):page558_i35@pure_quanta.q_res(chips)';

PART_NAME
 R978 'Q_RES_0402LF-412,1%,1/16W,CHIPA':;

SECTION_NUMBER 1
 '@S9S_MB_2U_LIB.S9S_MB_2U(SCH_1):PAGE558_I51@PURE_QUANTA.Q_RES(CHIPS)':
 C_PATH='@s9s_mb_2u_lib.s9s_mb_2u(sch_1):page558_i51@pure_quanta.q_res(chips)';

PART_NAME
 R977 'Q_RES_0402LF-412,1%,1/16W,CHIPA':;

SECTION_NUMBER 1
 '@S9S_MB_2U_LIB.S9S_MB_2U(SCH_1):PAGE558_I41@PURE_QUANTA.Q_RES(CHIPS)':
 C_PATH='@s9s_mb_2u_lib.s9s_mb_2u(sch_1):page558_i41@pure_quanta.q_res(chips)';

PART_NAME
 R976 'Q_RES_0402LF-33.2,1%,1/16W,CHIA':;

SECTION_NUMBER 1
 '@S9S_MB_2U_LIB.S9S_MB_2U(SCH_1):PAGE558_I60@PURE_QUANTA.Q_RES(CHIPS)':
 C_PATH='@s9s_mb_2u_lib.s9s_mb_2u(sch_1):page558_i60@pure_quanta.q_res(chips)';

PART_NAME
 R975 'Q_RES_0402LF-33.2,1%,1/16W,CHIA':;

SECTION_NUMBER 1
 '@S9S_MB_2U_LIB.S9S_MB_2U(SCH_1):PAGE558_I58@PURE_QUANTA.Q_RES(CHIPS)':
 C_PATH='@s9s_mb_2u_lib.s9s_mb_2u(sch_1):page558_i58@pure_quanta.q_res(chips)';

PART_NAME
 R974 'Q_RES_0402LF-33.2,1%,1/16W,CHIA':;

SECTION_NUMBER 1
 '@S9S_MB_2U_LIB.S9S_MB_2U(SCH_1):PAGE558_I42@PURE_QUANTA.Q_RES(CHIPS)':
 C_PATH='@s9s_mb_2u_lib.s9s_mb_2u(sch_1):page558_i42@pure_quanta.q_res(chips)';

PART_NAME
 R973 'Q_RES_0402LF-33.2,1%,1/16W,CHIA':;

SECTION_NUMBER 1
 '@S9S_MB_2U_LIB.S9S_MB_2U(SCH_1):PAGE558_I43@PURE_QUANTA.Q_RES(CHIPS)':
 C_PATH='@s9s_mb_2u_lib.s9s_mb_2u(sch_1):page558_i43@pure_quanta.q_res(chips)';

PART_NAME
 R972 'Q_RES_0402LF-240,1%,1/16W,CHIPA':;

SECTION_NUMBER 1
 '@S9S_MB_2U_LIB.S9S_MB_2U(SCH_1):PAGE558_I62@PURE_QUANTA.Q_RES(CHIPS)':
 C_PATH='@s9s_mb_2u_lib.s9s_mb_2u(sch_1):page558_i62@pure_quanta.q_res(chips)';

PART_NAME
 R971 'Q_RES_0402LF-240,1%,1/16W,CHIPA':;

SECTION_NUMBER 1
 '@S9S_MB_2U_LIB.S9S_MB_2U(SCH_1):PAGE558_I27@PURE_QUANTA.Q_RES(CHIPS)':
 C_PATH='@s9s_mb_2u_lib.s9s_mb_2u(sch_1):page558_i27@pure_quanta.q_res(chips)';

PART_NAME
 R970 'Q_RES_0402LF-240,1%,1/16W,CHIPA':;

SECTION_NUMBER 1
 '@S9S_MB_2U_LIB.S9S_MB_2U(SCH_1):PAGE558_I63@PURE_QUANTA.Q_RES(CHIPS)':
 C_PATH='@s9s_mb_2u_lib.s9s_mb_2u(sch_1):page558_i63@pure_quanta.q_res(chips)';

PART_NAME
 R969 'Q_RES_0402LF-240,1%,1/16W,CHIPA':;

SECTION_NUMBER 1
 '@S9S_MB_2U_LIB.S9S_MB_2U(SCH_1):PAGE558_I25@PURE_QUANTA.Q_RES(CHIPS)':
 C_PATH='@s9s_mb_2u_lib.s9s_mb_2u(sch_1):page558_i25@pure_quanta.q_res(chips)';

PART_NAME
 R448 'Q_RES_0402LF-0,5%,1/16W,EMPTY,A':;

SECTION_NUMBER 1
 '@S9S_MB_2U_LIB.S9S_MB_2U(SCH_1):PAGE558_I69@PURE_QUANTA.Q_RES(CHIPS)':
 C_PATH='@s9s_mb_2u_lib.s9s_mb_2u(sch_1):page558_i69@pure_quanta.q_res(chips)';

PART_NAME
 C570 'Q_CAP_0402-0.1UF,25V,10%,X7R,CA':;

SECTION_NUMBER 1
 '@S9S_MB_2U_LIB.S9S_MB_2U(SCH_1):PAGE558_I53@PURE_QUANTA.Q_CAP(CHIPS)':
 C_PATH='@s9s_mb_2u_lib.s9s_mb_2u(sch_1):page558_i53@pure_quanta.q_cap(chips)';

PART_NAME
 C569 'Q_CAP_0402-0.1UF,25V,10%,X7R,CA':;

SECTION_NUMBER 1
 '@S9S_MB_2U_LIB.S9S_MB_2U(SCH_1):PAGE558_I31@PURE_QUANTA.Q_CAP(CHIPS)':
 C_PATH='@s9s_mb_2u_lib.s9s_mb_2u(sch_1):page558_i31@pure_quanta.q_cap(chips)';

PART_NAME
 C568 'Q_CAP_0402-0.1UF,25V,10%,X7R,CA':;

SECTION_NUMBER 1
 '@S9S_MB_2U_LIB.S9S_MB_2U(SCH_1):PAGE558_I57@PURE_QUANTA.Q_CAP(CHIPS)':
 C_PATH='@s9s_mb_2u_lib.s9s_mb_2u(sch_1):page558_i57@pure_quanta.q_cap(chips)';

PART_NAME
 C567 'Q_CAP_0402-0.1UF,25V,10%,X7R,CA':;

SECTION_NUMBER 1
 '@S9S_MB_2U_LIB.S9S_MB_2U(SCH_1):PAGE558_I29@PURE_QUANTA.Q_CAP(CHIPS)':
 C_PATH='@s9s_mb_2u_lib.s9s_mb_2u(sch_1):page558_i29@pure_quanta.q_cap(chips)';

PART_NAME
 U27 'TPS2553DBVR1-TPS2553DBVR-1,SMLA':;

SECTION_NUMBER 1
 '@S9S_MB_2U_LIB.S9S_MB_2U(SCH_1):PAGE618_I2@PURE_QUANTA.TPS2553DBVR1(CHIPS)':
 C_PATH='@s9s_mb_2u_lib.s9s_mb_2u(sch_1):page618_i2@pure_quanta.tps2553dbvr1(chips~
)';

PART_NAME
 R471 'Q_RES_0402LF-0,5%,1/16W,CHIP,CA':;

SECTION_NUMBER 1
 '@S9S_MB_2U_LIB.S9S_MB_2U(SCH_1):PAGE618_I13@PURE_QUANTA.Q_RES(CHIPS)':
 C_PATH='@s9s_mb_2u_lib.s9s_mb_2u(sch_1):page618_i13@pure_quanta.q_res(chips)';

PART_NAME
 R470 'Q_RES_0402LF-0,5%,1/16W,CHIP,CA':;

SECTION_NUMBER 1
 '@S9S_MB_2U_LIB.S9S_MB_2U(SCH_1):PAGE618_I52@PURE_QUANTA.Q_RES(CHIPS)':
 C_PATH='@s9s_mb_2u_lib.s9s_mb_2u(sch_1):page618_i52@pure_quanta.q_res(chips)';

PART_NAME
 R469 'Q_RES_0402LF-0,5%,1/16W,CHIP,CA':;

SECTION_NUMBER 1
 '@S9S_MB_2U_LIB.S9S_MB_2U(SCH_1):PAGE618_I51@PURE_QUANTA.Q_RES(CHIPS)':
 C_PATH='@s9s_mb_2u_lib.s9s_mb_2u(sch_1):page618_i51@pure_quanta.q_res(chips)';

PART_NAME
 R468 'Q_RES_0402LF-0,5%,1/16W,CHIP,CA':;

SECTION_NUMBER 1
 '@S9S_MB_2U_LIB.S9S_MB_2U(SCH_1):PAGE618_I28@PURE_QUANTA.Q_RES(CHIPS)':
 C_PATH='@s9s_mb_2u_lib.s9s_mb_2u(sch_1):page618_i28@pure_quanta.q_res(chips)';

PART_NAME
 R466 'Q_RES_0402LF-0,5%,1/16W,CHIP,CA':;

SECTION_NUMBER 1
 '@S9S_MB_2U_LIB.S9S_MB_2U(SCH_1):PAGE618_I27@PURE_QUANTA.Q_RES(CHIPS)':
 C_PATH='@s9s_mb_2u_lib.s9s_mb_2u(sch_1):page618_i27@pure_quanta.q_res(chips)';

PART_NAME
 R465 'Q_RES_0402LF-0,5%,1/16W,CHIP,CA':;

SECTION_NUMBER 1
 '@S9S_MB_2U_LIB.S9S_MB_2U(SCH_1):PAGE618_I21@PURE_QUANTA.Q_RES(CHIPS)':
 C_PATH='@s9s_mb_2u_lib.s9s_mb_2u(sch_1):page618_i21@pure_quanta.q_res(chips)';

PART_NAME
 R464 'Q_RES_0402LF-0,5%,1/16W,CHIP,CA':;

SECTION_NUMBER 1
 '@S9S_MB_2U_LIB.S9S_MB_2U(SCH_1):PAGE618_I20@PURE_QUANTA.Q_RES(CHIPS)':
 C_PATH='@s9s_mb_2u_lib.s9s_mb_2u(sch_1):page618_i20@pure_quanta.q_res(chips)';

PART_NAME
 R463 'Q_RES_0402LF-10K,1%,1/16W,CHIPA':;

SECTION_NUMBER 1
 '@S9S_MB_2U_LIB.S9S_MB_2U(SCH_1):PAGE618_I11@PURE_QUANTA.Q_RES(CHIPS)':
 C_PATH='@s9s_mb_2u_lib.s9s_mb_2u(sch_1):page618_i11@pure_quanta.q_res(chips)';

PART_NAME
 R462 'Q_RES_0402LF-20K,1%,1/16W,CHIPA':;

SECTION_NUMBER 1
 '@S9S_MB_2U_LIB.S9S_MB_2U(SCH_1):PAGE618_I8@PURE_QUANTA.Q_RES(CHIPS)':
 C_PATH='@s9s_mb_2u_lib.s9s_mb_2u(sch_1):page618_i8@pure_quanta.q_res(chips)';

PART_NAME
 R461 'Q_RES_0402LF-100K,5%,1/16W,CHIA':;

SECTION_NUMBER 1
 '@S9S_MB_2U_LIB.S9S_MB_2U(SCH_1):PAGE618_I4@PURE_QUANTA.Q_RES(CHIPS)':
 C_PATH='@s9s_mb_2u_lib.s9s_mb_2u(sch_1):page618_i4@pure_quanta.q_res(chips)';

PART_NAME
 L9 'Q_INDUCTOR4P_12-67/320MA,320MAA':;

SECTION_NUMBER 1
 '@S9S_MB_2U_LIB.S9S_MB_2U(SCH_1):PAGE618_I48@PURE_QUANTA.Q_INDUCTOR4P_12(CHIPS)':
 C_PATH='@s9s_mb_2u_lib.s9s_mb_2u(sch_1):page618_i48@pure_quanta.q_inductor4p_12(c~
hips)';

PART_NAME
 L6 'Q_INDUCTOR4P_12-67/320MA,320MAA':;

SECTION_NUMBER 1
 '@S9S_MB_2U_LIB.S9S_MB_2U(SCH_1):PAGE618_I24@PURE_QUANTA.Q_INDUCTOR4P_12(CHIPS)':
 C_PATH='@s9s_mb_2u_lib.s9s_mb_2u(sch_1):page618_i24@pure_quanta.q_inductor4p_12(c~
hips)';

PART_NAME
 L5 'Q_INDUCTOR4P_12-67/320MA,320MAA':;

SECTION_NUMBER 1
 '@S9S_MB_2U_LIB.S9S_MB_2U(SCH_1):PAGE618_I15@PURE_QUANTA.Q_INDUCTOR4P_12(CHIPS)':
 C_PATH='@s9s_mb_2u_lib.s9s_mb_2u(sch_1):page618_i15@pure_quanta.q_inductor4p_12(c~
hips)';

PART_NAME
 J48 'CONN9_2UB3903013101F-CONN9_2UBA':;

SECTION_NUMBER 1
 '@S9S_MB_2U_LIB.S9S_MB_2U(SCH_1):PAGE618_I1@PURE_QUANTA.CONN9_2UB3903013101F(CHIPS)':
 C_PATH='@s9s_mb_2u_lib.s9s_mb_2u(sch_1):page618_i1@pure_quanta.conn9_2ub390301310~
1f(chips)';

PART_NAME
 C1343 'Q_CAP_C0603-22UF,6.3V,20%,X6S,A':;

SECTION_NUMBER 1
 '@S9S_MB_2U_LIB.S9S_MB_2U(SCH_1):PAGE618_I55@PURE_QUANTA.Q_CAP(CHIPS)':
 C_PATH='@s9s_mb_2u_lib.s9s_mb_2u(sch_1):page618_i55@pure_quanta.q_cap(chips)';

PART_NAME
 C1342 'Q_CAP_C0603-22UF,6.3V,20%,X6S,A':;

SECTION_NUMBER 1
 '@S9S_MB_2U_LIB.S9S_MB_2U(SCH_1):PAGE618_I56@PURE_QUANTA.Q_CAP(CHIPS)':
 C_PATH='@s9s_mb_2u_lib.s9s_mb_2u(sch_1):page618_i56@pure_quanta.q_cap(chips)';

PART_NAME
 C1341 'Q_CAP_C0603-22UF,6.3V,20%,X6S,A':;

SECTION_NUMBER 1
 '@S9S_MB_2U_LIB.S9S_MB_2U(SCH_1):PAGE618_I60@PURE_QUANTA.Q_CAP(CHIPS)':
 C_PATH='@s9s_mb_2u_lib.s9s_mb_2u(sch_1):page618_i60@pure_quanta.q_cap(chips)';

PART_NAME
 C1337 'Q_CAP_C0603-22UF,6.3V,20%,X6S,A':;

SECTION_NUMBER 1
 '@S9S_MB_2U_LIB.S9S_MB_2U(SCH_1):PAGE618_I59@PURE_QUANTA.Q_CAP(CHIPS)':
 C_PATH='@s9s_mb_2u_lib.s9s_mb_2u(sch_1):page618_i59@pure_quanta.q_cap(chips)';

PART_NAME
 C566 'Q_CAP_0402-0.1UF,25V,10%,X7R,CA':;

SECTION_NUMBER 1
 '@S9S_MB_2U_LIB.S9S_MB_2U(SCH_1):PAGE618_I18@PURE_QUANTA.Q_CAP(CHIPS)':
 C_PATH='@s9s_mb_2u_lib.s9s_mb_2u(sch_1):page618_i18@pure_quanta.q_cap(chips)';

PART_NAME
 C565 'Q_CAP_0402-0.1UF,25V,10%,X7R,CA':;

SECTION_NUMBER 1
 '@S9S_MB_2U_LIB.S9S_MB_2U(SCH_1):PAGE618_I16@PURE_QUANTA.Q_CAP(CHIPS)':
 C_PATH='@s9s_mb_2u_lib.s9s_mb_2u(sch_1):page618_i16@pure_quanta.q_cap(chips)';

PART_NAME
 C564 'Q_CAP_0402-0.1UF,25V,10%,X7R,CA':;

SECTION_NUMBER 1
 '@S9S_MB_2U_LIB.S9S_MB_2U(SCH_1):PAGE618_I6@PURE_QUANTA.Q_CAP(CHIPS)':
 C_PATH='@s9s_mb_2u_lib.s9s_mb_2u(sch_1):page618_i6@pure_quanta.q_cap(chips)';

PART_NAME
 U29 'PCA9617ADP-PCA9617ADP,SMLF,IC,A':;

SECTION_NUMBER 1
 '@S9S_MB_2U_LIB.S9S_MB_2U(SCH_1):PAGE557_I26@PURE_QUANTA.PCA9617ADP(CHIPS)':
 C_PATH='@s9s_mb_a_lib.s9s_mb_a(sch_1):page557_i26@pure_quanta.pca9617adp(chips)~
';

PART_NAME
 U28 'PCA9617ADP-PCA9617ADP,SMLF,IC,A':;

SECTION_NUMBER 1
 '@S9S_MB_2U_LIB.S9S_MB_2U(SCH_1):PAGE557_I1@PURE_QUANTA.PCA9617ADP(CHIPS)':
 C_PATH='@s9s_mb_2u_lib.s9s_mb_2u(sch_1):page557_i1@pure_quanta.pca9617adp(chips)';

PART_NAME
 R968 'Q_RES_0402LF-1K,1%,1/16W,CHIP,A':;

SECTION_NUMBER 1
 '@S9S_MB_2U_LIB.S9S_MB_2U(SCH_1):PAGE557_I32@PURE_QUANTA.Q_RES(CHIPS)':
 C_PATH='@s9s_mb_2u_lib.s9s_mb_2u(sch_1):page557_i32@pure_quanta.q_res(chips)';

PART_NAME
 R967 'Q_RES_0402LF-1K,1%,1/16W,CHIP,A':;

SECTION_NUMBER 1
 '@S9S_MB_2U_LIB.S9S_MB_2U(SCH_1):PAGE557_I23@PURE_QUANTA.Q_RES(CHIPS)':
 C_PATH='@s9s_mb_2u_lib.s9s_mb_2u(sch_1):page557_i23@pure_quanta.q_res(chips)';

PART_NAME
 R966 'Q_RES_0402LF-1K,1%,1/16W,CHIP,A':;

SECTION_NUMBER 1
 '@S9S_MB_2U_LIB.S9S_MB_2U(SCH_1):PAGE557_I33@PURE_QUANTA.Q_RES(CHIPS)':
 C_PATH='@s9s_mb_2u_lib.s9s_mb_2u(sch_1):page557_i33@pure_quanta.q_res(chips)';

PART_NAME
 R965 'Q_RES_0402LF-1K,1%,1/16W,CHIP,A':;

SECTION_NUMBER 1
 '@S9S_MB_2U_LIB.S9S_MB_2U(SCH_1):PAGE557_I24@PURE_QUANTA.Q_RES(CHIPS)':
 C_PATH='@s9s_mb_2u_lib.s9s_mb_2u(sch_1):page557_i24@pure_quanta.q_res(chips)';

PART_NAME
 R964 'Q_RES_0402LF-240,1%,1/16W,CHIPA':;

SECTION_NUMBER 1
 '@S9S_MB_2U_LIB.S9S_MB_2U(SCH_1):PAGE557_I40@PURE_QUANTA.Q_RES(CHIPS)':
 C_PATH='@s9s_mb_2u_lib.s9s_mb_2u(sch_1):page557_i40@pure_quanta.q_res(chips)';

PART_NAME
 R963 'Q_RES_0402LF-240,1%,1/16W,CHIPA':;

SECTION_NUMBER 1
 '@S9S_MB_2U_LIB.S9S_MB_2U(SCH_1):PAGE557_I42@PURE_QUANTA.Q_RES(CHIPS)':
 C_PATH='@s9s_mb_2u_lib.s9s_mb_2u(sch_1):page557_i42@pure_quanta.q_res(chips)';

PART_NAME
 R962 'Q_RES_0402LF-0,5%,1/16W,CHIP,CA':;

SECTION_NUMBER 1
 '@S9S_MB_2U_LIB.S9S_MB_2U(SCH_1):PAGE557_I44@PURE_QUANTA.Q_RES(CHIPS)':
 C_PATH='@s9s_mb_2u_lib.s9s_mb_2u(sch_1):page557_i44@pure_quanta.q_res(chips)';

PART_NAME
 R961 'Q_RES_0402LF-0,5%,1/16W,CHIP,CA':;

SECTION_NUMBER 1
 '@S9S_MB_2U_LIB.S9S_MB_2U(SCH_1):PAGE557_I43@PURE_QUANTA.Q_RES(CHIPS)':
 C_PATH='@s9s_mb_2u_lib.s9s_mb_2u(sch_1):page557_i43@pure_quanta.q_res(chips)';

PART_NAME
 R960 'Q_RES_0402LF-0,5%,1/16W,CHIP,CA':;

SECTION_NUMBER 1
 '@S9S_MB_2U_LIB.S9S_MB_2U(SCH_1):PAGE557_I4@PURE_QUANTA.Q_RES(CHIPS)':
 C_PATH='@s9s_mb_2u_lib.s9s_mb_2u(sch_1):page557_i4@pure_quanta.q_res(chips)';

PART_NAME
 R911 'Q_RES_0402LF-240,1%,1/16W,CHIPA':;

SECTION_NUMBER 1
 '@S9S_MB_2U_LIB.S9S_MB_2U(SCH_1):PAGE557_I21@PURE_QUANTA.Q_RES(CHIPS)':
 C_PATH='@s9s_mb_2u_lib.s9s_mb_2u(sch_1):page557_i21@pure_quanta.q_res(chips)';

PART_NAME
 R910 'Q_RES_0402LF-240,1%,1/16W,CHIPA':;

SECTION_NUMBER 1
 '@S9S_MB_2U_LIB.S9S_MB_2U(SCH_1):PAGE557_I20@PURE_QUANTA.Q_RES(CHIPS)':
 C_PATH='@s9s_mb_2u_lib.s9s_mb_2u(sch_1):page557_i20@pure_quanta.q_res(chips)';

PART_NAME
 R909 'Q_RES_0402LF-0,5%,1/16W,CHIP,CA':;

SECTION_NUMBER 1
 '@S9S_MB_2U_LIB.S9S_MB_2U(SCH_1):PAGE557_I3@PURE_QUANTA.Q_RES(CHIPS)':
 C_PATH='@s9s_mb_2u_lib.s9s_mb_2u(sch_1):page557_i3@pure_quanta.q_res(chips)';

PART_NAME
 C562 'Q_CAP_0402-0.1UF,25V,10%,X7R,CA':;

SECTION_NUMBER 1
 '@S9S_MB_2U_LIB.S9S_MB_2U(SCH_1):PAGE557_I35@PURE_QUANTA.Q_CAP(CHIPS)':
 C_PATH='@s9s_mb_2u_lib.s9s_mb_2u(sch_1):page557_i35@pure_quanta.q_cap(chips)';

PART_NAME
 C561 'Q_CAP_0402-0.1UF,25V,10%,X7R,CA':;

SECTION_NUMBER 1
 '@S9S_MB_2U_LIB.S9S_MB_2U(SCH_1):PAGE557_I13@PURE_QUANTA.Q_CAP(CHIPS)':
 C_PATH='@s9s_mb_2u_lib.s9s_mb_2u(sch_1):page557_i13@pure_quanta.q_cap(chips)';

PART_NAME
 C560 'Q_CAP_0402-0.1UF,25V,10%,X7R,CA':;

SECTION_NUMBER 1
 '@S9S_MB_2U_LIB.S9S_MB_2U(SCH_1):PAGE557_I39@PURE_QUANTA.Q_CAP(CHIPS)':
 C_PATH='@s9s_mb_2u_lib.s9s_mb_2u(sch_1):page557_i39@pure_quanta.q_cap(chips)';

PART_NAME
 C559 'Q_CAP_0402-0.1UF,25V,10%,X7R,CA':;

SECTION_NUMBER 1
 '@S9S_MB_2U_LIB.S9S_MB_2U(SCH_1):PAGE557_I8@PURE_QUANTA.Q_CAP(CHIPS)':
 C_PATH='@s9s_mb_2u_lib.s9s_mb_2u(sch_1):page557_i8@pure_quanta.q_cap(chips)';

PART_NAME
 U26 'GTL2014PW-GTL2014PW,SMLF,IC,ALA':;

SECTION_NUMBER 1
 '@S9S_MB_2U_LIB.S9S_MB_2U(SCH_1):PAGE475_I76@PURE_QUANTA.GTL2014PW(CHIPS)':
 C_PATH='@s9s_mb_2u_lib.s9s_mb_2u(sch_1):page475_i76@pure_quanta.gtl2014pw(chips)';

PART_NAME
 U25 'GTL2014PW-GTL2014PW,SMLF,IC,ALA':;

SECTION_NUMBER 1
 '@S9S_MB_2U_LIB.S9S_MB_2U(SCH_1):PAGE475_I24@PURE_QUANTA.GTL2014PW(CHIPS)':
 C_PATH='@s9s_mb_2u_lib.s9s_mb_2u(sch_1):page475_i24@pure_quanta.gtl2014pw(chips)';

PART_NAME
 R939 'Q_RES_0402LF-10K,1%,1/16W,CHIPA':;

SECTION_NUMBER 1
 '@S9S_MB_2U_LIB.S9S_MB_2U(SCH_1):PAGE475_I83@PURE_QUANTA.Q_RES(CHIPS)':
 C_PATH='@s9s_mb_2u_lib.s9s_mb_2u(sch_1):page475_i83@pure_quanta.q_res(chips)';

PART_NAME
 R938 'Q_RES_0402LF-10K,1%,1/16W,CHIPA':;

SECTION_NUMBER 1
 '@S9S_MB_2U_LIB.S9S_MB_2U(SCH_1):PAGE475_I77@PURE_QUANTA.Q_RES(CHIPS)':
 C_PATH='@s9s_mb_2u_lib.s9s_mb_2u(sch_1):page475_i77@pure_quanta.q_res(chips)';

PART_NAME
 R937 'Q_RES_0402LF-10K,1%,1/16W,CHIPA':;

SECTION_NUMBER 1
 '@S9S_MB_2U_LIB.S9S_MB_2U(SCH_1):PAGE475_I85@PURE_QUANTA.Q_RES(CHIPS)':
 C_PATH='@s9s_mb_2u_lib.s9s_mb_2u(sch_1):page475_i85@pure_quanta.q_res(chips)';

PART_NAME
 R936 'Q_RES_0402LF-10K,1%,1/16W,CHIPA':;

SECTION_NUMBER 1
 '@S9S_MB_2U_LIB.S9S_MB_2U(SCH_1):PAGE475_I78@PURE_QUANTA.Q_RES(CHIPS)':
 C_PATH='@s9s_mb_2u_lib.s9s_mb_2u(sch_1):page475_i78@pure_quanta.q_res(chips)';

PART_NAME
 R935 'Q_RES_0402LF-10K,1%,1/16W,CHIPA':;

SECTION_NUMBER 1
 '@S9S_MB_2U_LIB.S9S_MB_2U(SCH_1):PAGE475_I86@PURE_QUANTA.Q_RES(CHIPS)':
 C_PATH='@s9s_mb_2u_lib.s9s_mb_2u(sch_1):page475_i86@pure_quanta.q_res(chips)';

PART_NAME
 R934 'Q_RES_0402LF-10K,1%,1/16W,CHIPA':;

SECTION_NUMBER 1
 '@S9S_MB_2U_LIB.S9S_MB_2U(SCH_1):PAGE475_I79@PURE_QUANTA.Q_RES(CHIPS)':
 C_PATH='@s9s_mb_2u_lib.s9s_mb_2u(sch_1):page475_i79@pure_quanta.q_res(chips)';

PART_NAME
 R933 'Q_RES_0402LF-10K,1%,1/16W,CHIPA':;

SECTION_NUMBER 1
 '@S9S_MB_2U_LIB.S9S_MB_2U(SCH_1):PAGE475_I82@PURE_QUANTA.Q_RES(CHIPS)':
 C_PATH='@s9s_mb_2u_lib.s9s_mb_2u(sch_1):page475_i82@pure_quanta.q_res(chips)';

PART_NAME
 R932 'Q_RES_0402LF-10K,1%,1/16W,CHIPA':;

SECTION_NUMBER 1
 '@S9S_MB_2U_LIB.S9S_MB_2U(SCH_1):PAGE475_I80@PURE_QUANTA.Q_RES(CHIPS)':
 C_PATH='@s9s_mb_2u_lib.s9s_mb_2u(sch_1):page475_i80@pure_quanta.q_res(chips)';

PART_NAME
 R876 'Q_RES_0402LF-1K,1%,1/16W,CHIP,A':;

SECTION_NUMBER 1
 '@S9S_MB_2U_LIB.S9S_MB_2U(SCH_1):PAGE475_I64@PURE_QUANTA.Q_RES(CHIPS)':
 C_PATH='@s9s_mb_2u_lib.s9s_mb_2u(sch_1):page475_i64@pure_quanta.q_res(chips)';

PART_NAME
 R875 'Q_RES_0402LF-1K,1%,1/16W,CHIP,A':;

SECTION_NUMBER 1
 '@S9S_MB_2U_LIB.S9S_MB_2U(SCH_1):PAGE475_I39@PURE_QUANTA.Q_RES(CHIPS)':
 C_PATH='@s9s_mb_2u_lib.s9s_mb_2u(sch_1):page475_i39@pure_quanta.q_res(chips)';

PART_NAME
 R874 'Q_RES_0402LF-0,5%,1/16W,EMPTY,A':;

SECTION_NUMBER 1
 '@S9S_MB_2U_LIB.S9S_MB_2U(SCH_1):PAGE475_I58@PURE_QUANTA.Q_RES(CHIPS)':
 C_PATH='@s9s_mb_2u_lib.s9s_mb_2u(sch_1):page475_i58@pure_quanta.q_res(chips)';

PART_NAME
 R873 'Q_RES_0402LF-0,5%,1/16W,EMPTY,A':;

SECTION_NUMBER 1
 '@S9S_MB_2U_LIB.S9S_MB_2U(SCH_1):PAGE475_I59@PURE_QUANTA.Q_RES(CHIPS)':
 C_PATH='@s9s_mb_2u_lib.s9s_mb_2u(sch_1):page475_i59@pure_quanta.q_res(chips)';

PART_NAME
 R872 'Q_RES_0402LF-0,5%,1/16W,EMPTY,A':;

SECTION_NUMBER 1
 '@S9S_MB_2U_LIB.S9S_MB_2U(SCH_1):PAGE475_I60@PURE_QUANTA.Q_RES(CHIPS)':
 C_PATH='@s9s_mb_2u_lib.s9s_mb_2u(sch_1):page475_i60@pure_quanta.q_res(chips)';

PART_NAME
 R871 'Q_RES_0402LF-0,5%,1/16W,EMPTY,A':;

SECTION_NUMBER 1
 '@S9S_MB_2U_LIB.S9S_MB_2U(SCH_1):PAGE475_I61@PURE_QUANTA.Q_RES(CHIPS)':
 C_PATH='@s9s_mb_2u_lib.s9s_mb_2u(sch_1):page475_i61@pure_quanta.q_res(chips)';

PART_NAME
 R870 'Q_RES_0402LF-0,5%,1/16W,EMPTY,A':;

SECTION_NUMBER 1
 '@S9S_MB_2U_LIB.S9S_MB_2U(SCH_1):PAGE475_I25@PURE_QUANTA.Q_RES(CHIPS)':
 C_PATH='@s9s_mb_2u_lib.s9s_mb_2u(sch_1):page475_i25@pure_quanta.q_res(chips)';

PART_NAME
 R869 'Q_RES_0402LF-0,5%,1/16W,EMPTY,A':;

SECTION_NUMBER 1
 '@S9S_MB_2U_LIB.S9S_MB_2U(SCH_1):PAGE475_I26@PURE_QUANTA.Q_RES(CHIPS)':
 C_PATH='@s9s_mb_2u_lib.s9s_mb_2u(sch_1):page475_i26@pure_quanta.q_res(chips)';

PART_NAME
 R868 'Q_RES_0402LF-0,5%,1/16W,EMPTY,A':;

SECTION_NUMBER 1
 '@S9S_MB_2U_LIB.S9S_MB_2U(SCH_1):PAGE475_I27@PURE_QUANTA.Q_RES(CHIPS)':
 C_PATH='@s9s_mb_2u_lib.s9s_mb_2u(sch_1):page475_i27@pure_quanta.q_res(chips)';

PART_NAME
 R867 'Q_RES_0402LF-0,5%,1/16W,EMPTY,A':;

SECTION_NUMBER 1
 '@S9S_MB_2U_LIB.S9S_MB_2U(SCH_1):PAGE475_I28@PURE_QUANTA.Q_RES(CHIPS)':
 C_PATH='@s9s_mb_2u_lib.s9s_mb_2u(sch_1):page475_i28@pure_quanta.q_res(chips)';

PART_NAME
 R866 'Q_RES_0402LF-1K,1%,1/16W,CHIP,A':;

SECTION_NUMBER 1
 '@S9S_MB_2U_LIB.S9S_MB_2U(SCH_1):PAGE475_I62@PURE_QUANTA.Q_RES(CHIPS)':
 C_PATH='@s9s_mb_2u_lib.s9s_mb_2u(sch_1):page475_i62@pure_quanta.q_res(chips)';

PART_NAME
 R865 'Q_RES_0402LF-4.32K,1%,1/16W,CHA':;

SECTION_NUMBER 1
 '@S9S_MB_2U_LIB.S9S_MB_2U(SCH_1):PAGE475_I74@PURE_QUANTA.Q_RES(CHIPS)':
 C_PATH='@s9s_mb_2u_lib.s9s_mb_2u(sch_1):page475_i74@pure_quanta.q_res(chips)';

PART_NAME
 R864 'Q_RES_0402LF-1K,1%,1/16W,CHIP,A':;

SECTION_NUMBER 1
 '@S9S_MB_2U_LIB.S9S_MB_2U(SCH_1):PAGE475_I38@PURE_QUANTA.Q_RES(CHIPS)':
 C_PATH='@s9s_mb_2u_lib.s9s_mb_2u(sch_1):page475_i38@pure_quanta.q_res(chips)';

PART_NAME
 R863 'Q_RES_0402LF-4.32K,1%,1/16W,CHA':;

SECTION_NUMBER 1
 '@S9S_MB_2U_LIB.S9S_MB_2U(SCH_1):PAGE475_I40@PURE_QUANTA.Q_RES(CHIPS)':
 C_PATH='@s9s_mb_2u_lib.s9s_mb_2u(sch_1):page475_i40@pure_quanta.q_res(chips)';

PART_NAME
 R862 'Q_RES_0402LF-0,5%,1/16W,CHIP,CA':;

SECTION_NUMBER 1
 '@S9S_MB_2U_LIB.S9S_MB_2U(SCH_1):PAGE475_I49@PURE_QUANTA.Q_RES(CHIPS)':
 C_PATH='@s9s_mb_2u_lib.s9s_mb_2u(sch_1):page475_i49@pure_quanta.q_res(chips)';

PART_NAME
 R861 'Q_RES_0402LF-0,5%,1/16W,CHIP,CA':;

SECTION_NUMBER 1
 '@S9S_MB_2U_LIB.S9S_MB_2U(SCH_1):PAGE475_I48@PURE_QUANTA.Q_RES(CHIPS)':
 C_PATH='@s9s_mb_2u_lib.s9s_mb_2u(sch_1):page475_i48@pure_quanta.q_res(chips)';

PART_NAME
 R860 'Q_RES_0402LF-0,5%,1/16W,CHIP,CA':;

SECTION_NUMBER 1
 '@S9S_MB_2U_LIB.S9S_MB_2U(SCH_1):PAGE475_I51@PURE_QUANTA.Q_RES(CHIPS)':
 C_PATH='@s9s_mb_2u_lib.s9s_mb_2u(sch_1):page475_i51@pure_quanta.q_res(chips)';

PART_NAME
 R859 'Q_RES_0402LF-0,5%,1/16W,CHIP,CA':;

SECTION_NUMBER 1
 '@S9S_MB_2U_LIB.S9S_MB_2U(SCH_1):PAGE475_I50@PURE_QUANTA.Q_RES(CHIPS)':
 C_PATH='@s9s_mb_2u_lib.s9s_mb_2u(sch_1):page475_i50@pure_quanta.q_res(chips)';

PART_NAME
 R858 'Q_RES_0402LF-0,5%,1/16W,EMPTY,A':;

SECTION_NUMBER 1
 '@S9S_MB_2U_LIB.S9S_MB_2U(SCH_1):PAGE475_I52@PURE_QUANTA.Q_RES(CHIPS)':
 C_PATH='@s9s_mb_2u_lib.s9s_mb_2u(sch_1):page475_i52@pure_quanta.q_res(chips)';

PART_NAME
 R857 'Q_RES_0402LF-0,5%,1/16W,EMPTY,A':;

SECTION_NUMBER 1
 '@S9S_MB_2U_LIB.S9S_MB_2U(SCH_1):PAGE475_I53@PURE_QUANTA.Q_RES(CHIPS)':
 C_PATH='@s9s_mb_2u_lib.s9s_mb_2u(sch_1):page475_i53@pure_quanta.q_res(chips)';

PART_NAME
 R856 'Q_RES_0402LF-0,5%,1/16W,EMPTY,A':;

SECTION_NUMBER 1
 '@S9S_MB_2U_LIB.S9S_MB_2U(SCH_1):PAGE475_I54@PURE_QUANTA.Q_RES(CHIPS)':
 C_PATH='@s9s_mb_2u_lib.s9s_mb_2u(sch_1):page475_i54@pure_quanta.q_res(chips)';

PART_NAME
 R855 'Q_RES_0402LF-0,5%,1/16W,EMPTY,A':;

SECTION_NUMBER 1
 '@S9S_MB_2U_LIB.S9S_MB_2U(SCH_1):PAGE475_I55@PURE_QUANTA.Q_RES(CHIPS)':
 C_PATH='@s9s_mb_2u_lib.s9s_mb_2u(sch_1):page475_i55@pure_quanta.q_res(chips)';

PART_NAME
 R854 'Q_RES_0402LF-0,5%,1/16W,CHIP,CA':;

SECTION_NUMBER 1
 '@S9S_MB_2U_LIB.S9S_MB_2U(SCH_1):PAGE475_I9@PURE_QUANTA.Q_RES(CHIPS)':
 C_PATH='@s9s_mb_2u_lib.s9s_mb_2u(sch_1):page475_i9@pure_quanta.q_res(chips)';

PART_NAME
 R853 'Q_RES_0402LF-0,5%,1/16W,CHIP,CA':;

SECTION_NUMBER 1
 '@S9S_MB_2U_LIB.S9S_MB_2U(SCH_1):PAGE475_I10@PURE_QUANTA.Q_RES(CHIPS)':
 C_PATH='@s9s_mb_2u_lib.s9s_mb_2u(sch_1):page475_i10@pure_quanta.q_res(chips)';

PART_NAME
 R852 'Q_RES_0402LF-0,5%,1/16W,CHIP,CA':;

SECTION_NUMBER 1
 '@S9S_MB_2U_LIB.S9S_MB_2U(SCH_1):PAGE475_I11@PURE_QUANTA.Q_RES(CHIPS)':
 C_PATH='@s9s_mb_2u_lib.s9s_mb_2u(sch_1):page475_i11@pure_quanta.q_res(chips)';

PART_NAME
 R851 'Q_RES_0402LF-0,5%,1/16W,CHIP,CA':;

SECTION_NUMBER 1
 '@S9S_MB_2U_LIB.S9S_MB_2U(SCH_1):PAGE475_I12@PURE_QUANTA.Q_RES(CHIPS)':
 C_PATH='@s9s_mb_2u_lib.s9s_mb_2u(sch_1):page475_i12@pure_quanta.q_res(chips)';

PART_NAME
 R850 'Q_RES_0402LF-0,5%,1/16W,EMPTY,A':;

SECTION_NUMBER 1
 '@S9S_MB_2U_LIB.S9S_MB_2U(SCH_1):PAGE475_I13@PURE_QUANTA.Q_RES(CHIPS)':
 C_PATH='@s9s_mb_2u_lib.s9s_mb_2u(sch_1):page475_i13@pure_quanta.q_res(chips)';

PART_NAME
 R849 'Q_RES_0402LF-0,5%,1/16W,EMPTY,A':;

SECTION_NUMBER 1
 '@S9S_MB_2U_LIB.S9S_MB_2U(SCH_1):PAGE475_I14@PURE_QUANTA.Q_RES(CHIPS)':
 C_PATH='@s9s_mb_2u_lib.s9s_mb_2u(sch_1):page475_i14@pure_quanta.q_res(chips)';

PART_NAME
 R848 'Q_RES_0402LF-0,5%,1/16W,EMPTY,A':;

SECTION_NUMBER 1
 '@S9S_MB_2U_LIB.S9S_MB_2U(SCH_1):PAGE475_I15@PURE_QUANTA.Q_RES(CHIPS)':
 C_PATH='@s9s_mb_2u_lib.s9s_mb_2u(sch_1):page475_i15@pure_quanta.q_res(chips)';

PART_NAME
 R847 'Q_RES_0402LF-0,5%,1/16W,EMPTY,A':;

SECTION_NUMBER 1
 '@S9S_MB_2U_LIB.S9S_MB_2U(SCH_1):PAGE475_I16@PURE_QUANTA.Q_RES(CHIPS)':
 C_PATH='@s9s_mb_2u_lib.s9s_mb_2u(sch_1):page475_i16@pure_quanta.q_res(chips)';

PART_NAME
 C558 'Q_CAP_0402-0.1UF,25V,10%,X7R,CA':;

SECTION_NUMBER 1
 '@S9S_MB_2U_LIB.S9S_MB_2U(SCH_1):PAGE475_I67@PURE_QUANTA.Q_CAP(CHIPS)':
 C_PATH='@s9s_mb_2u_lib.s9s_mb_2u(sch_1):page475_i67@pure_quanta.q_cap(chips)';

PART_NAME
 C557 'Q_CAP_0402-0.1UF,25V,10%,X7R,CA':;

SECTION_NUMBER 1
 '@S9S_MB_2U_LIB.S9S_MB_2U(SCH_1):PAGE475_I42@PURE_QUANTA.Q_CAP(CHIPS)':
 C_PATH='@s9s_mb_2u_lib.s9s_mb_2u(sch_1):page475_i42@pure_quanta.q_cap(chips)';

PART_NAME
 C556 'Q_CAP_C0402-1UF,25V,10%,X6S,CHA':;

SECTION_NUMBER 1
 '@S9S_MB_2U_LIB.S9S_MB_2U(SCH_1):PAGE475_I73@PURE_QUANTA.Q_CAP(CHIPS)':
 C_PATH='@s9s_mb_2u_lib.s9s_mb_2u(sch_1):page475_i73@pure_quanta.q_cap(chips)';

PART_NAME
 C555 'Q_CAP_C0402-1UF,25V,10%,X6S,CHA':;

SECTION_NUMBER 1
 '@S9S_MB_2U_LIB.S9S_MB_2U(SCH_1):PAGE475_I36@PURE_QUANTA.Q_CAP(CHIPS)':
 C_PATH='@s9s_mb_2u_lib.s9s_mb_2u(sch_1):page475_i36@pure_quanta.q_cap(chips)';

PART_NAME
 R1743 'Q_RES_0402LF-0,5%,1/16W,EMPTY,A':;

SECTION_NUMBER 1
 '@S9S_MB_2U_LIB.S9S_MB_2U(SCH_1):PAGE548_I81@PURE_QUANTA.Q_RES(CHIPS)':
 C_PATH='@s9s_mb_2u_lib.s9s_mb_2u(sch_1):page548_i81@pure_quanta.q_res(chips)';

PART_NAME
 R931 'Q_RES_0402LF-0,5%,1/16W,CHIP,CA':;

SECTION_NUMBER 1
 '@S9S_MB_2U_LIB.S9S_MB_2U(SCH_1):PAGE548_I48@PURE_QUANTA.Q_RES(CHIPS)':
 C_PATH='@s9s_mb_2u_lib.s9s_mb_2u(sch_1):page548_i48@pure_quanta.q_res(chips)';

PART_NAME
 R930 'Q_RES_0402LF-4.7K,1%,1/16W,CHIA':;

SECTION_NUMBER 1
 '@S9S_MB_2U_LIB.S9S_MB_2U(SCH_1):PAGE548_I63@PURE_QUANTA.Q_RES(CHIPS)':
 C_PATH='@s9s_mb_2u_lib.s9s_mb_2u(sch_1):page548_i63@pure_quanta.q_res(chips)';

PART_NAME
 R929 'Q_RES_0402LF-10K,1%,1/16W,CHIPA':;

SECTION_NUMBER 1
 '@S9S_MB_2U_LIB.S9S_MB_2U(SCH_1):PAGE548_I59@PURE_QUANTA.Q_RES(CHIPS)':
 C_PATH='@s9s_mb_2u_lib.s9s_mb_2u(sch_1):page548_i59@pure_quanta.q_res(chips)';

PART_NAME
 R928 'Q_RES_0402LF-10K,1%,1/16W,CHIPA':;

SECTION_NUMBER 1
 '@S9S_MB_2U_LIB.S9S_MB_2U(SCH_1):PAGE548_I60@PURE_QUANTA.Q_RES(CHIPS)':
 C_PATH='@s9s_mb_2u_lib.s9s_mb_2u(sch_1):page548_i60@pure_quanta.q_res(chips)';

PART_NAME
 R927 'Q_RES_0402LF-10K,1%,1/16W,CHIPA':;

SECTION_NUMBER 1
 '@S9S_MB_2U_LIB.S9S_MB_2U(SCH_1):PAGE548_I61@PURE_QUANTA.Q_RES(CHIPS)':
 C_PATH='@s9s_mb_2u_lib.s9s_mb_2u(sch_1):page548_i61@pure_quanta.q_res(chips)';

PART_NAME
 R920 'Q_RES_0402LF-1K,5%,1/16W,EMPTYA':;

SECTION_NUMBER 1
 '@S9S_MB_2U_LIB.S9S_MB_2U(SCH_1):PAGE548_I76@PURE_QUANTA.Q_RES(CHIPS)':
 C_PATH='@s9s_mb_2u_lib.s9s_mb_2u(sch_1):page548_i76@pure_quanta.q_res(chips)';

PART_NAME
 R919 'Q_RES_0402LF-10K,1%,1/16W,CHIPA':;

SECTION_NUMBER 1
 '@S9S_MB_2U_LIB.S9S_MB_2U(SCH_1):PAGE548_I75@PURE_QUANTA.Q_RES(CHIPS)':
 C_PATH='@s9s_mb_2u_lib.s9s_mb_2u(sch_1):page548_i75@pure_quanta.q_res(chips)';

PART_NAME
 R806 'Q_RES_0402LF-33,5%,1/16W,CHIP,A':;

SECTION_NUMBER 1
 '@S9S_MB_2U_LIB.S9S_MB_2U(SCH_1):PAGE548_I54@PURE_QUANTA.Q_RES(CHIPS)':
 C_PATH='@s9s_mb_2u_lib.s9s_mb_2u(sch_1):page548_i54@pure_quanta.q_res(chips)';

PART_NAME
 R805 'Q_RES_0402LF-33,5%,1/16W,CHIP,A':;

SECTION_NUMBER 1
 '@S9S_MB_2U_LIB.S9S_MB_2U(SCH_1):PAGE548_I25@PURE_QUANTA.Q_RES(CHIPS)':
 C_PATH='@s9s_mb_2u_lib.s9s_mb_2u(sch_1):page548_i25@pure_quanta.q_res(chips)';

PART_NAME
 R804 'Q_RES_0402LF-33,5%,1/16W,CHIP,A':;

SECTION_NUMBER 1
 '@S9S_MB_2U_LIB.S9S_MB_2U(SCH_1):PAGE548_I20@PURE_QUANTA.Q_RES(CHIPS)':
 C_PATH='@s9s_mb_2u_lib.s9s_mb_2u(sch_1):page548_i20@pure_quanta.q_res(chips)';

PART_NAME
 R803 'Q_RES_0402LF-33,5%,1/16W,CHIP,A':;

SECTION_NUMBER 1
 '@S9S_MB_2U_LIB.S9S_MB_2U(SCH_1):PAGE548_I19@PURE_QUANTA.Q_RES(CHIPS)':
 C_PATH='@s9s_mb_2u_lib.s9s_mb_2u(sch_1):page548_i19@pure_quanta.q_res(chips)';

PART_NAME
 J43 'CONN10_G2100HT0038071-CONN10_GA':;

SECTION_NUMBER 1
 '@S9S_MB_2U_LIB.S9S_MB_2U(SCH_1):PAGE548_I42@PURE_QUANTA.CONN10_G2100HT0038071(CHIPS)':
 C_PATH='@s9s_mb_2u_lib.s9s_mb_2u(sch_1):page548_i42@pure_quanta.conn10_g2100ht003~
8071(chips)';

PART_NAME
 C563 'Q_CAP_C0805-10UF,25V,10%,X6S,CA':;

SECTION_NUMBER 1
 '@S9S_MB_2U_LIB.S9S_MB_2U(SCH_1):PAGE548_I50@PURE_QUANTA.Q_CAP(CHIPS)':
 C_PATH='@s9s_mb_2u_lib.s9s_mb_2u(sch_1):page548_i50@pure_quanta.q_cap(chips)';

PART_NAME
 C554 'Q_CAP_0402-0.1UF,25V,10%,X7R,CA':;

SECTION_NUMBER 1
 '@S9S_MB_2U_LIB.S9S_MB_2U(SCH_1):PAGE548_I52@PURE_QUANTA.Q_CAP(CHIPS)':
 C_PATH='@s9s_mb_2u_lib.s9s_mb_2u(sch_1):page548_i52@pure_quanta.q_cap(chips)';

PART_NAME
 U24 'PCA9546APW-PCA9546APW,SMLF,IC,A':;

SECTION_NUMBER 1
 '@S9S_MB_2U_LIB.S9S_MB_2U(SCH_1):PAGE556_I35@PURE_QUANTA.PCA9546APW(CHIPS)':
 C_PATH='@s9s_mb_a_lib.s9s_mb_a(sch_1):page556_i35@pure_quanta.pca9546apw(chips)~
';

PART_NAME
 R1522 'Q_RES_0402LF-10K,1%,1/16W,CHIPA':;

SECTION_NUMBER 1
 '@S9S_MB_2U_LIB.S9S_MB_2U(SCH_1):PAGE556_I58@PURE_QUANTA.Q_RES(CHIPS)':
 C_PATH='@s9s_mb_2u_lib.s9s_mb_2u(sch_1):page556_i58@pure_quanta.q_res(chips)';

PART_NAME
 R802 'Q_RES_0402LF-0,5%,1/16W,CHIP,CA':;

SECTION_NUMBER 1
 '@S9S_MB_2U_LIB.S9S_MB_2U(SCH_1):PAGE556_I50@PURE_QUANTA.Q_RES(CHIPS)':
 C_PATH='@s9s_mb_2u_lib.s9s_mb_2u(sch_1):page556_i50@pure_quanta.q_res(chips)';

PART_NAME
 R801 'Q_RES_0402LF-0,5%,1/16W,CHIP,CA':;

SECTION_NUMBER 1
 '@S9S_MB_2U_LIB.S9S_MB_2U(SCH_1):PAGE556_I51@PURE_QUANTA.Q_RES(CHIPS)':
 C_PATH='@s9s_mb_2u_lib.s9s_mb_2u(sch_1):page556_i51@pure_quanta.q_res(chips)';

PART_NAME
 R800 'Q_RES_0402LF-0,5%,1/16W,CHIP,CA':;

SECTION_NUMBER 1
 '@S9S_MB_2U_LIB.S9S_MB_2U(SCH_1):PAGE556_I57@PURE_QUANTA.Q_RES(CHIPS)':
 C_PATH='@s9s_mb_2u_lib.s9s_mb_2u(sch_1):page556_i57@pure_quanta.q_res(chips)';

PART_NAME
 R799 'Q_RES_0402LF-0,5%,1/16W,CHIP,CA':;

SECTION_NUMBER 1
 '@S9S_MB_2U_LIB.S9S_MB_2U(SCH_1):PAGE556_I56@PURE_QUANTA.Q_RES(CHIPS)':
 C_PATH='@s9s_mb_2u_lib.s9s_mb_2u(sch_1):page556_i56@pure_quanta.q_res(chips)';

PART_NAME
 R798 'Q_RES_0402LF-2.2K ,5%,1/16W,CHA':;

SECTION_NUMBER 1
 '@S9S_MB_2U_LIB.S9S_MB_2U(SCH_1):PAGE556_I26@PURE_QUANTA.Q_RES(CHIPS)':
 C_PATH='@s9s_mb_2u_lib.s9s_mb_2u(sch_1):page556_i26@pure_quanta.q_res(chips)';

PART_NAME
 R797 'Q_RES_0402LF-2.2K ,5%,1/16W,CHA':;

SECTION_NUMBER 1
 '@S9S_MB_2U_LIB.S9S_MB_2U(SCH_1):PAGE556_I27@PURE_QUANTA.Q_RES(CHIPS)':
 C_PATH='@s9s_mb_2u_lib.s9s_mb_2u(sch_1):page556_i27@pure_quanta.q_res(chips)';

PART_NAME
 R796 'Q_RES_0402LF-2.2K ,5%,1/16W,CHA':;

SECTION_NUMBER 1
 '@S9S_MB_2U_LIB.S9S_MB_2U(SCH_1):PAGE556_I28@PURE_QUANTA.Q_RES(CHIPS)':
 C_PATH='@s9s_mb_2u_lib.s9s_mb_2u(sch_1):page556_i28@pure_quanta.q_res(chips)';

PART_NAME
 R795 'Q_RES_0402LF-2.2K ,5%,1/16W,CHA':;

SECTION_NUMBER 1
 '@S9S_MB_2U_LIB.S9S_MB_2U(SCH_1):PAGE556_I29@PURE_QUANTA.Q_RES(CHIPS)':
 C_PATH='@s9s_mb_2u_lib.s9s_mb_2u(sch_1):page556_i29@pure_quanta.q_res(chips)';

PART_NAME
 R794 'Q_RES_0402LF-2.2K ,5%,1/16W,CHA':;

SECTION_NUMBER 1
 '@S9S_MB_2U_LIB.S9S_MB_2U(SCH_1):PAGE556_I30@PURE_QUANTA.Q_RES(CHIPS)':
 C_PATH='@s9s_mb_2u_lib.s9s_mb_2u(sch_1):page556_i30@pure_quanta.q_res(chips)';

PART_NAME
 R793 'Q_RES_0402LF-2.2K ,5%,1/16W,CHA':;

SECTION_NUMBER 1
 '@S9S_MB_2U_LIB.S9S_MB_2U(SCH_1):PAGE556_I31@PURE_QUANTA.Q_RES(CHIPS)':
 C_PATH='@s9s_mb_2u_lib.s9s_mb_2u(sch_1):page556_i31@pure_quanta.q_res(chips)';

PART_NAME
 R792 'Q_RES_0402LF-2.2K ,5%,1/16W,CHA':;

SECTION_NUMBER 1
 '@S9S_MB_2U_LIB.S9S_MB_2U(SCH_1):PAGE556_I32@PURE_QUANTA.Q_RES(CHIPS)':
 C_PATH='@s9s_mb_2u_lib.s9s_mb_2u(sch_1):page556_i32@pure_quanta.q_res(chips)';

PART_NAME
 R791 'Q_RES_0402LF-2.2K ,5%,1/16W,CHA':;

SECTION_NUMBER 1
 '@S9S_MB_2U_LIB.S9S_MB_2U(SCH_1):PAGE556_I33@PURE_QUANTA.Q_RES(CHIPS)':
 C_PATH='@s9s_mb_2u_lib.s9s_mb_2u(sch_1):page556_i33@pure_quanta.q_res(chips)';

PART_NAME
 R790 'Q_RES_0402LF-0,5%,1/16W,CHIP,CA':;

SECTION_NUMBER 1
 '@S9S_MB_2U_LIB.S9S_MB_2U(SCH_1):PAGE556_I18@PURE_QUANTA.Q_RES(CHIPS)':
 C_PATH='@s9s_mb_2u_lib.s9s_mb_2u(sch_1):page556_i18@pure_quanta.q_res(chips)';

PART_NAME
 R789 'Q_RES_0402LF-0,5%,1/16W,CHIP,CA':;

SECTION_NUMBER 1
 '@S9S_MB_2U_LIB.S9S_MB_2U(SCH_1):PAGE556_I19@PURE_QUANTA.Q_RES(CHIPS)':
 C_PATH='@s9s_mb_2u_lib.s9s_mb_2u(sch_1):page556_i19@pure_quanta.q_res(chips)';

PART_NAME
 R788 'Q_RES_0402LF-0,5%,1/16W,CHIP,CA':;

SECTION_NUMBER 1
 '@S9S_MB_2U_LIB.S9S_MB_2U(SCH_1):PAGE556_I20@PURE_QUANTA.Q_RES(CHIPS)':
 C_PATH='@s9s_mb_2u_lib.s9s_mb_2u(sch_1):page556_i20@pure_quanta.q_res(chips)';

PART_NAME
 R787 'Q_RES_0402LF-0,5%,1/16W,CHIP,CA':;

SECTION_NUMBER 1
 '@S9S_MB_2U_LIB.S9S_MB_2U(SCH_1):PAGE556_I21@PURE_QUANTA.Q_RES(CHIPS)':
 C_PATH='@s9s_mb_2u_lib.s9s_mb_2u(sch_1):page556_i21@pure_quanta.q_res(chips)';

PART_NAME
 R786 'Q_RES_0402LF-1K,1%,1/16W,CHIP,A':;

SECTION_NUMBER 1
 '@S9S_MB_2U_LIB.S9S_MB_2U(SCH_1):PAGE556_I12@PURE_QUANTA.Q_RES(CHIPS)':
 C_PATH='@s9s_mb_2u_lib.s9s_mb_2u(sch_1):page556_i12@pure_quanta.q_res(chips)';

PART_NAME
 R785 'Q_RES_0402LF-10K,1%,1/16W,EMPTA':;

SECTION_NUMBER 1
 '@S9S_MB_2U_LIB.S9S_MB_2U(SCH_1):PAGE556_I13@PURE_QUANTA.Q_RES(CHIPS)':
 C_PATH='@s9s_mb_2u_lib.s9s_mb_2u(sch_1):page556_i13@pure_quanta.q_res(chips)';

PART_NAME
 R784 'Q_RES_0402LF-1K,1%,1/16W,EMPTYA':;

SECTION_NUMBER 1
 '@S9S_MB_2U_LIB.S9S_MB_2U(SCH_1):PAGE556_I8@PURE_QUANTA.Q_RES(CHIPS)':
 C_PATH='@s9s_mb_2u_lib.s9s_mb_2u(sch_1):page556_i8@pure_quanta.q_res(chips)';

PART_NAME
 R783 'Q_RES_0402LF-10K,1%,1/16W,CHIPA':;

SECTION_NUMBER 1
 '@S9S_MB_2U_LIB.S9S_MB_2U(SCH_1):PAGE556_I10@PURE_QUANTA.Q_RES(CHIPS)':
 C_PATH='@s9s_mb_2u_lib.s9s_mb_2u(sch_1):page556_i10@pure_quanta.q_res(chips)';

PART_NAME
 R782 'Q_RES_0402LF-1K,1%,1/16W,CHIP,A':;

SECTION_NUMBER 1
 '@S9S_MB_2U_LIB.S9S_MB_2U(SCH_1):PAGE556_I6@PURE_QUANTA.Q_RES(CHIPS)':
 C_PATH='@s9s_mb_2u_lib.s9s_mb_2u(sch_1):page556_i6@pure_quanta.q_res(chips)';

PART_NAME
 R781 'Q_RES_0402LF-10K,1%,1/16W,EMPTA':;

SECTION_NUMBER 1
 '@S9S_MB_2U_LIB.S9S_MB_2U(SCH_1):PAGE556_I9@PURE_QUANTA.Q_RES(CHIPS)':
 C_PATH='@s9s_mb_2u_lib.s9s_mb_2u(sch_1):page556_i9@pure_quanta.q_res(chips)';

PART_NAME
 C553 'Q_CAP_0402-0.1UF,25V,10%,X7R,CA':;

SECTION_NUMBER 1
 '@S9S_MB_2U_LIB.S9S_MB_2U(SCH_1):PAGE556_I40@PURE_QUANTA.Q_CAP(CHIPS)':
 C_PATH='@s9s_mb_2u_lib.s9s_mb_2u(sch_1):page556_i40@pure_quanta.q_cap(chips)';

PART_NAME
 R1472 'Q_RES_0402LF-33.2,1%,1/16W,CHIA':;

SECTION_NUMBER 1
 '@S9S_MB_2U_LIB.S9S_MB_2U(SCH_1):PAGE470_I144@PURE_QUANTA.Q_RES(CHIPS)':
 C_PATH='@s9s_mb_2u_lib.s9s_mb_2u(sch_1):page470_i144@pure_quanta.q_res(chips)';

PART_NAME
 R780 'Q_RES_0402LF-49.9     ,1%  ,1/A':;

SECTION_NUMBER 1
 '@S9S_MB_2U_LIB.S9S_MB_2U(SCH_1):PAGE470_I92@PURE_QUANTA.Q_RES(CHIPS)':
 C_PATH='@s9s_mb_2u_lib.s9s_mb_2u(sch_1):page470_i92@pure_quanta.q_res(chips)';

PART_NAME
 R779 'Q_RES_0402LF-150,5%,1/16W,CHIPA':;

SECTION_NUMBER 1
 '@S9S_MB_2U_LIB.S9S_MB_2U(SCH_1):PAGE470_I95@PURE_QUANTA.Q_RES(CHIPS)':
 C_PATH='@s9s_mb_2u_lib.s9s_mb_2u(sch_1):page470_i95@pure_quanta.q_res(chips)';

PART_NAME
 R778 'Q_RES_0402LF-1K,1%,1/16W,CHIP,A':;

SECTION_NUMBER 1
 '@S9S_MB_2U_LIB.S9S_MB_2U(SCH_1):PAGE470_I15@PURE_QUANTA.Q_RES(CHIPS)':
 C_PATH='@s9s_mb_2u_lib.s9s_mb_2u(sch_1):page470_i15@pure_quanta.q_res(chips)';

PART_NAME
 R777 'Q_RES_0402LF-10,1%,1/16W,CHIP,A':;

SECTION_NUMBER 1
 '@S9S_MB_2U_LIB.S9S_MB_2U(SCH_1):PAGE470_I10@PURE_QUANTA.Q_RES(CHIPS)':
 C_PATH='@s9s_mb_2u_lib.s9s_mb_2u(sch_1):page470_i10@pure_quanta.q_res(chips)';

PART_NAME
 R776 'Q_RES_0402LF-100,1%,1/16W,CHIPA':;

SECTION_NUMBER 1
 '@S9S_MB_2U_LIB.S9S_MB_2U(SCH_1):PAGE470_I7@PURE_QUANTA.Q_RES(CHIPS)':
 C_PATH='@s9s_mb_2u_lib.s9s_mb_2u(sch_1):page470_i7@pure_quanta.q_res(chips)';

PART_NAME
 R775 'Q_RES_0402LF-10,1%,1/16W,CHIP,A':;

SECTION_NUMBER 1
 '@S9S_MB_2U_LIB.S9S_MB_2U(SCH_1):PAGE470_I5@PURE_QUANTA.Q_RES(CHIPS)':
 C_PATH='@s9s_mb_2u_lib.s9s_mb_2u(sch_1):page470_i5@pure_quanta.q_res(chips)';

PART_NAME
 R774 'Q_RES_0402LF-75,1%,1/16W,CHIP,A':;

SECTION_NUMBER 1
 '@S9S_MB_2U_LIB.S9S_MB_2U(SCH_1):PAGE470_I132@PURE_QUANTA.Q_RES(CHIPS)':
 C_PATH='@s9s_mb_2u_lib.s9s_mb_2u(sch_1):page470_i132@pure_quanta.q_res(chips)';

PART_NAME
 R773 'Q_RES_0402LF-1K,1%,1/16W,CHIP,A':;

SECTION_NUMBER 1
 '@S9S_MB_2U_LIB.S9S_MB_2U(SCH_1):PAGE470_I124@PURE_QUANTA.Q_RES(CHIPS)':
 C_PATH='@s9s_mb_2u_lib.s9s_mb_2u(sch_1):page470_i124@pure_quanta.q_res(chips)';

PART_NAME
 R772 'Q_RES_0402LF-1K,1%,1/16W,CHIP,A':;

SECTION_NUMBER 1
 '@S9S_MB_2U_LIB.S9S_MB_2U(SCH_1):PAGE470_I118@PURE_QUANTA.Q_RES(CHIPS)':
 C_PATH='@s9s_mb_2u_lib.s9s_mb_2u(sch_1):page470_i118@pure_quanta.q_res(chips)';

PART_NAME
 R771 'Q_RES_0402LF-1K,1%,1/16W,CHIP,A':;

SECTION_NUMBER 1
 '@S9S_MB_2U_LIB.S9S_MB_2U(SCH_1):PAGE470_I120@PURE_QUANTA.Q_RES(CHIPS)':
 C_PATH='@s9s_mb_2u_lib.s9s_mb_2u(sch_1):page470_i120@pure_quanta.q_res(chips)';

PART_NAME
 R769 'Q_RES_0402LF-10K,1%,1/16W,CHIPA':;

SECTION_NUMBER 1
 '@S9S_MB_2U_LIB.S9S_MB_2U(SCH_1):PAGE470_I102@PURE_QUANTA.Q_RES(CHIPS)':
 C_PATH='@s9s_mb_2u_lib.s9s_mb_2u(sch_1):page470_i102@pure_quanta.q_res(chips)';

PART_NAME
 R768 'Q_RES_0402LF-1K,1%,1/16W,CHIP,A':;

SECTION_NUMBER 1
 '@S9S_MB_2U_LIB.S9S_MB_2U(SCH_1):PAGE470_I112@PURE_QUANTA.Q_RES(CHIPS)':
 C_PATH='@s9s_mb_2u_lib.s9s_mb_2u(sch_1):page470_i112@pure_quanta.q_res(chips)';

PART_NAME
 R767 'Q_RES_0402LF-1K,1%,1/16W,CHIP,A':;

SECTION_NUMBER 1
 '@S9S_MB_2U_LIB.S9S_MB_2U(SCH_1):PAGE470_I113@PURE_QUANTA.Q_RES(CHIPS)':
 C_PATH='@s9s_mb_2u_lib.s9s_mb_2u(sch_1):page470_i113@pure_quanta.q_res(chips)';

PART_NAME
 R766 'Q_RES_0402LF-1K,1%,1/16W,EMPTYA':;

SECTION_NUMBER 1
 '@S9S_MB_2U_LIB.S9S_MB_2U(SCH_1):PAGE470_I111@PURE_QUANTA.Q_RES(CHIPS)':
 C_PATH='@s9s_mb_2u_lib.s9s_mb_2u(sch_1):page470_i111@pure_quanta.q_res(chips)';

PART_NAME
 R765 'Q_RES_0402LF-0,5%,1/16W,CHIP,CA':;

SECTION_NUMBER 1
 '@S9S_MB_2U_LIB.S9S_MB_2U(SCH_1):PAGE470_I74@PURE_QUANTA.Q_RES(CHIPS)':
 C_PATH='@s9s_mb_2u_lib.s9s_mb_2u(sch_1):page470_i74@pure_quanta.q_res(chips)';

PART_NAME
 R764 'Q_RES_0402LF-0,5%,1/16W,CHIP,CA':;

SECTION_NUMBER 1
 '@S9S_MB_2U_LIB.S9S_MB_2U(SCH_1):PAGE470_I83@PURE_QUANTA.Q_RES(CHIPS)':
 C_PATH='@s9s_mb_2u_lib.s9s_mb_2u(sch_1):page470_i83@pure_quanta.q_res(chips)';

PART_NAME
 R763 'Q_RES_0402LF-10,1%,1/16W,CHIP,A':;

SECTION_NUMBER 1
 '@S9S_MB_2U_LIB.S9S_MB_2U(SCH_1):PAGE470_I70@PURE_QUANTA.Q_RES(CHIPS)':
 C_PATH='@s9s_mb_2u_lib.s9s_mb_2u(sch_1):page470_i70@pure_quanta.q_res(chips)';

PART_NAME
 R762 'Q_RES_0402LF-0,5%,1/16W,CHIP,CA':;

SECTION_NUMBER 1
 '@S9S_MB_2U_LIB.S9S_MB_2U(SCH_1):PAGE470_I71@PURE_QUANTA.Q_RES(CHIPS)':
 C_PATH='@s9s_mb_2u_lib.s9s_mb_2u(sch_1):page470_i71@pure_quanta.q_res(chips)';

PART_NAME
 J42 'SCONN60_QSH03001LDAKTR-SCONN60A':;

SECTION_NUMBER 1
 '@S9S_MB_2U_LIB.S9S_MB_2U(SCH_1):PAGE470_I44@PURE_QUANTA.SCONN60_QSH03001LDAKTR(CHIPS)':
 C_PATH='@s9s_mb_2u_lib.s9s_mb_2u(sch_1):page470_i44@pure_quanta.sconn60_qsh03001l~
daktr(chips)';

PART_NAME
 C552 'Q_CAP_0402-0.1UF,25V,10%,X7R,CA':;

SECTION_NUMBER 1
 '@S9S_MB_2U_LIB.S9S_MB_2U(SCH_1):PAGE470_I96@PURE_QUANTA.Q_CAP(CHIPS)':
 C_PATH='@s9s_mb_2u_lib.s9s_mb_2u(sch_1):page470_i96@pure_quanta.q_cap(chips)';

PART_NAME
 C551 'Q_CAP_C0402-1UF,25V,10%,X6S,CHA':;

SECTION_NUMBER 1
 '@S9S_MB_2U_LIB.S9S_MB_2U(SCH_1):PAGE470_I105@PURE_QUANTA.Q_CAP(CHIPS)':
 C_PATH='@s9s_mb_2u_lib.s9s_mb_2u(sch_1):page470_i105@pure_quanta.q_cap(chips)';

PART_NAME
 C550 'Q_CAP_C0402-1UF,25V,10%,X6S,CHA':;

SECTION_NUMBER 1
 '@S9S_MB_2U_LIB.S9S_MB_2U(SCH_1):PAGE470_I99@PURE_QUANTA.Q_CAP(CHIPS)':
 C_PATH='@s9s_mb_2u_lib.s9s_mb_2u(sch_1):page470_i99@pure_quanta.q_cap(chips)';

PART_NAME
 C549 'Q_CAP_0402-0.1UF,25V,10%,X7R,CA':;

SECTION_NUMBER 1
 '@S9S_MB_2U_LIB.S9S_MB_2U(SCH_1):PAGE470_I129@PURE_QUANTA.Q_CAP(CHIPS)':
 C_PATH='@s9s_mb_2u_lib.s9s_mb_2u(sch_1):page470_i129@pure_quanta.q_cap(chips)';

PART_NAME
 C548 'Q_CAP_0402-0.1UF,25V,10%,X7R,CA':;

SECTION_NUMBER 1
 '@S9S_MB_2U_LIB.S9S_MB_2U(SCH_1):PAGE470_I130@PURE_QUANTA.Q_CAP(CHIPS)':
 C_PATH='@s9s_mb_2u_lib.s9s_mb_2u(sch_1):page470_i130@pure_quanta.q_cap(chips)';

PART_NAME
 C547 'Q_CAP_C0402-1UF,25V,10%,X6S,CHA':;

SECTION_NUMBER 1
 '@S9S_MB_2U_LIB.S9S_MB_2U(SCH_1):PAGE470_I100@PURE_QUANTA.Q_CAP(CHIPS)':
 C_PATH='@s9s_mb_2u_lib.s9s_mb_2u(sch_1):page470_i100@pure_quanta.q_cap(chips)';

PART_NAME
 U18 '74CBTLV3126PW-74CBTLV3126PW,SMA':;

SECTION_NUMBER 1
 '@S9S_MB_2U_LIB.S9S_MB_2U(SCH_1):PAGE469_I129@PURE_QUANTA.74CBTLV3126PW(CHIPS)':
 C_PATH='@s9s_mb_2u_lib.s9s_mb_2u(sch_1):page469_i129@pure_quanta.\74cbtlv3126pw\(~
chips)';

PART_NAME
 U17 '74CBTLV3126PW-74CBTLV3126PW,SMA':;

SECTION_NUMBER 1
 '@S9S_MB_2U_LIB.S9S_MB_2U(SCH_1):PAGE469_I80@PURE_QUANTA.74CBTLV3126PW(CHIPS)':
 C_PATH='@s9s_mb_2u_lib.s9s_mb_2u(sch_1):page469_i80@pure_quanta.\74cbtlv3126pw\(c~
hips)';

PART_NAME
 R761 'Q_RES_0402LF-499,1%,1/16W,CHIPA':;

SECTION_NUMBER 1
 '@S9S_MB_2U_LIB.S9S_MB_2U(SCH_1):PAGE469_I175@PURE_QUANTA.Q_RES(CHIPS)':
 C_PATH='@s9s_mb_2u_lib.s9s_mb_2u(sch_1):page469_i175@pure_quanta.q_res(chips)';

PART_NAME
 R760 'Q_RES_0402LF-499,1%,1/16W,CHIPA':;

SECTION_NUMBER 1
 '@S9S_MB_2U_LIB.S9S_MB_2U(SCH_1):PAGE469_I174@PURE_QUANTA.Q_RES(CHIPS)':
 C_PATH='@s9s_mb_2u_lib.s9s_mb_2u(sch_1):page469_i174@pure_quanta.q_res(chips)';

PART_NAME
 R759 'Q_RES_0402LF-150,1%,1/16W,CHIPA':;

SECTION_NUMBER 1
 '@S9S_MB_2U_LIB.S9S_MB_2U(SCH_1):PAGE469_I169@PURE_QUANTA.Q_RES(CHIPS)':
 C_PATH='@s9s_mb_2u_lib.s9s_mb_2u(sch_1):page469_i169@pure_quanta.q_res(chips)';

PART_NAME
 R758 'Q_RES_0402LF-150,1%,1/16W,CHIPA':;

SECTION_NUMBER 1
 '@S9S_MB_2U_LIB.S9S_MB_2U(SCH_1):PAGE469_I168@PURE_QUANTA.Q_RES(CHIPS)':
 C_PATH='@s9s_mb_2u_lib.s9s_mb_2u(sch_1):page469_i168@pure_quanta.q_res(chips)';

PART_NAME
 R757 'Q_RES_0402LF-120,1%,1/16W,CHIPA':;

SECTION_NUMBER 1
 '@S9S_MB_2U_LIB.S9S_MB_2U(SCH_1):PAGE469_I166@PURE_QUANTA.Q_RES(CHIPS)':
 C_PATH='@s9s_mb_2u_lib.s9s_mb_2u(sch_1):page469_i166@pure_quanta.q_res(chips)';

PART_NAME
 R756 'Q_RES_0402LF-10,1%,1/16W,CHIP,A':;

SECTION_NUMBER 1
 '@S9S_MB_2U_LIB.S9S_MB_2U(SCH_1):PAGE469_I148@PURE_QUANTA.Q_RES(CHIPS)':
 C_PATH='@s9s_mb_2u_lib.s9s_mb_2u(sch_1):page469_i148@pure_quanta.q_res(chips)';

PART_NAME
 R755 'Q_RES_0402LF-10,1%,1/16W,CHIP,A':;

SECTION_NUMBER 1
 '@S9S_MB_2U_LIB.S9S_MB_2U(SCH_1):PAGE469_I147@PURE_QUANTA.Q_RES(CHIPS)':
 C_PATH='@s9s_mb_2u_lib.s9s_mb_2u(sch_1):page469_i147@pure_quanta.q_res(chips)';

PART_NAME
 R754 'Q_RES_0402LF-10,1%,1/16W,CHIP,A':;

SECTION_NUMBER 1
 '@S9S_MB_2U_LIB.S9S_MB_2U(SCH_1):PAGE469_I126@PURE_QUANTA.Q_RES(CHIPS)':
 C_PATH='@s9s_mb_2u_lib.s9s_mb_2u(sch_1):page469_i126@pure_quanta.q_res(chips)';

PART_NAME
 R753 'Q_RES_0402LF-10,1%,1/16W,CHIP,A':;

SECTION_NUMBER 1
 '@S9S_MB_2U_LIB.S9S_MB_2U(SCH_1):PAGE469_I128@PURE_QUANTA.Q_RES(CHIPS)':
 C_PATH='@s9s_mb_2u_lib.s9s_mb_2u(sch_1):page469_i128@pure_quanta.q_res(chips)';

PART_NAME
 R752 'Q_RES_0402LF-10,1%,1/16W,CHIP,A':;

SECTION_NUMBER 1
 '@S9S_MB_2U_LIB.S9S_MB_2U(SCH_1):PAGE469_I127@PURE_QUANTA.Q_RES(CHIPS)':
 C_PATH='@s9s_mb_2u_lib.s9s_mb_2u(sch_1):page469_i127@pure_quanta.q_res(chips)';

PART_NAME
 R751 'Q_RES_0402LF-150,1%,1/16W,CHIPA':;

SECTION_NUMBER 1
 '@S9S_MB_2U_LIB.S9S_MB_2U(SCH_1):PAGE469_I177@PURE_QUANTA.Q_RES(CHIPS)':
 C_PATH='@s9s_mb_2u_lib.s9s_mb_2u(sch_1):page469_i177@pure_quanta.q_res(chips)';

PART_NAME
 R750 'Q_RES_0402LF-150,1%,1/16W,CHIPA':;

SECTION_NUMBER 1
 '@S9S_MB_2U_LIB.S9S_MB_2U(SCH_1):PAGE469_I178@PURE_QUANTA.Q_RES(CHIPS)':
 C_PATH='@s9s_mb_2u_lib.s9s_mb_2u(sch_1):page469_i178@pure_quanta.q_res(chips)';

PART_NAME
 R749 'Q_RES_0402LF-75,1%,1/16W,CHIP,A':;

SECTION_NUMBER 1
 '@S9S_MB_2U_LIB.S9S_MB_2U(SCH_1):PAGE469_I179@PURE_QUANTA.Q_RES(CHIPS)':
 C_PATH='@s9s_mb_2u_lib.s9s_mb_2u(sch_1):page469_i179@pure_quanta.q_res(chips)';

PART_NAME
 R748 'Q_RES_0402LF-75,1%,1/16W,CHIP,A':;

SECTION_NUMBER 1
 '@S9S_MB_2U_LIB.S9S_MB_2U(SCH_1):PAGE469_I180@PURE_QUANTA.Q_RES(CHIPS)':
 C_PATH='@s9s_mb_2u_lib.s9s_mb_2u(sch_1):page469_i180@pure_quanta.q_res(chips)';

PART_NAME
 R747 'Q_RES_0402LF-150,1%,1/16W,CHIPA':;

SECTION_NUMBER 1
 '@S9S_MB_2U_LIB.S9S_MB_2U(SCH_1):PAGE469_I176@PURE_QUANTA.Q_RES(CHIPS)':
 C_PATH='@s9s_mb_2u_lib.s9s_mb_2u(sch_1):page469_i176@pure_quanta.q_res(chips)';

PART_NAME
 R746 'Q_RES_0402LF-0,5%,1/16W,CHIP,CA':;

SECTION_NUMBER 1
 '@S9S_MB_2U_LIB.S9S_MB_2U(SCH_1):PAGE469_I90@PURE_QUANTA.Q_RES(CHIPS)':
 C_PATH='@s9s_mb_2u_lib.s9s_mb_2u(sch_1):page469_i90@pure_quanta.q_res(chips)';

PART_NAME
 C546 'Q_CAP_C0402-1UF,25V,10%,X6S,CHA':;

SECTION_NUMBER 1
 '@S9S_MB_2U_LIB.S9S_MB_2U(SCH_1):PAGE469_I135@PURE_QUANTA.Q_CAP(CHIPS)':
 C_PATH='@s9s_mb_2u_lib.s9s_mb_2u(sch_1):page469_i135@pure_quanta.q_cap(chips)';

PART_NAME
 C545 'Q_CAP_C0402-1UF,25V,10%,X6S,CHA':;

SECTION_NUMBER 1
 '@S9S_MB_2U_LIB.S9S_MB_2U(SCH_1):PAGE469_I93@PURE_QUANTA.Q_CAP(CHIPS)':
 C_PATH='@s9s_mb_2u_lib.s9s_mb_2u(sch_1):page469_i93@pure_quanta.q_cap(chips)';

PART_NAME
 U23 '74LVC1G02GW_SMLF-74LVC1G02GW,IA':;

SECTION_NUMBER 1
 '@S9S_MB_2U_LIB.S9S_MB_2U(SCH_1):PAGE468_I96@PURE_QUANTA.74LVC1G02GW(CHIPS)':
 C_PATH='@s9s_mb_2u_lib.s9s_mb_2u(sch_1):page468_i96@pure_quanta.\74lvc1g02gw\(chi~
ps)';

PART_NAME
 U22 'NC7SB3157_SMLF-NC7SB3157P6X,NCA':;

SECTION_NUMBER 1
 '@S9S_MB_2U_LIB.S9S_MB_2U(SCH_1):PAGE468_I71@PURE_QUANTA.NC7SB3157(CHIPS)':
 C_PATH='@s9s_mb_2u_lib.s9s_mb_2u(sch_1):page468_i71@pure_quanta.nc7sb3157(chips)';

PART_NAME
 U21 'NC7SB3157_SMLF-NC7SB3157P6X,NCA':;

SECTION_NUMBER 1
 '@S9S_MB_2U_LIB.S9S_MB_2U(SCH_1):PAGE468_I58@PURE_QUANTA.NC7SB3157(CHIPS)':
 C_PATH='@s9s_mb_2u_lib.s9s_mb_2u(sch_1):page468_i58@pure_quanta.nc7sb3157(chips)';

PART_NAME
 U16 'NC7SZ66M5X_SMLF-NC7SZ66M5X,NC7A':;

SECTION_NUMBER 1
 '@S9S_MB_2U_LIB.S9S_MB_2U(SCH_1):PAGE468_I88@PURE_QUANTA.NC7SZ66M5X(CHIPS)':
 C_PATH='@s9s_mb_a_lib.s9s_mb_a(sch_1):page468_i88@pure_quanta.nc7sz66m5x(chips)~
';

PART_NAME
 R745 'Q_RES_0402LF-33,5%,1/16W,CHIP,A':;

SECTION_NUMBER 1
 '@S9S_MB_2U_LIB.S9S_MB_2U(SCH_1):PAGE468_I97@PURE_QUANTA.Q_RES(CHIPS)':
 C_PATH='@s9s_mb_2u_lib.s9s_mb_2u(sch_1):page468_i97@pure_quanta.q_res(chips)';

PART_NAME
 R744 'Q_RES_0402LF-75,1%,1/16W,CHIP,A':;

SECTION_NUMBER 1
 '@S9S_MB_2U_LIB.S9S_MB_2U(SCH_1):PAGE468_I77@PURE_QUANTA.Q_RES(CHIPS)':
 C_PATH='@s9s_mb_2u_lib.s9s_mb_2u(sch_1):page468_i77@pure_quanta.q_res(chips)';

PART_NAME
 R743 'Q_RES_0402LF-150,1%,1/16W,CHIPA':;

SECTION_NUMBER 1
 '@S9S_MB_2U_LIB.S9S_MB_2U(SCH_1):PAGE468_I65@PURE_QUANTA.Q_RES(CHIPS)':
 C_PATH='@s9s_mb_2u_lib.s9s_mb_2u(sch_1):page468_i65@pure_quanta.q_res(chips)';

PART_NAME
 R742 'Q_RES_0402LF-75,1%,1/16W,CHIP,A':;

SECTION_NUMBER 1
 '@S9S_MB_2U_LIB.S9S_MB_2U(SCH_1):PAGE468_I78@PURE_QUANTA.Q_RES(CHIPS)':
 C_PATH='@s9s_mb_2u_lib.s9s_mb_2u(sch_1):page468_i78@pure_quanta.q_res(chips)';

PART_NAME
 R741 'Q_RES_0402LF-150,1%,1/16W,CHIPA':;

SECTION_NUMBER 1
 '@S9S_MB_2U_LIB.S9S_MB_2U(SCH_1):PAGE468_I66@PURE_QUANTA.Q_RES(CHIPS)':
 C_PATH='@s9s_mb_2u_lib.s9s_mb_2u(sch_1):page468_i66@pure_quanta.q_res(chips)';

PART_NAME
 R740 'Q_RES_0402LF-10K,1%,1/16W,CHIPA':;

SECTION_NUMBER 1
 '@S9S_MB_2U_LIB.S9S_MB_2U(SCH_1):PAGE468_I107@PURE_QUANTA.Q_RES(CHIPS)':
 C_PATH='@s9s_mb_2u_lib.s9s_mb_2u(sch_1):page468_i107@pure_quanta.q_res(chips)';

PART_NAME
 R739 'Q_RES_0402LF-10K,1%,1/16W,CHIPA':;

SECTION_NUMBER 1
 '@S9S_MB_2U_LIB.S9S_MB_2U(SCH_1):PAGE468_I109@PURE_QUANTA.Q_RES(CHIPS)':
 C_PATH='@s9s_mb_2u_lib.s9s_mb_2u(sch_1):page468_i109@pure_quanta.q_res(chips)';

PART_NAME
 R738 'Q_RES_0402LF-0,5%,1/16W,CHIP,CA':;

SECTION_NUMBER 1
 '@S9S_MB_2U_LIB.S9S_MB_2U(SCH_1):PAGE468_I110@PURE_QUANTA.Q_RES(CHIPS)':
 C_PATH='@s9s_mb_2u_lib.s9s_mb_2u(sch_1):page468_i110@pure_quanta.q_res(chips)';

PART_NAME
 R737 'Q_RES_0402LF-0,5%,1/16W,CHIP,CA':;

SECTION_NUMBER 1
 '@S9S_MB_2U_LIB.S9S_MB_2U(SCH_1):PAGE468_I106@PURE_QUANTA.Q_RES(CHIPS)':
 C_PATH='@s9s_mb_2u_lib.s9s_mb_2u(sch_1):page468_i106@pure_quanta.q_res(chips)';

PART_NAME
 C544 'Q_CAP_0402-0.1UF,25V,10%,X7R,CA':;

SECTION_NUMBER 1
 '@S9S_MB_2U_LIB.S9S_MB_2U(SCH_1):PAGE468_I94@PURE_QUANTA.Q_CAP(CHIPS)':
 C_PATH='@s9s_mb_2u_lib.s9s_mb_2u(sch_1):page468_i94@pure_quanta.q_cap(chips)';

PART_NAME
 C543 'Q_CAP_0402-0.1UF,25V,10%,X7R,CA':;

SECTION_NUMBER 1
 '@S9S_MB_2U_LIB.S9S_MB_2U(SCH_1):PAGE468_I100@PURE_QUANTA.Q_CAP(CHIPS)':
 C_PATH='@s9s_mb_2u_lib.s9s_mb_2u(sch_1):page468_i100@pure_quanta.q_cap(chips)';

PART_NAME
 C542 'Q_CAP_C0402-1UF,25V,10%,X6S,CHA':;

SECTION_NUMBER 1
 '@S9S_MB_2U_LIB.S9S_MB_2U(SCH_1):PAGE468_I80@PURE_QUANTA.Q_CAP(CHIPS)':
 C_PATH='@s9s_mb_2u_lib.s9s_mb_2u(sch_1):page468_i80@pure_quanta.q_cap(chips)';

PART_NAME
 C541 'Q_CAP_C0402-1UF,25V,10%,X6S,CHA':;

SECTION_NUMBER 1
 '@S9S_MB_2U_LIB.S9S_MB_2U(SCH_1):PAGE468_I61@PURE_QUANTA.Q_CAP(CHIPS)':
 C_PATH='@s9s_mb_2u_lib.s9s_mb_2u(sch_1):page468_i61@pure_quanta.q_cap(chips)';

PART_NAME
 C540 'Q_CAP_0402-0.1UF,25V,10%,X7R,CA':;

SECTION_NUMBER 1
 '@S9S_MB_2U_LIB.S9S_MB_2U(SCH_1):PAGE468_I81@PURE_QUANTA.Q_CAP(CHIPS)':
 C_PATH='@s9s_mb_2u_lib.s9s_mb_2u(sch_1):page468_i81@pure_quanta.q_cap(chips)';

PART_NAME
 C539 'Q_CAP_0402-0.1UF,25V,10%,X7R,CA':;

SECTION_NUMBER 1
 '@S9S_MB_2U_LIB.S9S_MB_2U(SCH_1):PAGE468_I70@PURE_QUANTA.Q_CAP(CHIPS)':
 C_PATH='@s9s_mb_2u_lib.s9s_mb_2u(sch_1):page468_i70@pure_quanta.q_cap(chips)';

PART_NAME
 U15 'IDTQS3VH257QG_SMLF-IDTQS3VH257A':;

SECTION_NUMBER 1
 '@S9S_MB_2U_LIB.S9S_MB_2U(SCH_1):PAGE553_I25@PURE_QUANTA.IDTQS3VH257QG(CHIPS)':
 C_PATH='@s9s_mb_2u_lib.s9s_mb_2u(sch_1):page553_i25@pure_quanta.idtqs3vh257qg(chi~
ps)';

PART_NAME
 R1821 'Q_RES_0402LF-0,5%,1/16W,EMPTY,A':;

SECTION_NUMBER 1
 '@S9S_MB_2U_LIB.S9S_MB_2U(SCH_1):PAGE553_I90@PURE_QUANTA.Q_RES(CHIPS)':
 C_PATH='@s9s_mb_2u_lib.s9s_mb_2u(sch_1):page553_i90@pure_quanta.q_res(chips)';

PART_NAME
 R694 'Q_RES_0402LF-0,5%,1/16W,CHIP,CA':;

SECTION_NUMBER 1
 '@S9S_MB_2U_LIB.S9S_MB_2U(SCH_1):PAGE553_I76@PURE_QUANTA.Q_RES(CHIPS)':
 C_PATH='@s9s_mb_2u_lib.s9s_mb_2u(sch_1):page553_i76@pure_quanta.q_res(chips)';

PART_NAME
 R693 'Q_RES_0402LF-0,5%,1/16W,CHIP,CA':;

SECTION_NUMBER 1
 '@S9S_MB_2U_LIB.S9S_MB_2U(SCH_1):PAGE553_I75@PURE_QUANTA.Q_RES(CHIPS)':
 C_PATH='@s9s_mb_2u_lib.s9s_mb_2u(sch_1):page553_i75@pure_quanta.q_res(chips)';

PART_NAME
 R692 'Q_RES_0402LF-0,5%,1/16W,CHIP,CA':;

SECTION_NUMBER 1
 '@S9S_MB_2U_LIB.S9S_MB_2U(SCH_1):PAGE553_I73@PURE_QUANTA.Q_RES(CHIPS)':
 C_PATH='@s9s_mb_2u_lib.s9s_mb_2u(sch_1):page553_i73@pure_quanta.q_res(chips)';

PART_NAME
 R691 'Q_RES_0402LF-0,5%,1/16W,CHIP,CA':;

SECTION_NUMBER 1
 '@S9S_MB_2U_LIB.S9S_MB_2U(SCH_1):PAGE553_I74@PURE_QUANTA.Q_RES(CHIPS)':
 C_PATH='@s9s_mb_2u_lib.s9s_mb_2u(sch_1):page553_i74@pure_quanta.q_res(chips)';

PART_NAME
 R690 'Q_RES_0402LF-0,5%,1/16W,CHIP,CA':;

SECTION_NUMBER 1
 '@S9S_MB_2U_LIB.S9S_MB_2U(SCH_1):PAGE553_I29@PURE_QUANTA.Q_RES(CHIPS)':
 C_PATH='@s9s_mb_2u_lib.s9s_mb_2u(sch_1):page553_i29@pure_quanta.q_res(chips)';

PART_NAME
 R689 'Q_RES_0402LF-0,5%,1/16W,CHIP,CA':;

SECTION_NUMBER 1
 '@S9S_MB_2U_LIB.S9S_MB_2U(SCH_1):PAGE553_I30@PURE_QUANTA.Q_RES(CHIPS)':
 C_PATH='@s9s_mb_2u_lib.s9s_mb_2u(sch_1):page553_i30@pure_quanta.q_res(chips)';

PART_NAME
 R688 'Q_RES_0402LF-0,5%,1/16W,CHIP,CA':;

SECTION_NUMBER 1
 '@S9S_MB_2U_LIB.S9S_MB_2U(SCH_1):PAGE553_I28@PURE_QUANTA.Q_RES(CHIPS)':
 C_PATH='@s9s_mb_2u_lib.s9s_mb_2u(sch_1):page553_i28@pure_quanta.q_res(chips)';

PART_NAME
 R687 'Q_RES_0402LF-0,5%,1/16W,CHIP,CA':;

SECTION_NUMBER 1
 '@S9S_MB_2U_LIB.S9S_MB_2U(SCH_1):PAGE553_I27@PURE_QUANTA.Q_RES(CHIPS)':
 C_PATH='@s9s_mb_2u_lib.s9s_mb_2u(sch_1):page553_i27@pure_quanta.q_res(chips)';

PART_NAME
 R686 'Q_RES_0402LF-240,1%,1/16W,CHIPA':;

SECTION_NUMBER 1
 '@S9S_MB_2U_LIB.S9S_MB_2U(SCH_1):PAGE553_I86@PURE_QUANTA.Q_RES(CHIPS)':
 C_PATH='@s9s_mb_2u_lib.s9s_mb_2u(sch_1):page553_i86@pure_quanta.q_res(chips)';

PART_NAME
 R685 'Q_RES_0402LF-0,5%,1/16W,EMPTY,A':;

SECTION_NUMBER 1
 '@S9S_MB_2U_LIB.S9S_MB_2U(SCH_1):PAGE553_I68@PURE_QUANTA.Q_RES(CHIPS)':
 C_PATH='@s9s_mb_2u_lib.s9s_mb_2u(sch_1):page553_i68@pure_quanta.q_res(chips)';

PART_NAME
 R684 'Q_RES_0402LF-0,5%,1/16W,EMPTY,A':;

SECTION_NUMBER 1
 '@S9S_MB_2U_LIB.S9S_MB_2U(SCH_1):PAGE553_I67@PURE_QUANTA.Q_RES(CHIPS)':
 C_PATH='@s9s_mb_2u_lib.s9s_mb_2u(sch_1):page553_i67@pure_quanta.q_res(chips)';

PART_NAME
 R683 'Q_RES_0402LF-0,5%,1/16W,EMPTY,A':;

SECTION_NUMBER 1
 '@S9S_MB_2U_LIB.S9S_MB_2U(SCH_1):PAGE553_I66@PURE_QUANTA.Q_RES(CHIPS)':
 C_PATH='@s9s_mb_2u_lib.s9s_mb_2u(sch_1):page553_i66@pure_quanta.q_res(chips)';

PART_NAME
 R682 'Q_RES_0402LF-0,5%,1/16W,EMPTY,A':;

SECTION_NUMBER 1
 '@S9S_MB_2U_LIB.S9S_MB_2U(SCH_1):PAGE553_I65@PURE_QUANTA.Q_RES(CHIPS)':
 C_PATH='@s9s_mb_2u_lib.s9s_mb_2u(sch_1):page553_i65@pure_quanta.q_res(chips)';

PART_NAME
 R681 'Q_RES_0402LF-240,1%,1/16W,CHIPA':;

SECTION_NUMBER 1
 '@S9S_MB_2U_LIB.S9S_MB_2U(SCH_1):PAGE553_I87@PURE_QUANTA.Q_RES(CHIPS)':
 C_PATH='@s9s_mb_2u_lib.s9s_mb_2u(sch_1):page553_i87@pure_quanta.q_res(chips)';

PART_NAME
 R680 'Q_RES_0402LF-240,1%,1/16W,CHIPA':;

SECTION_NUMBER 1
 '@S9S_MB_2U_LIB.S9S_MB_2U(SCH_1):PAGE553_I89@PURE_QUANTA.Q_RES(CHIPS)':
 C_PATH='@s9s_mb_2u_lib.s9s_mb_2u(sch_1):page553_i89@pure_quanta.q_res(chips)';

PART_NAME
 R679 'Q_RES_0402LF-240,1%,1/16W,CHIPA':;

SECTION_NUMBER 1
 '@S9S_MB_2U_LIB.S9S_MB_2U(SCH_1):PAGE553_I85@PURE_QUANTA.Q_RES(CHIPS)':
 C_PATH='@s9s_mb_2u_lib.s9s_mb_2u(sch_1):page553_i85@pure_quanta.q_res(chips)';

PART_NAME
 R678 'Q_RES_0402LF-1K,1%,1/16W,CHIP,A':;

SECTION_NUMBER 1
 '@S9S_MB_2U_LIB.S9S_MB_2U(SCH_1):PAGE553_I63@PURE_QUANTA.Q_RES(CHIPS)':
 C_PATH='@s9s_mb_2u_lib.s9s_mb_2u(sch_1):page553_i63@pure_quanta.q_res(chips)';

PART_NAME
 R318 'Q_RES_0402LF-10K,1%,1/16W,CHIPA':;

SECTION_NUMBER 1
 '@S9S_MB_2U_LIB.S9S_MB_2U(SCH_1):PAGE553_I81@PURE_QUANTA.Q_RES(CHIPS)':
 C_PATH='@s9s_mb_2u_lib.s9s_mb_2u(sch_1):page553_i81@pure_quanta.q_res(chips)';

PART_NAME
 R87 'Q_RES_0402LF-1K,5%,1/16W,EMPTYA':;

SECTION_NUMBER 1
 '@S9S_MB_2U_LIB.S9S_MB_2U(SCH_1):PAGE553_I79@PURE_QUANTA.Q_RES(CHIPS)':
 C_PATH='@s9s_mb_2u_lib.s9s_mb_2u(sch_1):page553_i79@pure_quanta.q_res(chips)';

PART_NAME
 C538 'Q_CAP_0402-0.1UF,25V,10%,X7R,CA':;

SECTION_NUMBER 1
 '@S9S_MB_2U_LIB.S9S_MB_2U(SCH_1):PAGE553_I84@PURE_QUANTA.Q_CAP(CHIPS)':
 C_PATH='@s9s_mb_2u_lib.s9s_mb_2u(sch_1):page553_i84@pure_quanta.q_cap(chips)';

PART_NAME
 U14 'IDTQS3VH257QG_SMLF-IDTQS3VH257A':;

SECTION_NUMBER 1
 '@S9S_MB_2U_LIB.S9S_MB_2U(SCH_1):PAGE554_I17@PURE_QUANTA.IDTQS3VH257QG(CHIPS)':
 C_PATH='@s9s_mb_2u_lib.s9s_mb_2u(sch_1):page554_i17@pure_quanta.idtqs3vh257qg(chi~
ps)';

PART_NAME
 R677 'Q_RES_0402LF-0,5%,1/16W,CHIP,CA':;

SECTION_NUMBER 1
 '@S9S_MB_2U_LIB.S9S_MB_2U(SCH_1):PAGE554_I30@PURE_QUANTA.Q_RES(CHIPS)':
 C_PATH='@s9s_mb_2u_lib.s9s_mb_2u(sch_1):page554_i30@pure_quanta.q_res(chips)';

PART_NAME
 R676 'Q_RES_0402LF-0,5%,1/16W,CHIP,CA':;

SECTION_NUMBER 1
 '@S9S_MB_2U_LIB.S9S_MB_2U(SCH_1):PAGE554_I32@PURE_QUANTA.Q_RES(CHIPS)':
 C_PATH='@s9s_mb_2u_lib.s9s_mb_2u(sch_1):page554_i32@pure_quanta.q_res(chips)';

PART_NAME
 R675 'Q_RES_0402LF-0,5%,1/16W,CHIP,CA':;

SECTION_NUMBER 1
 '@S9S_MB_2U_LIB.S9S_MB_2U(SCH_1):PAGE554_I33@PURE_QUANTA.Q_RES(CHIPS)':
 C_PATH='@s9s_mb_2u_lib.s9s_mb_2u(sch_1):page554_i33@pure_quanta.q_res(chips)';

PART_NAME
 R674 'Q_RES_0402LF-0,5%,1/16W,CHIP,CA':;

SECTION_NUMBER 1
 '@S9S_MB_2U_LIB.S9S_MB_2U(SCH_1):PAGE554_I31@PURE_QUANTA.Q_RES(CHIPS)':
 C_PATH='@s9s_mb_2u_lib.s9s_mb_2u(sch_1):page554_i31@pure_quanta.q_res(chips)';

PART_NAME
 R673 'Q_RES_0402LF-0,5%,1/16W,CHIP,CA':;

SECTION_NUMBER 1
 '@S9S_MB_2U_LIB.S9S_MB_2U(SCH_1):PAGE554_I22@PURE_QUANTA.Q_RES(CHIPS)':
 C_PATH='@s9s_mb_2u_lib.s9s_mb_2u(sch_1):page554_i22@pure_quanta.q_res(chips)';

PART_NAME
 R672 'Q_RES_0402LF-0,5%,1/16W,CHIP,CA':;

SECTION_NUMBER 1
 '@S9S_MB_2U_LIB.S9S_MB_2U(SCH_1):PAGE554_I21@PURE_QUANTA.Q_RES(CHIPS)':
 C_PATH='@s9s_mb_2u_lib.s9s_mb_2u(sch_1):page554_i21@pure_quanta.q_res(chips)';

PART_NAME
 R671 'Q_RES_0402LF-0,5%,1/16W,CHIP,CA':;

SECTION_NUMBER 1
 '@S9S_MB_2U_LIB.S9S_MB_2U(SCH_1):PAGE554_I28@PURE_QUANTA.Q_RES(CHIPS)':
 C_PATH='@s9s_mb_2u_lib.s9s_mb_2u(sch_1):page554_i28@pure_quanta.q_res(chips)';

PART_NAME
 R670 'Q_RES_0402LF-0,5%,1/16W,CHIP,CA':;

SECTION_NUMBER 1
 '@S9S_MB_2U_LIB.S9S_MB_2U(SCH_1):PAGE554_I27@PURE_QUANTA.Q_RES(CHIPS)':
 C_PATH='@s9s_mb_2u_lib.s9s_mb_2u(sch_1):page554_i27@pure_quanta.q_res(chips)';

PART_NAME
 R669 'Q_RES_0402LF-240,1%,1/16W,CHIPA':;

SECTION_NUMBER 1
 '@S9S_MB_2U_LIB.S9S_MB_2U(SCH_1):PAGE554_I46@PURE_QUANTA.Q_RES(CHIPS)':
 C_PATH='@s9s_mb_2u_lib.s9s_mb_2u(sch_1):page554_i46@pure_quanta.q_res(chips)';

PART_NAME
 R668 'Q_RES_0402LF-0,5%,1/16W,EMPTY,A':;

SECTION_NUMBER 1
 '@S9S_MB_2U_LIB.S9S_MB_2U(SCH_1):PAGE554_I14@PURE_QUANTA.Q_RES(CHIPS)':
 C_PATH='@s9s_mb_2u_lib.s9s_mb_2u(sch_1):page554_i14@pure_quanta.q_res(chips)';

PART_NAME
 R667 'Q_RES_0402LF-0,5%,1/16W,EMPTY,A':;

SECTION_NUMBER 1
 '@S9S_MB_2U_LIB.S9S_MB_2U(SCH_1):PAGE554_I15@PURE_QUANTA.Q_RES(CHIPS)':
 C_PATH='@s9s_mb_2u_lib.s9s_mb_2u(sch_1):page554_i15@pure_quanta.q_res(chips)';

PART_NAME
 R666 'Q_RES_0402LF-0,5%,1/16W,EMPTY,A':;

SECTION_NUMBER 1
 '@S9S_MB_2U_LIB.S9S_MB_2U(SCH_1):PAGE554_I16@PURE_QUANTA.Q_RES(CHIPS)':
 C_PATH='@s9s_mb_2u_lib.s9s_mb_2u(sch_1):page554_i16@pure_quanta.q_res(chips)';

PART_NAME
 R665 'Q_RES_0402LF-0,5%,1/16W,EMPTY,A':;

SECTION_NUMBER 1
 '@S9S_MB_2U_LIB.S9S_MB_2U(SCH_1):PAGE554_I18@PURE_QUANTA.Q_RES(CHIPS)':
 C_PATH='@s9s_mb_2u_lib.s9s_mb_2u(sch_1):page554_i18@pure_quanta.q_res(chips)';

PART_NAME
 R664 'Q_RES_0402LF-240,1%,1/16W,CHIPA':;

SECTION_NUMBER 1
 '@S9S_MB_2U_LIB.S9S_MB_2U(SCH_1):PAGE554_I47@PURE_QUANTA.Q_RES(CHIPS)':
 C_PATH='@s9s_mb_2u_lib.s9s_mb_2u(sch_1):page554_i47@pure_quanta.q_res(chips)';

PART_NAME
 R663 'Q_RES_0402LF-240,1%,1/16W,CHIPA':;

SECTION_NUMBER 1
 '@S9S_MB_2U_LIB.S9S_MB_2U(SCH_1):PAGE554_I48@PURE_QUANTA.Q_RES(CHIPS)':
 C_PATH='@s9s_mb_2u_lib.s9s_mb_2u(sch_1):page554_i48@pure_quanta.q_res(chips)';

PART_NAME
 R662 'Q_RES_0402LF-240,1%,1/16W,CHIPA':;

SECTION_NUMBER 1
 '@S9S_MB_2U_LIB.S9S_MB_2U(SCH_1):PAGE554_I49@PURE_QUANTA.Q_RES(CHIPS)':
 C_PATH='@s9s_mb_2u_lib.s9s_mb_2u(sch_1):page554_i49@pure_quanta.q_res(chips)';

PART_NAME
 R661 'Q_RES_0402LF-1K,1%,1/16W,CHIP,A':;

SECTION_NUMBER 1
 '@S9S_MB_2U_LIB.S9S_MB_2U(SCH_1):PAGE554_I11@PURE_QUANTA.Q_RES(CHIPS)':
 C_PATH='@s9s_mb_2u_lib.s9s_mb_2u(sch_1):page554_i11@pure_quanta.q_res(chips)';

PART_NAME
 C537 'Q_CAP_0402-0.1UF,25V,10%,X7R,CA':;

SECTION_NUMBER 1
 '@S9S_MB_2U_LIB.S9S_MB_2U(SCH_1):PAGE554_I24@PURE_QUANTA.Q_CAP(CHIPS)':
 C_PATH='@s9s_mb_2u_lib.s9s_mb_2u(sch_1):page554_i24@pure_quanta.q_cap(chips)';

PART_NAME
 U10 'PCA9548APW-PCA9548APW,SMLF,IC,A':;

SECTION_NUMBER 1
 '@S9S_MB_2U_LIB.S9S_MB_2U(SCH_1):PAGE555_I78@PURE_QUANTA.PCA9548APW(CHIPS)':
 C_PATH='@s9s_mb_a_lib.s9s_mb_a(sch_1):page555_i78@pure_quanta.pca9548apw(chips)~
';

PART_NAME
 R1667 'Q_RES_0402LF-10K,1%,1/16W,CHIPA':;

SECTION_NUMBER 1
 '@S9S_MB_2U_LIB.S9S_MB_2U(SCH_1):PAGE555_I157@PURE_QUANTA.Q_RES(CHIPS)':
 C_PATH='@s9s_mb_2u_lib.s9s_mb_2u(sch_1):page555_i157@pure_quanta.q_res(chips)';

PART_NAME
 R1314 'Q_RES_0402LF-2.2K ,5%,1/16W,EMA':;

SECTION_NUMBER 1
 '@S9S_MB_2U_LIB.S9S_MB_2U(SCH_1):PAGE555_I161@PURE_QUANTA.Q_RES(CHIPS)':
 C_PATH='@s9s_mb_2u_lib.s9s_mb_2u(sch_1):page555_i161@pure_quanta.q_res(chips)';

PART_NAME
 R1072 'Q_RES_0402LF-2.2K ,5%,1/16W,CHA':;

SECTION_NUMBER 1
 '@S9S_MB_2U_LIB.S9S_MB_2U(SCH_1):PAGE555_I151@PURE_QUANTA.Q_RES(CHIPS)':
 C_PATH='@s9s_mb_2u_lib.s9s_mb_2u(sch_1):page555_i151@pure_quanta.q_res(chips)';

PART_NAME
 R1071 'Q_RES_0402LF-2.2K ,5%,1/16W,CHA':;

SECTION_NUMBER 1
 '@S9S_MB_2U_LIB.S9S_MB_2U(SCH_1):PAGE555_I154@PURE_QUANTA.Q_RES(CHIPS)':
 C_PATH='@s9s_mb_2u_lib.s9s_mb_2u(sch_1):page555_i154@pure_quanta.q_res(chips)';

PART_NAME
 R1070 'Q_RES_0402LF-2.2K ,5%,1/16W,CHA':;

SECTION_NUMBER 1
 '@S9S_MB_2U_LIB.S9S_MB_2U(SCH_1):PAGE555_I150@PURE_QUANTA.Q_RES(CHIPS)':
 C_PATH='@s9s_mb_2u_lib.s9s_mb_2u(sch_1):page555_i150@pure_quanta.q_res(chips)';

PART_NAME
 R1069 'Q_RES_0402LF-2.2K ,5%,1/16W,CHA':;

SECTION_NUMBER 1
 '@S9S_MB_2U_LIB.S9S_MB_2U(SCH_1):PAGE555_I149@PURE_QUANTA.Q_RES(CHIPS)':
 C_PATH='@s9s_mb_2u_lib.s9s_mb_2u(sch_1):page555_i149@pure_quanta.q_res(chips)';

PART_NAME
 R1068 'Q_RES_0402LF-2.2K ,5%,1/16W,CHA':;

SECTION_NUMBER 1
 '@S9S_MB_2U_LIB.S9S_MB_2U(SCH_1):PAGE555_I147@PURE_QUANTA.Q_RES(CHIPS)':
 C_PATH='@s9s_mb_2u_lib.s9s_mb_2u(sch_1):page555_i147@pure_quanta.q_res(chips)';

PART_NAME
 R1067 'Q_RES_0402LF-2.2K ,5%,1/16W,CHA':;

SECTION_NUMBER 1
 '@S9S_MB_2U_LIB.S9S_MB_2U(SCH_1):PAGE555_I148@PURE_QUANTA.Q_RES(CHIPS)':
 C_PATH='@s9s_mb_2u_lib.s9s_mb_2u(sch_1):page555_i148@pure_quanta.q_res(chips)';

PART_NAME
 R1066 'Q_RES_0402LF-2.2K ,5%,1/16W,EMA':;

SECTION_NUMBER 1
 '@S9S_MB_2U_LIB.S9S_MB_2U(SCH_1):PAGE555_I145@PURE_QUANTA.Q_RES(CHIPS)':
 C_PATH='@s9s_mb_2u_lib.s9s_mb_2u(sch_1):page555_i145@pure_quanta.q_res(chips)';

PART_NAME
 R1065 'Q_RES_0402LF-2.2K ,5%,1/16W,EMA':;

SECTION_NUMBER 1
 '@S9S_MB_2U_LIB.S9S_MB_2U(SCH_1):PAGE555_I146@PURE_QUANTA.Q_RES(CHIPS)':
 C_PATH='@s9s_mb_2u_lib.s9s_mb_2u(sch_1):page555_i146@pure_quanta.q_res(chips)';

PART_NAME
 R1064 'Q_RES_0402LF-0,5%,1/16W,CHIP,CA':;

SECTION_NUMBER 1
 '@S9S_MB_2U_LIB.S9S_MB_2U(SCH_1):PAGE555_I132@PURE_QUANTA.Q_RES(CHIPS)':
 C_PATH='@s9s_mb_2u_lib.s9s_mb_2u(sch_1):page555_i132@pure_quanta.q_res(chips)';

PART_NAME
 R1063 'Q_RES_0402LF-0,5%,1/16W,CHIP,CA':;

SECTION_NUMBER 1
 '@S9S_MB_2U_LIB.S9S_MB_2U(SCH_1):PAGE555_I133@PURE_QUANTA.Q_RES(CHIPS)':
 C_PATH='@s9s_mb_2u_lib.s9s_mb_2u(sch_1):page555_i133@pure_quanta.q_res(chips)';

PART_NAME
 R1062 'Q_RES_0402LF-0,5%,1/16W,CHIP,CA':;

SECTION_NUMBER 1
 '@S9S_MB_2U_LIB.S9S_MB_2U(SCH_1):PAGE555_I130@PURE_QUANTA.Q_RES(CHIPS)':
 C_PATH='@s9s_mb_2u_lib.s9s_mb_2u(sch_1):page555_i130@pure_quanta.q_res(chips)';

PART_NAME
 R1061 'Q_RES_0402LF-0,5%,1/16W,CHIP,CA':;

SECTION_NUMBER 1
 '@S9S_MB_2U_LIB.S9S_MB_2U(SCH_1):PAGE555_I131@PURE_QUANTA.Q_RES(CHIPS)':
 C_PATH='@s9s_mb_2u_lib.s9s_mb_2u(sch_1):page555_i131@pure_quanta.q_res(chips)';

PART_NAME
 R1060 'Q_RES_0402LF-0,5%,1/16W,CHIP,CA':;

SECTION_NUMBER 1
 '@S9S_MB_2U_LIB.S9S_MB_2U(SCH_1):PAGE555_I128@PURE_QUANTA.Q_RES(CHIPS)':
 C_PATH='@s9s_mb_2u_lib.s9s_mb_2u(sch_1):page555_i128@pure_quanta.q_res(chips)';

PART_NAME
 R1059 'Q_RES_0402LF-0,5%,1/16W,CHIP,CA':;

SECTION_NUMBER 1
 '@S9S_MB_2U_LIB.S9S_MB_2U(SCH_1):PAGE555_I129@PURE_QUANTA.Q_RES(CHIPS)':
 C_PATH='@s9s_mb_2u_lib.s9s_mb_2u(sch_1):page555_i129@pure_quanta.q_res(chips)';

PART_NAME
 R1058 'Q_RES_0402LF-0,5%,1/16W,CHIP,CA':;

SECTION_NUMBER 1
 '@S9S_MB_2U_LIB.S9S_MB_2U(SCH_1):PAGE555_I126@PURE_QUANTA.Q_RES(CHIPS)':
 C_PATH='@s9s_mb_2u_lib.s9s_mb_2u(sch_1):page555_i126@pure_quanta.q_res(chips)';

PART_NAME
 R1057 'Q_RES_0402LF-33.2,1%,1/16W,CHIA':;

SECTION_NUMBER 1
 '@S9S_MB_2U_LIB.S9S_MB_2U(SCH_1):PAGE555_I127@PURE_QUANTA.Q_RES(CHIPS)':
 C_PATH='@s9s_mb_2u_lib.s9s_mb_2u(sch_1):page555_i127@pure_quanta.q_res(chips)';

PART_NAME
 R1056 'Q_RES_0402LF-0,5%,1/16W,CHIP,CA':;

SECTION_NUMBER 1
 '@S9S_MB_2U_LIB.S9S_MB_2U(SCH_1):PAGE555_I124@PURE_QUANTA.Q_RES(CHIPS)':
 C_PATH='@s9s_mb_2u_lib.s9s_mb_2u(sch_1):page555_i124@pure_quanta.q_res(chips)';

PART_NAME
 R1055 'Q_RES_0402LF-0,5%,1/16W,CHIP,CA':;

SECTION_NUMBER 1
 '@S9S_MB_2U_LIB.S9S_MB_2U(SCH_1):PAGE555_I125@PURE_QUANTA.Q_RES(CHIPS)':
 C_PATH='@s9s_mb_2u_lib.s9s_mb_2u(sch_1):page555_i125@pure_quanta.q_res(chips)';

PART_NAME
 R1054 'Q_RES_0402LF-0,5%,1/16W,CHIP,CA':;

SECTION_NUMBER 1
 '@S9S_MB_2U_LIB.S9S_MB_2U(SCH_1):PAGE555_I123@PURE_QUANTA.Q_RES(CHIPS)':
 C_PATH='@s9s_mb_2u_lib.s9s_mb_2u(sch_1):page555_i123@pure_quanta.q_res(chips)';

PART_NAME
 R1053 'Q_RES_0402LF-0,5%,1/16W,CHIP,CA':;

SECTION_NUMBER 1
 '@S9S_MB_2U_LIB.S9S_MB_2U(SCH_1):PAGE555_I122@PURE_QUANTA.Q_RES(CHIPS)':
 C_PATH='@s9s_mb_2u_lib.s9s_mb_2u(sch_1):page555_i122@pure_quanta.q_res(chips)';

PART_NAME
 R1052 'Q_RES_0402LF-0,5%,1/16W,CHIP,CA':;

SECTION_NUMBER 1
 '@S9S_MB_2U_LIB.S9S_MB_2U(SCH_1):PAGE555_I120@PURE_QUANTA.Q_RES(CHIPS)':
 C_PATH='@s9s_mb_2u_lib.s9s_mb_2u(sch_1):page555_i120@pure_quanta.q_res(chips)';

PART_NAME
 R1051 'Q_RES_0402LF-0,5%,1/16W,CHIP,CA':;

SECTION_NUMBER 1
 '@S9S_MB_2U_LIB.S9S_MB_2U(SCH_1):PAGE555_I121@PURE_QUANTA.Q_RES(CHIPS)':
 C_PATH='@s9s_mb_2u_lib.s9s_mb_2u(sch_1):page555_i121@pure_quanta.q_res(chips)';

PART_NAME
 R914 'Q_RES_0402LF-2.2K ,5%,1/16W,EMA':;

SECTION_NUMBER 1
 '@S9S_MB_2U_LIB.S9S_MB_2U(SCH_1):PAGE555_I162@PURE_QUANTA.Q_RES(CHIPS)':
 C_PATH='@s9s_mb_2u_lib.s9s_mb_2u(sch_1):page555_i162@pure_quanta.q_res(chips)';

PART_NAME
 R660 'Q_RES_0402LF-0,5%,1/16W,CHIP,CA':;

SECTION_NUMBER 1
 '@S9S_MB_2U_LIB.S9S_MB_2U(SCH_1):PAGE555_I90@PURE_QUANTA.Q_RES(CHIPS)':
 C_PATH='@s9s_mb_2u_lib.s9s_mb_2u(sch_1):page555_i90@pure_quanta.q_res(chips)';

PART_NAME
 R659 'Q_RES_0402LF-0,5%,1/16W,CHIP,CA':;

SECTION_NUMBER 1
 '@S9S_MB_2U_LIB.S9S_MB_2U(SCH_1):PAGE555_I91@PURE_QUANTA.Q_RES(CHIPS)':
 C_PATH='@s9s_mb_2u_lib.s9s_mb_2u(sch_1):page555_i91@pure_quanta.q_res(chips)';

PART_NAME
 R658 'Q_RES_0402LF-2.2K ,5%,1/16W,EMA':;

SECTION_NUMBER 1
 '@S9S_MB_2U_LIB.S9S_MB_2U(SCH_1):PAGE555_I72@PURE_QUANTA.Q_RES(CHIPS)':
 C_PATH='@s9s_mb_2u_lib.s9s_mb_2u(sch_1):page555_i72@pure_quanta.q_res(chips)';

PART_NAME
 R657 'Q_RES_0402LF-2.2K ,5%,1/16W,EMA':;

SECTION_NUMBER 1
 '@S9S_MB_2U_LIB.S9S_MB_2U(SCH_1):PAGE555_I71@PURE_QUANTA.Q_RES(CHIPS)':
 C_PATH='@s9s_mb_2u_lib.s9s_mb_2u(sch_1):page555_i71@pure_quanta.q_res(chips)';

PART_NAME
 R656 'Q_RES_0402LF-2.2K ,5%,1/16W,CHA':;

SECTION_NUMBER 1
 '@S9S_MB_2U_LIB.S9S_MB_2U(SCH_1):PAGE555_I65@PURE_QUANTA.Q_RES(CHIPS)':
 C_PATH='@s9s_mb_2u_lib.s9s_mb_2u(sch_1):page555_i65@pure_quanta.q_res(chips)';

PART_NAME
 R655 'Q_RES_0402LF-2.2K ,5%,1/16W,CHA':;

SECTION_NUMBER 1
 '@S9S_MB_2U_LIB.S9S_MB_2U(SCH_1):PAGE555_I66@PURE_QUANTA.Q_RES(CHIPS)':
 C_PATH='@s9s_mb_2u_lib.s9s_mb_2u(sch_1):page555_i66@pure_quanta.q_res(chips)';

PART_NAME
 R654 'Q_RES_0402LF-2.2K ,5%,1/16W,CHA':;

SECTION_NUMBER 1
 '@S9S_MB_2U_LIB.S9S_MB_2U(SCH_1):PAGE555_I63@PURE_QUANTA.Q_RES(CHIPS)':
 C_PATH='@s9s_mb_2u_lib.s9s_mb_2u(sch_1):page555_i63@pure_quanta.q_res(chips)';

PART_NAME
 R653 'Q_RES_0402LF-2.2K ,5%,1/16W,CHA':;

SECTION_NUMBER 1
 '@S9S_MB_2U_LIB.S9S_MB_2U(SCH_1):PAGE555_I62@PURE_QUANTA.Q_RES(CHIPS)':
 C_PATH='@s9s_mb_2u_lib.s9s_mb_2u(sch_1):page555_i62@pure_quanta.q_res(chips)';

PART_NAME
 R652 'Q_RES_0402LF-2.2K ,5%,1/16W,CHA':;

SECTION_NUMBER 1
 '@S9S_MB_2U_LIB.S9S_MB_2U(SCH_1):PAGE555_I74@PURE_QUANTA.Q_RES(CHIPS)':
 C_PATH='@s9s_mb_2u_lib.s9s_mb_2u(sch_1):page555_i74@pure_quanta.q_res(chips)';

PART_NAME
 R651 'Q_RES_0402LF-2.2K ,5%,1/16W,CHA':;

SECTION_NUMBER 1
 '@S9S_MB_2U_LIB.S9S_MB_2U(SCH_1):PAGE555_I77@PURE_QUANTA.Q_RES(CHIPS)':
 C_PATH='@s9s_mb_2u_lib.s9s_mb_2u(sch_1):page555_i77@pure_quanta.q_res(chips)';

PART_NAME
 R648 'Q_RES_0402LF-0,5%,1/16W,CHIP,CA':;

SECTION_NUMBER 1
 '@S9S_MB_2U_LIB.S9S_MB_2U(SCH_1):PAGE555_I82@PURE_QUANTA.Q_RES(CHIPS)':
 C_PATH='@s9s_mb_2u_lib.s9s_mb_2u(sch_1):page555_i82@pure_quanta.q_res(chips)';

PART_NAME
 R647 'Q_RES_0402LF-33.2,1%,1/16W,CHIA':;

SECTION_NUMBER 1
 '@S9S_MB_2U_LIB.S9S_MB_2U(SCH_1):PAGE555_I84@PURE_QUANTA.Q_RES(CHIPS)':
 C_PATH='@s9s_mb_2u_lib.s9s_mb_2u(sch_1):page555_i84@pure_quanta.q_res(chips)';

PART_NAME
 R646 'Q_RES_0402LF-1K,1%,1/16W,EMPTYA':;

SECTION_NUMBER 1
 '@S9S_MB_2U_LIB.S9S_MB_2U(SCH_1):PAGE555_I56@PURE_QUANTA.Q_RES(CHIPS)':
 C_PATH='@s9s_mb_2u_lib.s9s_mb_2u(sch_1):page555_i56@pure_quanta.q_res(chips)';

PART_NAME
 R645 'Q_RES_0402LF-10K,1%,1/16W,CHIPA':;

SECTION_NUMBER 1
 '@S9S_MB_2U_LIB.S9S_MB_2U(SCH_1):PAGE555_I57@PURE_QUANTA.Q_RES(CHIPS)':
 C_PATH='@s9s_mb_2u_lib.s9s_mb_2u(sch_1):page555_i57@pure_quanta.q_res(chips)';

PART_NAME
 R644 'Q_RES_0402LF-1K,1%,1/16W,CHIP,A':;

SECTION_NUMBER 1
 '@S9S_MB_2U_LIB.S9S_MB_2U(SCH_1):PAGE555_I55@PURE_QUANTA.Q_RES(CHIPS)':
 C_PATH='@s9s_mb_2u_lib.s9s_mb_2u(sch_1):page555_i55@pure_quanta.q_res(chips)';

PART_NAME
 R643 'Q_RES_0402LF-10K,1%,1/16W,EMPTA':;

SECTION_NUMBER 1
 '@S9S_MB_2U_LIB.S9S_MB_2U(SCH_1):PAGE555_I58@PURE_QUANTA.Q_RES(CHIPS)':
 C_PATH='@s9s_mb_2u_lib.s9s_mb_2u(sch_1):page555_i58@pure_quanta.q_res(chips)';

PART_NAME
 R642 'Q_RES_0402LF-1K,1%,1/16W,CHIP,A':;

SECTION_NUMBER 1
 '@S9S_MB_2U_LIB.S9S_MB_2U(SCH_1):PAGE555_I53@PURE_QUANTA.Q_RES(CHIPS)':
 C_PATH='@s9s_mb_2u_lib.s9s_mb_2u(sch_1):page555_i53@pure_quanta.q_res(chips)';

PART_NAME
 R641 'Q_RES_0402LF-10K,1%,1/16W,EMPTA':;

SECTION_NUMBER 1
 '@S9S_MB_2U_LIB.S9S_MB_2U(SCH_1):PAGE555_I54@PURE_QUANTA.Q_RES(CHIPS)':
 C_PATH='@s9s_mb_2u_lib.s9s_mb_2u(sch_1):page555_i54@pure_quanta.q_res(chips)';

PART_NAME
 C536 'Q_CAP_0402-0.1UF,25V,10%,X7R,CA':;

SECTION_NUMBER 1
 '@S9S_MB_2U_LIB.S9S_MB_2U(SCH_1):PAGE555_I14@PURE_QUANTA.Q_CAP(CHIPS)':
 C_PATH='@s9s_mb_2u_lib.s9s_mb_2u(sch_1):page555_i14@pure_quanta.q_cap(chips)';

PART_NAME
 R1765 'Q_RES_0805LF-0,5%,1/8W,EMPTY,CA':;

SECTION_NUMBER 1
 '@S9S_MB_2U_LIB.S9S_MB_2U(SCH_1):PAGE573_I18@PURE_QUANTA.Q_RES(CHIPS)':
 C_PATH='@s9s_mb_2u_lib.s9s_mb_2u(sch_1):page573_i18@pure_quanta.q_res(chips)';

PART_NAME
 R1764 'Q_RES_0402LF-10K,1%,1/16W,CHIPA':;

SECTION_NUMBER 1
 '@S9S_MB_2U_LIB.S9S_MB_2U(SCH_1):PAGE573_I13@PURE_QUANTA.Q_RES(CHIPS)':
 C_PATH='@s9s_mb_2u_lib.s9s_mb_2u(sch_1):page573_i13@pure_quanta.q_res(chips)';

PART_NAME
 R1763 'Q_RES_0402LF-1K,1%,1/16W,EMPTYA':;

SECTION_NUMBER 1
 '@S9S_MB_2U_LIB.S9S_MB_2U(SCH_1):PAGE573_I12@PURE_QUANTA.Q_RES(CHIPS)':
 C_PATH='@s9s_mb_2u_lib.s9s_mb_2u(sch_1):page573_i12@pure_quanta.q_res(chips)';

PART_NAME
 R1747 'Q_RES_0805LF-0,5%,1/8W,CHIP,CSA':;

SECTION_NUMBER 1
 '@S9S_MB_2U_LIB.S9S_MB_2U(SCH_1):PAGE573_I17@PURE_QUANTA.Q_RES(CHIPS)':
 C_PATH='@s9s_mb_2u_lib.s9s_mb_2u(sch_1):page573_i17@pure_quanta.q_res(chips)';

PART_NAME
 C535 'Q_CAP_C0805-22UF,16V,20%,X6S,CA':;

SECTION_NUMBER 1
 '@S9S_MB_2U_LIB.S9S_MB_2U(SCH_1):PAGE573_I15@PURE_QUANTA.Q_CAP(CHIPS)':
 C_PATH='@s9s_mb_2u_lib.s9s_mb_2u(sch_1):page573_i15@pure_quanta.q_cap(chips)';

PART_NAME
 C513 'Q_CAP_C0805-22UF,16V,20%,X6S,CA':;

SECTION_NUMBER 1
 '@S9S_MB_2U_LIB.S9S_MB_2U(SCH_1):PAGE573_I14@PURE_QUANTA.Q_CAP(CHIPS)':
 C_PATH='@s9s_mb_2u_lib.s9s_mb_2u(sch_1):page573_i14@pure_quanta.q_cap(chips)';

PART_NAME
 C1400 'Q_CAP_C0805-100UF,4V,20%,X6S,CA':;

SECTION_NUMBER 1
 '@S9S_MB_2U_LIB.S9S_MB_2U(SCH_1):PAGE614_I112@PURE_QUANTA.Q_CAP(CHIPS)':
 C_PATH='@s9s_mb_2u_lib.s9s_mb_2u(sch_1):page614_i112@pure_quanta.q_cap(chips)';

PART_NAME
 C1399 'Q_CAP_C0805-100UF,4V,20%,X6S,CA':;

SECTION_NUMBER 1
 '@S9S_MB_2U_LIB.S9S_MB_2U(SCH_1):PAGE614_I111@PURE_QUANTA.Q_CAP(CHIPS)':
 C_PATH='@s9s_mb_2u_lib.s9s_mb_2u(sch_1):page614_i111@pure_quanta.q_cap(chips)';

PART_NAME
 C1362 'Q_CAP_C0402-22UF,4V,20%,X6S,CHA':;

SECTION_NUMBER 1
 '@S9S_MB_2U_LIB.S9S_MB_2U(SCH_1):PAGE614_I119@PURE_QUANTA.Q_CAP(CHIPS)':
 C_PATH='@s9s_mb_2u_lib.s9s_mb_2u(sch_1):page614_i119@pure_quanta.q_cap(chips)';

PART_NAME
 C531 'Q_CAP_C0805-100UF,4V,20%,X6S,CA':;

SECTION_NUMBER 1
 '@S9S_MB_2U_LIB.S9S_MB_2U(SCH_1):PAGE614_I115@PURE_QUANTA.Q_CAP(CHIPS)':
 C_PATH='@s9s_mb_2u_lib.s9s_mb_2u(sch_1):page614_i115@pure_quanta.q_cap(chips)';

PART_NAME
 C530 'Q_CAP_C0805-100UF,4V,20%,X6S,CA':;

SECTION_NUMBER 1
 '@S9S_MB_2U_LIB.S9S_MB_2U(SCH_1):PAGE614_I117@PURE_QUANTA.Q_CAP(CHIPS)':
 C_PATH='@s9s_mb_2u_lib.s9s_mb_2u(sch_1):page614_i117@pure_quanta.q_cap(chips)';

PART_NAME
 C529 'Q_CAP_C0805-100UF,4V,20%,X6S,CA':;

SECTION_NUMBER 1
 '@S9S_MB_2U_LIB.S9S_MB_2U(SCH_1):PAGE614_I31@PURE_QUANTA.Q_CAP(CHIPS)':
 C_PATH='@s9s_mb_2u_lib.s9s_mb_2u(sch_1):page614_i31@pure_quanta.q_cap(chips)';

PART_NAME
 C528 'Q_CAP_C0805-100UF,4V,20%,X6S,CA':;

SECTION_NUMBER 1
 '@S9S_MB_2U_LIB.S9S_MB_2U(SCH_1):PAGE614_I118@PURE_QUANTA.Q_CAP(CHIPS)':
 C_PATH='@s9s_mb_2u_lib.s9s_mb_2u(sch_1):page614_i118@pure_quanta.q_cap(chips)';

PART_NAME
 C526 'Q_CAP_C0805-100UF,4V,20%,X6S,CA':;

SECTION_NUMBER 1
 '@S9S_MB_2U_LIB.S9S_MB_2U(SCH_1):PAGE614_I29@PURE_QUANTA.Q_CAP(CHIPS)':
 C_PATH='@s9s_mb_2u_lib.s9s_mb_2u(sch_1):page614_i29@pure_quanta.q_cap(chips)';

PART_NAME
 C525 'Q_CAP_C0805-100UF,4V,20%,X6S,CA':;

SECTION_NUMBER 1
 '@S9S_MB_2U_LIB.S9S_MB_2U(SCH_1):PAGE614_I114@PURE_QUANTA.Q_CAP(CHIPS)':
 C_PATH='@s9s_mb_2u_lib.s9s_mb_2u(sch_1):page614_i114@pure_quanta.q_cap(chips)';

PART_NAME
 C523 'Q_CAP_C0805-100UF,4V,20%,X6S,CA':;

SECTION_NUMBER 1
 '@S9S_MB_2U_LIB.S9S_MB_2U(SCH_1):PAGE614_I28@PURE_QUANTA.Q_CAP(CHIPS)':
 C_PATH='@s9s_mb_2u_lib.s9s_mb_2u(sch_1):page614_i28@pure_quanta.q_cap(chips)';

PART_NAME
 C521 'Q_CAP_C0805-100UF,4V,20%,X6S,CA':;

SECTION_NUMBER 1
 '@S9S_MB_2U_LIB.S9S_MB_2U(SCH_1):PAGE614_I27@PURE_QUANTA.Q_CAP(CHIPS)':
 C_PATH='@s9s_mb_2u_lib.s9s_mb_2u(sch_1):page614_i27@pure_quanta.q_cap(chips)';

PART_NAME
 C520 'Q_CAP_C0805-100UF,4V,20%,X6S,CA':;

SECTION_NUMBER 1
 '@S9S_MB_2U_LIB.S9S_MB_2U(SCH_1):PAGE614_I20@PURE_QUANTA.Q_CAP(CHIPS)':
 C_PATH='@s9s_mb_2u_lib.s9s_mb_2u(sch_1):page614_i20@pure_quanta.q_cap(chips)';

PART_NAME
 C519 'Q_CAP_C0603-47UF,2.5V,20%,X6S,A':;

SECTION_NUMBER 1
 '@S9S_MB_2U_LIB.S9S_MB_2U(SCH_1):PAGE614_I81@PURE_QUANTA.Q_CAP(CHIPS)':
 C_PATH='@s9s_mb_2u_lib.s9s_mb_2u(sch_1):page614_i81@pure_quanta.q_cap(chips)';

PART_NAME
 C517 'Q_CAP_C0805-100UF,4V,20%,X6S,CA':;

SECTION_NUMBER 1
 '@S9S_MB_2U_LIB.S9S_MB_2U(SCH_1):PAGE614_I19@PURE_QUANTA.Q_CAP(CHIPS)':
 C_PATH='@s9s_mb_2u_lib.s9s_mb_2u(sch_1):page614_i19@pure_quanta.q_cap(chips)';

PART_NAME
 C516 'Q_CAP_C0603-47UF,2.5V,20%,X6S,A':;

SECTION_NUMBER 1
 '@S9S_MB_2U_LIB.S9S_MB_2U(SCH_1):PAGE614_I79@PURE_QUANTA.Q_CAP(CHIPS)':
 C_PATH='@s9s_mb_2u_lib.s9s_mb_2u(sch_1):page614_i79@pure_quanta.q_cap(chips)';

PART_NAME
 C514 'Q_CAP_C0805-100UF,4V,20%,X6S,CA':;

SECTION_NUMBER 1
 '@S9S_MB_2U_LIB.S9S_MB_2U(SCH_1):PAGE614_I18@PURE_QUANTA.Q_CAP(CHIPS)':
 C_PATH='@s9s_mb_2u_lib.s9s_mb_2u(sch_1):page614_i18@pure_quanta.q_cap(chips)';

PART_NAME
 C512 'Q_CAP_C0805-100UF,4V,20%,X6S,CA':;

SECTION_NUMBER 1
 '@S9S_MB_2U_LIB.S9S_MB_2U(SCH_1):PAGE614_I78@PURE_QUANTA.Q_CAP(CHIPS)':
 C_PATH='@s9s_mb_2u_lib.s9s_mb_2u(sch_1):page614_i78@pure_quanta.q_cap(chips)';

PART_NAME
 C511 'Q_CAP_C0805-100UF,4V,20%,X6S,CA':;

SECTION_NUMBER 1
 '@S9S_MB_2U_LIB.S9S_MB_2U(SCH_1):PAGE614_I108@PURE_QUANTA.Q_CAP(CHIPS)':
 C_PATH='@s9s_mb_2u_lib.s9s_mb_2u(sch_1):page614_i108@pure_quanta.q_cap(chips)';

PART_NAME
 C510 'Q_CAP_C0805-100UF,4V,20%,X6S,CA':;

SECTION_NUMBER 1
 '@S9S_MB_2U_LIB.S9S_MB_2U(SCH_1):PAGE614_I13@PURE_QUANTA.Q_CAP(CHIPS)':
 C_PATH='@s9s_mb_2u_lib.s9s_mb_2u(sch_1):page614_i13@pure_quanta.q_cap(chips)';

PART_NAME
 C508 'Q_CAP_C0805-100UF,4V,20%,X6S,CA':;

SECTION_NUMBER 1
 '@S9S_MB_2U_LIB.S9S_MB_2U(SCH_1):PAGE614_I77@PURE_QUANTA.Q_CAP(CHIPS)':
 C_PATH='@s9s_mb_2u_lib.s9s_mb_2u(sch_1):page614_i77@pure_quanta.q_cap(chips)';

PART_NAME
 C507 'Q_CAP_C0805-100UF,4V,20%,X6S,CA':;

SECTION_NUMBER 1
 '@S9S_MB_2U_LIB.S9S_MB_2U(SCH_1):PAGE614_I109@PURE_QUANTA.Q_CAP(CHIPS)':
 C_PATH='@s9s_mb_2u_lib.s9s_mb_2u(sch_1):page614_i109@pure_quanta.q_cap(chips)';

PART_NAME
 C506 'Q_CAP_C0805-100UF,4V,20%,X6S,CA':;

SECTION_NUMBER 1
 '@S9S_MB_2U_LIB.S9S_MB_2U(SCH_1):PAGE614_I12@PURE_QUANTA.Q_CAP(CHIPS)':
 C_PATH='@s9s_mb_2u_lib.s9s_mb_2u(sch_1):page614_i12@pure_quanta.q_cap(chips)';

PART_NAME
 C504 'Q_CAP_C0805-100UF,4V,20%,X6S,CA':;

SECTION_NUMBER 1
 '@S9S_MB_2U_LIB.S9S_MB_2U(SCH_1):PAGE614_I56@PURE_QUANTA.Q_CAP(CHIPS)':
 C_PATH='@s9s_mb_2u_lib.s9s_mb_2u(sch_1):page614_i56@pure_quanta.q_cap(chips)';

PART_NAME
 C503 'Q_CAP_C0805-100UF,4V,20%,X6S,CA':;

SECTION_NUMBER 1
 '@S9S_MB_2U_LIB.S9S_MB_2U(SCH_1):PAGE614_I110@PURE_QUANTA.Q_CAP(CHIPS)':
 C_PATH='@s9s_mb_2u_lib.s9s_mb_2u(sch_1):page614_i110@pure_quanta.q_cap(chips)';

PART_NAME
 C502 'Q_CAP_C0805-100UF,4V,20%,X6S,CA':;

SECTION_NUMBER 1
 '@S9S_MB_2U_LIB.S9S_MB_2U(SCH_1):PAGE614_I7@PURE_QUANTA.Q_CAP(CHIPS)':
 C_PATH='@s9s_mb_2u_lib.s9s_mb_2u(sch_1):page614_i7@pure_quanta.q_cap(chips)';

PART_NAME
 C500 'Q_CAP_C0805-100UF,4V,20%,X6S,CA':;

SECTION_NUMBER 1
 '@S9S_MB_2U_LIB.S9S_MB_2U(SCH_1):PAGE614_I55@PURE_QUANTA.Q_CAP(CHIPS)':
 C_PATH='@s9s_mb_2u_lib.s9s_mb_2u(sch_1):page614_i55@pure_quanta.q_cap(chips)';

PART_NAME
 C499 'Q_CAP_C0805-100UF,4V,20%,X6S,CA':;

SECTION_NUMBER 1
 '@S9S_MB_2U_LIB.S9S_MB_2U(SCH_1):PAGE614_I107@PURE_QUANTA.Q_CAP(CHIPS)':
 C_PATH='@s9s_mb_2u_lib.s9s_mb_2u(sch_1):page614_i107@pure_quanta.q_cap(chips)';

PART_NAME
 C498 'Q_CAP_C0805-100UF,4V,20%,X6S,CA':;

SECTION_NUMBER 1
 '@S9S_MB_2U_LIB.S9S_MB_2U(SCH_1):PAGE614_I6@PURE_QUANTA.Q_CAP(CHIPS)':
 C_PATH='@s9s_mb_2u_lib.s9s_mb_2u(sch_1):page614_i6@pure_quanta.q_cap(chips)';

PART_NAME
 C494 'Q_CAP_C0805-100UF,4V,20%,X6S,CA':;

SECTION_NUMBER 1
 '@S9S_MB_2U_LIB.S9S_MB_2U(SCH_1):PAGE614_I1@PURE_QUANTA.Q_CAP(CHIPS)':
 C_PATH='@s9s_mb_2u_lib.s9s_mb_2u(sch_1):page614_i1@pure_quanta.q_cap(chips)';

PART_NAME
 C398 'Q_CAP_C0805-100UF,4V,20%,X6S,CA':;

SECTION_NUMBER 1
 '@S9S_MB_2U_LIB.S9S_MB_2U(SCH_1):PAGE614_I69@PURE_QUANTA.Q_CAP(CHIPS)':
 C_PATH='@s9s_mb_2u_lib.s9s_mb_2u(sch_1):page614_i69@pure_quanta.q_cap(chips)';

PART_NAME
 C396 'Q_CAP_C0805-100UF,4V,20%,X6S,CA':;

SECTION_NUMBER 1
 '@S9S_MB_2U_LIB.S9S_MB_2U(SCH_1):PAGE614_I68@PURE_QUANTA.Q_CAP(CHIPS)':
 C_PATH='@s9s_mb_2u_lib.s9s_mb_2u(sch_1):page614_i68@pure_quanta.q_cap(chips)';

PART_NAME
 C394 'Q_CAP_C0805-100UF,4V,20%,X6S,CA':;

SECTION_NUMBER 1
 '@S9S_MB_2U_LIB.S9S_MB_2U(SCH_1):PAGE614_I63@PURE_QUANTA.Q_CAP(CHIPS)':
 C_PATH='@s9s_mb_2u_lib.s9s_mb_2u(sch_1):page614_i63@pure_quanta.q_cap(chips)';

PART_NAME
 C392 'Q_CAP_C0805-100UF,4V,20%,X6S,CA':;

SECTION_NUMBER 1
 '@S9S_MB_2U_LIB.S9S_MB_2U(SCH_1):PAGE614_I62@PURE_QUANTA.Q_CAP(CHIPS)':
 C_PATH='@s9s_mb_2u_lib.s9s_mb_2u(sch_1):page614_i62@pure_quanta.q_cap(chips)';

PART_NAME
 C390 'Q_CAP_C0805-100UF,4V,20%,X6S,CA':;

SECTION_NUMBER 1
 '@S9S_MB_2U_LIB.S9S_MB_2U(SCH_1):PAGE614_I47@PURE_QUANTA.Q_CAP(CHIPS)':
 C_PATH='@s9s_mb_2u_lib.s9s_mb_2u(sch_1):page614_i47@pure_quanta.q_cap(chips)';

PART_NAME
 C388 'Q_CAP_C0805-100UF,4V,20%,X6S,CA':;

SECTION_NUMBER 1
 '@S9S_MB_2U_LIB.S9S_MB_2U(SCH_1):PAGE614_I46@PURE_QUANTA.Q_CAP(CHIPS)':
 C_PATH='@s9s_mb_2u_lib.s9s_mb_2u(sch_1):page614_i46@pure_quanta.q_cap(chips)';

PART_NAME
 C386 'Q_CAP_C0805-100UF,4V,20%,X6S,CA':;

SECTION_NUMBER 1
 '@S9S_MB_2U_LIB.S9S_MB_2U(SCH_1):PAGE614_I41@PURE_QUANTA.Q_CAP(CHIPS)':
 C_PATH='@s9s_mb_2u_lib.s9s_mb_2u(sch_1):page614_i41@pure_quanta.q_cap(chips)';

PART_NAME
 C383 'Q_CAP_C0805-100UF,4V,20%,X6S,CA':;

SECTION_NUMBER 1
 '@S9S_MB_2U_LIB.S9S_MB_2U(SCH_1):PAGE614_I97@PURE_QUANTA.Q_CAP(CHIPS)':
 C_PATH='@s9s_mb_2u_lib.s9s_mb_2u(sch_1):page614_i97@pure_quanta.q_cap(chips)';

PART_NAME
 C380 'Q_CAP_C0805-100UF,4V,20%,X6S,CA':;

SECTION_NUMBER 1
 '@S9S_MB_2U_LIB.S9S_MB_2U(SCH_1):PAGE614_I95@PURE_QUANTA.Q_CAP(CHIPS)':
 C_PATH='@s9s_mb_2u_lib.s9s_mb_2u(sch_1):page614_i95@pure_quanta.q_cap(chips)';

PART_NAME
 C377 'Q_CAP_C0805-100UF,4V,20%,X6S,CA':;

SECTION_NUMBER 1
 '@S9S_MB_2U_LIB.S9S_MB_2U(SCH_1):PAGE614_I90@PURE_QUANTA.Q_CAP(CHIPS)':
 C_PATH='@s9s_mb_2u_lib.s9s_mb_2u(sch_1):page614_i90@pure_quanta.q_cap(chips)';

PART_NAME
 C374 'Q_CAP_C0805-100UF,4V,20%,X6S,CA':;

SECTION_NUMBER 1
 '@S9S_MB_2U_LIB.S9S_MB_2U(SCH_1):PAGE614_I88@PURE_QUANTA.Q_CAP(CHIPS)':
 C_PATH='@s9s_mb_2u_lib.s9s_mb_2u(sch_1):page614_i88@pure_quanta.q_cap(chips)';

PART_NAME
 C372 'Q_CAP_C0805-100UF,4V,20%,X6S,CA':;

SECTION_NUMBER 1
 '@S9S_MB_2U_LIB.S9S_MB_2U(SCH_1):PAGE614_I83@PURE_QUANTA.Q_CAP(CHIPS)':
 C_PATH='@s9s_mb_2u_lib.s9s_mb_2u(sch_1):page614_i83@pure_quanta.q_cap(chips)';

PART_NAME
 C369 'Q_CAP_C0805-100UF,4V,20%,X6S,CA':;

SECTION_NUMBER 1
 '@S9S_MB_2U_LIB.S9S_MB_2U(SCH_1):PAGE614_I82@PURE_QUANTA.Q_CAP(CHIPS)':
 C_PATH='@s9s_mb_2u_lib.s9s_mb_2u(sch_1):page614_i82@pure_quanta.q_cap(chips)';

PART_NAME
 C366 'Q_CAP_C0805-100UF,4V,20%,X6S,CA':;

SECTION_NUMBER 1
 '@S9S_MB_2U_LIB.S9S_MB_2U(SCH_1):PAGE614_I70@PURE_QUANTA.Q_CAP(CHIPS)':
 C_PATH='@s9s_mb_2u_lib.s9s_mb_2u(sch_1):page614_i70@pure_quanta.q_cap(chips)';

PART_NAME
 C1407 'Q_CAP_C0603-47UF,2.5V,20%,X6S,A':;

SECTION_NUMBER 1
 '@S9S_MB_2U_LIB.S9S_MB_2U(SCH_1):PAGE365_I240@PURE_QUANTA.Q_CAP(CHIPS)':
 C_PATH='@s9s_mb_2u_lib.s9s_mb_2u(sch_1):page365_i240@pure_quanta.q_cap(chips)';

PART_NAME
 C1406 'Q_CAP_C0603-47UF,2.5V,20%,X6S,A':;

SECTION_NUMBER 1
 '@S9S_MB_2U_LIB.S9S_MB_2U(SCH_1):PAGE365_I239@PURE_QUANTA.Q_CAP(CHIPS)':
 C_PATH='@s9s_mb_2u_lib.s9s_mb_2u(sch_1):page365_i239@pure_quanta.q_cap(chips)';

PART_NAME
 C1405 'Q_CAP_C0603-47UF,2.5V,20%,X6S,A':;

SECTION_NUMBER 1
 '@S9S_MB_2U_LIB.S9S_MB_2U(SCH_1):PAGE365_I238@PURE_QUANTA.Q_CAP(CHIPS)':
 C_PATH='@s9s_mb_2u_lib.s9s_mb_2u(sch_1):page365_i238@pure_quanta.q_cap(chips)';

PART_NAME
 C1398 'Q_CAP_C0805-100UF,4V,20%,X6S,CA':;

SECTION_NUMBER 1
 '@S9S_MB_2U_LIB.S9S_MB_2U(SCH_1):PAGE365_I230@PURE_QUANTA.Q_CAP(CHIPS)':
 C_PATH='@s9s_mb_2u_lib.s9s_mb_2u(sch_1):page365_i230@pure_quanta.q_cap(chips)';

PART_NAME
 C1397 'Q_CAP_C0805-100UF,4V,20%,X6S,CA':;

SECTION_NUMBER 1
 '@S9S_MB_2U_LIB.S9S_MB_2U(SCH_1):PAGE365_I229@PURE_QUANTA.Q_CAP(CHIPS)':
 C_PATH='@s9s_mb_2u_lib.s9s_mb_2u(sch_1):page365_i229@pure_quanta.q_cap(chips)';

PART_NAME
 C1396 'Q_CAP_C0805-100UF,4V,20%,X6S,CA':;

SECTION_NUMBER 1
 '@S9S_MB_2U_LIB.S9S_MB_2U(SCH_1):PAGE365_I227@PURE_QUANTA.Q_CAP(CHIPS)':
 C_PATH='@s9s_mb_2u_lib.s9s_mb_2u(sch_1):page365_i227@pure_quanta.q_cap(chips)';

PART_NAME
 C534 'Q_CAP_C0402-22UF,4V,20%,X6S,CHA':;

SECTION_NUMBER 1
 '@S9S_MB_2U_LIB.S9S_MB_2U(SCH_1):PAGE365_I165@PURE_QUANTA.Q_CAP(CHIPS)':
 C_PATH='@s9s_mb_2u_lib.s9s_mb_2u(sch_1):page365_i165@pure_quanta.q_cap(chips)';

PART_NAME
 C533 'Q_CAP_C0603-47UF,2.5V,20%,X6S,A':;

SECTION_NUMBER 1
 '@S9S_MB_2U_LIB.S9S_MB_2U(SCH_1):PAGE365_I164@PURE_QUANTA.Q_CAP(CHIPS)':
 C_PATH='@s9s_mb_2u_lib.s9s_mb_2u(sch_1):page365_i164@pure_quanta.q_cap(chips)';

PART_NAME
 C532 'Q_CAP_C0603-47UF,2.5V,20%,X6S,A':;

SECTION_NUMBER 1
 '@S9S_MB_2U_LIB.S9S_MB_2U(SCH_1):PAGE365_I163@PURE_QUANTA.Q_CAP(CHIPS)':
 C_PATH='@s9s_mb_2u_lib.s9s_mb_2u(sch_1):page365_i163@pure_quanta.q_cap(chips)';

PART_NAME
 C527 'Q_CAP_C0603-47UF,2.5V,20%,X6S,A':;

SECTION_NUMBER 1
 '@S9S_MB_2U_LIB.S9S_MB_2U(SCH_1):PAGE365_I185@PURE_QUANTA.Q_CAP(CHIPS)':
 C_PATH='@s9s_mb_2u_lib.s9s_mb_2u(sch_1):page365_i185@pure_quanta.q_cap(chips)';

PART_NAME
 C524 'Q_CAP_C0603-47UF,2.5V,20%,X6S,A':;

SECTION_NUMBER 1
 '@S9S_MB_2U_LIB.S9S_MB_2U(SCH_1):PAGE365_I186@PURE_QUANTA.Q_CAP(CHIPS)':
 C_PATH='@s9s_mb_2u_lib.s9s_mb_2u(sch_1):page365_i186@pure_quanta.q_cap(chips)';

PART_NAME
 C522 'Q_CAP_C0805-100UF,4V,20%,X6S,CA':;

SECTION_NUMBER 1
 '@S9S_MB_2U_LIB.S9S_MB_2U(SCH_1):PAGE365_I33@PURE_QUANTA.Q_CAP(CHIPS)':
 C_PATH='@s9s_mb_2u_lib.s9s_mb_2u(sch_1):page365_i33@pure_quanta.q_cap(chips)';

PART_NAME
 C518 'Q_CAP_C0603-47UF,2.5V,20%,X6S,A':;

SECTION_NUMBER 1
 '@S9S_MB_2U_LIB.S9S_MB_2U(SCH_1):PAGE365_I130@PURE_QUANTA.Q_CAP(CHIPS)':
 C_PATH='@s9s_mb_2u_lib.s9s_mb_2u(sch_1):page365_i130@pure_quanta.q_cap(chips)';

PART_NAME
 C515 'Q_CAP_C0603-47UF,2.5V,20%,X6S,A':;

SECTION_NUMBER 1
 '@S9S_MB_2U_LIB.S9S_MB_2U(SCH_1):PAGE365_I126@PURE_QUANTA.Q_CAP(CHIPS)':
 C_PATH='@s9s_mb_2u_lib.s9s_mb_2u(sch_1):page365_i126@pure_quanta.q_cap(chips)';

PART_NAME
 C509 'Q_CAP_C0603-47UF,2.5V,20%,X6S,A':;

SECTION_NUMBER 1
 '@S9S_MB_2U_LIB.S9S_MB_2U(SCH_1):PAGE365_I105@PURE_QUANTA.Q_CAP(CHIPS)':
 C_PATH='@s9s_mb_2u_lib.s9s_mb_2u(sch_1):page365_i105@pure_quanta.q_cap(chips)';

PART_NAME
 C505 'Q_CAP_C0805-100UF,4V,20%,X6S,CA':;

SECTION_NUMBER 1
 '@S9S_MB_2U_LIB.S9S_MB_2U(SCH_1):PAGE365_I4@PURE_QUANTA.Q_CAP(CHIPS)':
 C_PATH='@s9s_mb_2u_lib.s9s_mb_2u(sch_1):page365_i4@pure_quanta.q_cap(chips)';

PART_NAME
 C501 'Q_CAP_C0805-100UF,4V,20%,X6S,CA':;

SECTION_NUMBER 1
 '@S9S_MB_2U_LIB.S9S_MB_2U(SCH_1):PAGE365_I3@PURE_QUANTA.Q_CAP(CHIPS)':
 C_PATH='@s9s_mb_2u_lib.s9s_mb_2u(sch_1):page365_i3@pure_quanta.q_cap(chips)';

PART_NAME
 C497 'Q_CAP_C0805-100UF,4V,20%,X6S,CA':;

SECTION_NUMBER 1
 '@S9S_MB_2U_LIB.S9S_MB_2U(SCH_1):PAGE365_I2@PURE_QUANTA.Q_CAP(CHIPS)':
 C_PATH='@s9s_mb_2u_lib.s9s_mb_2u(sch_1):page365_i2@pure_quanta.q_cap(chips)';

PART_NAME
 C496 'Q_CAP_C0805-100UF,4V,20%,X6S,CA':;

SECTION_NUMBER 1
 '@S9S_MB_2U_LIB.S9S_MB_2U(SCH_1):PAGE365_I67@PURE_QUANTA.Q_CAP(CHIPS)':
 C_PATH='@s9s_mb_2u_lib.s9s_mb_2u(sch_1):page365_i67@pure_quanta.q_cap(chips)';

PART_NAME
 C495 'Q_CAP_C0805-100UF,4V,20%,X6S,CA':;

SECTION_NUMBER 1
 '@S9S_MB_2U_LIB.S9S_MB_2U(SCH_1):PAGE365_I14@PURE_QUANTA.Q_CAP(CHIPS)':
 C_PATH='@s9s_mb_2u_lib.s9s_mb_2u(sch_1):page365_i14@pure_quanta.q_cap(chips)';

PART_NAME
 C493 'Q_CAP_C0805-100UF,4V,20%,X6S,CA':;

SECTION_NUMBER 1
 '@S9S_MB_2U_LIB.S9S_MB_2U(SCH_1):PAGE365_I1@PURE_QUANTA.Q_CAP(CHIPS)':
 C_PATH='@s9s_mb_2u_lib.s9s_mb_2u(sch_1):page365_i1@pure_quanta.q_cap(chips)';

PART_NAME
 C492 'Q_CAP_C0805-100UF,4V,20%,X6S,CA':;

SECTION_NUMBER 1
 '@S9S_MB_2U_LIB.S9S_MB_2U(SCH_1):PAGE365_I66@PURE_QUANTA.Q_CAP(CHIPS)':
 C_PATH='@s9s_mb_2u_lib.s9s_mb_2u(sch_1):page365_i66@pure_quanta.q_cap(chips)';

PART_NAME
 C491 'Q_CAP_C0805-100UF,4V,20%,X6S,CA':;

SECTION_NUMBER 1
 '@S9S_MB_2U_LIB.S9S_MB_2U(SCH_1):PAGE365_I10@PURE_QUANTA.Q_CAP(CHIPS)':
 C_PATH='@s9s_mb_2u_lib.s9s_mb_2u(sch_1):page365_i10@pure_quanta.q_cap(chips)';

PART_NAME
 C397 'Q_CAP_C0805-100UF,4V,20%,X6S,CA':;

SECTION_NUMBER 1
 '@S9S_MB_2U_LIB.S9S_MB_2U(SCH_1):PAGE365_I236@PURE_QUANTA.Q_CAP(CHIPS)':
 C_PATH='@s9s_mb_2u_lib.s9s_mb_2u(sch_1):page365_i236@pure_quanta.q_cap(chips)';

PART_NAME
 C395 'Q_CAP_C0805-100UF,4V,20%,X6S,CA':;

SECTION_NUMBER 1
 '@S9S_MB_2U_LIB.S9S_MB_2U(SCH_1):PAGE365_I108@PURE_QUANTA.Q_CAP(CHIPS)':
 C_PATH='@s9s_mb_2u_lib.s9s_mb_2u(sch_1):page365_i108@pure_quanta.q_cap(chips)';

PART_NAME
 C393 'Q_CAP_C0805-100UF,4V,20%,X6S,CA':;

SECTION_NUMBER 1
 '@S9S_MB_2U_LIB.S9S_MB_2U(SCH_1):PAGE365_I215@PURE_QUANTA.Q_CAP(CHIPS)':
 C_PATH='@s9s_mb_2u_lib.s9s_mb_2u(sch_1):page365_i215@pure_quanta.q_cap(chips)';

PART_NAME
 C391 'Q_CAP_C0805-100UF,4V,20%,X6S,CA':;

SECTION_NUMBER 1
 '@S9S_MB_2U_LIB.S9S_MB_2U(SCH_1):PAGE365_I216@PURE_QUANTA.Q_CAP(CHIPS)':
 C_PATH='@s9s_mb_2u_lib.s9s_mb_2u(sch_1):page365_i216@pure_quanta.q_cap(chips)';

PART_NAME
 C389 'Q_CAP_C0805-100UF,4V,20%,X6S,CA':;

SECTION_NUMBER 1
 '@S9S_MB_2U_LIB.S9S_MB_2U(SCH_1):PAGE365_I217@PURE_QUANTA.Q_CAP(CHIPS)':
 C_PATH='@s9s_mb_2u_lib.s9s_mb_2u(sch_1):page365_i217@pure_quanta.q_cap(chips)';

PART_NAME
 C387 'Q_CAP_C0805-100UF,4V,20%,X6S,CA':;

SECTION_NUMBER 1
 '@S9S_MB_2U_LIB.S9S_MB_2U(SCH_1):PAGE365_I112@PURE_QUANTA.Q_CAP(CHIPS)':
 C_PATH='@s9s_mb_2u_lib.s9s_mb_2u(sch_1):page365_i112@pure_quanta.q_cap(chips)';

PART_NAME
 C385 'Q_CAP_C0805-100UF,4V,20%,X6S,CA':;

SECTION_NUMBER 1
 '@S9S_MB_2U_LIB.S9S_MB_2U(SCH_1):PAGE365_I113@PURE_QUANTA.Q_CAP(CHIPS)':
 C_PATH='@s9s_mb_2u_lib.s9s_mb_2u(sch_1):page365_i113@pure_quanta.q_cap(chips)';

PART_NAME
 C384 'Q_CAP_C0603-47UF,2.5V,20%,X6S,A':;

SECTION_NUMBER 1
 '@S9S_MB_2U_LIB.S9S_MB_2U(SCH_1):PAGE365_I187@PURE_QUANTA.Q_CAP(CHIPS)':
 C_PATH='@s9s_mb_2u_lib.s9s_mb_2u(sch_1):page365_i187@pure_quanta.q_cap(chips)';

PART_NAME
 C382 'Q_CAP_C0805-100UF,4V,20%,X6S,CA':;

SECTION_NUMBER 1
 '@S9S_MB_2U_LIB.S9S_MB_2U(SCH_1):PAGE365_I80@PURE_QUANTA.Q_CAP(CHIPS)':
 C_PATH='@s9s_mb_2u_lib.s9s_mb_2u(sch_1):page365_i80@pure_quanta.q_cap(chips)';

PART_NAME
 C381 'Q_CAP_C0603-47UF,2.5V,20%,X6S,A':;

SECTION_NUMBER 1
 '@S9S_MB_2U_LIB.S9S_MB_2U(SCH_1):PAGE365_I189@PURE_QUANTA.Q_CAP(CHIPS)':
 C_PATH='@s9s_mb_2u_lib.s9s_mb_2u(sch_1):page365_i189@pure_quanta.q_cap(chips)';

PART_NAME
 C379 'Q_CAP_C0805-100UF,4V,20%,X6S,CA':;

SECTION_NUMBER 1
 '@S9S_MB_2U_LIB.S9S_MB_2U(SCH_1):PAGE365_I77@PURE_QUANTA.Q_CAP(CHIPS)':
 C_PATH='@s9s_mb_2u_lib.s9s_mb_2u(sch_1):page365_i77@pure_quanta.q_cap(chips)';

PART_NAME
 C376 'Q_CAP_C0805-100UF,4V,20%,X6S,CA':;

SECTION_NUMBER 1
 '@S9S_MB_2U_LIB.S9S_MB_2U(SCH_1):PAGE365_I54@PURE_QUANTA.Q_CAP(CHIPS)':
 C_PATH='@s9s_mb_2u_lib.s9s_mb_2u(sch_1):page365_i54@pure_quanta.q_cap(chips)';

PART_NAME
 C373 'Q_CAP_C0805-100UF,4V,20%,X6S,CA':;

SECTION_NUMBER 1
 '@S9S_MB_2U_LIB.S9S_MB_2U(SCH_1):PAGE365_I52@PURE_QUANTA.Q_CAP(CHIPS)':
 C_PATH='@s9s_mb_2u_lib.s9s_mb_2u(sch_1):page365_i52@pure_quanta.q_cap(chips)';

PART_NAME
 C371 'Q_CAP_C0805-100UF,4V,20%,X6S,CA':;

SECTION_NUMBER 1
 '@S9S_MB_2U_LIB.S9S_MB_2U(SCH_1):PAGE365_I49@PURE_QUANTA.Q_CAP(CHIPS)':
 C_PATH='@s9s_mb_2u_lib.s9s_mb_2u(sch_1):page365_i49@pure_quanta.q_cap(chips)';

PART_NAME
 C370 'Q_CAP_C0805-100UF,4V,20%,X6S,CA':;

SECTION_NUMBER 1
 '@S9S_MB_2U_LIB.S9S_MB_2U(SCH_1):PAGE365_I50@PURE_QUANTA.Q_CAP(CHIPS)':
 C_PATH='@s9s_mb_2u_lib.s9s_mb_2u(sch_1):page365_i50@pure_quanta.q_cap(chips)';

PART_NAME
 C368 'Q_CAP_C0805-100UF,4V,20%,X6S,CA':;

SECTION_NUMBER 1
 '@S9S_MB_2U_LIB.S9S_MB_2U(SCH_1):PAGE365_I44@PURE_QUANTA.Q_CAP(CHIPS)':
 C_PATH='@s9s_mb_2u_lib.s9s_mb_2u(sch_1):page365_i44@pure_quanta.q_cap(chips)';

PART_NAME
 C367 'Q_CAP_C0805-100UF,4V,20%,X6S,CA':;

SECTION_NUMBER 1
 '@S9S_MB_2U_LIB.S9S_MB_2U(SCH_1):PAGE365_I45@PURE_QUANTA.Q_CAP(CHIPS)':
 C_PATH='@s9s_mb_2u_lib.s9s_mb_2u(sch_1):page365_i45@pure_quanta.q_cap(chips)';

PART_NAME
 C365 'Q_CAP_C0805-100UF,4V,20%,X6S,CA':;

SECTION_NUMBER 1
 '@S9S_MB_2U_LIB.S9S_MB_2U(SCH_1):PAGE365_I42@PURE_QUANTA.Q_CAP(CHIPS)':
 C_PATH='@s9s_mb_2u_lib.s9s_mb_2u(sch_1):page365_i42@pure_quanta.q_cap(chips)';

PART_NAME
 C364 'Q_CAP_C0805-100UF,4V,20%,X6S,CA':;

SECTION_NUMBER 1
 '@S9S_MB_2U_LIB.S9S_MB_2U(SCH_1):PAGE365_I43@PURE_QUANTA.Q_CAP(CHIPS)':
 C_PATH='@s9s_mb_2u_lib.s9s_mb_2u(sch_1):page365_i43@pure_quanta.q_cap(chips)';

PART_NAME
 C363 'Q_CAP_C0805-100UF,4V,20%,X6S,CA':;

SECTION_NUMBER 1
 '@S9S_MB_2U_LIB.S9S_MB_2U(SCH_1):PAGE365_I232@PURE_QUANTA.Q_CAP(CHIPS)':
 C_PATH='@s9s_mb_2u_lib.s9s_mb_2u(sch_1):page365_i232@pure_quanta.q_cap(chips)';

PART_NAME
 C362 'Q_CAP_C0805-100UF,4V,20%,X6S,CA':;

SECTION_NUMBER 1
 '@S9S_MB_2U_LIB.S9S_MB_2U(SCH_1):PAGE365_I27@PURE_QUANTA.Q_CAP(CHIPS)':
 C_PATH='@s9s_mb_2u_lib.s9s_mb_2u(sch_1):page365_i27@pure_quanta.q_cap(chips)';

PART_NAME
 C361 'Q_CAP_C0805-100UF,4V,20%,X6S,CA':;

SECTION_NUMBER 1
 '@S9S_MB_2U_LIB.S9S_MB_2U(SCH_1):PAGE365_I28@PURE_QUANTA.Q_CAP(CHIPS)':
 C_PATH='@s9s_mb_2u_lib.s9s_mb_2u(sch_1):page365_i28@pure_quanta.q_cap(chips)';

PART_NAME
 C360 'Q_CAP_C0805-100UF,4V,20%,X6S,CA':;

SECTION_NUMBER 1
 '@S9S_MB_2U_LIB.S9S_MB_2U(SCH_1):PAGE365_I234@PURE_QUANTA.Q_CAP(CHIPS)':
 C_PATH='@s9s_mb_2u_lib.s9s_mb_2u(sch_1):page365_i234@pure_quanta.q_cap(chips)';

PART_NAME
 C359 'Q_CAP_C0805-100UF,4V,20%,X6S,CA':;

SECTION_NUMBER 1
 '@S9S_MB_2U_LIB.S9S_MB_2U(SCH_1):PAGE365_I25@PURE_QUANTA.Q_CAP(CHIPS)':
 C_PATH='@s9s_mb_2u_lib.s9s_mb_2u(sch_1):page365_i25@pure_quanta.q_cap(chips)';

PART_NAME
 C358 'Q_CAP_C0805-100UF,4V,20%,X6S,CA':;

SECTION_NUMBER 1
 '@S9S_MB_2U_LIB.S9S_MB_2U(SCH_1):PAGE365_I26@PURE_QUANTA.Q_CAP(CHIPS)':
 C_PATH='@s9s_mb_2u_lib.s9s_mb_2u(sch_1):page365_i26@pure_quanta.q_cap(chips)';

PART_NAME
 C357 'Q_CAP_C0805-100UF,4V,20%,X6S,CA':;

SECTION_NUMBER 1
 '@S9S_MB_2U_LIB.S9S_MB_2U(SCH_1):PAGE365_I237@PURE_QUANTA.Q_CAP(CHIPS)':
 C_PATH='@s9s_mb_2u_lib.s9s_mb_2u(sch_1):page365_i237@pure_quanta.q_cap(chips)';

PART_NAME
 C356 'Q_CAP_C0805-100UF,4V,20%,X6S,CA':;

SECTION_NUMBER 1
 '@S9S_MB_2U_LIB.S9S_MB_2U(SCH_1):PAGE365_I20@PURE_QUANTA.Q_CAP(CHIPS)':
 C_PATH='@s9s_mb_2u_lib.s9s_mb_2u(sch_1):page365_i20@pure_quanta.q_cap(chips)';

PART_NAME
 C355 'Q_CAP_C0805-100UF,4V,20%,X6S,CA':;

SECTION_NUMBER 1
 '@S9S_MB_2U_LIB.S9S_MB_2U(SCH_1):PAGE365_I22@PURE_QUANTA.Q_CAP(CHIPS)':
 C_PATH='@s9s_mb_2u_lib.s9s_mb_2u(sch_1):page365_i22@pure_quanta.q_cap(chips)';

PART_NAME
 C1404 'Q_CAP_C0805-100UF,4V,20%,X6S,CA':;

SECTION_NUMBER 1
 '@S9S_MB_2U_LIB.S9S_MB_2U(SCH_1):PAGE79_I147@PURE_QUANTA.Q_CAP(CHIPS)':
 C_PATH='@s9s_mb_2u_lib.s9s_mb_2u(sch_1):page79_i147@pure_quanta.q_cap(chips)';

PART_NAME
 C1403 'Q_CAP_C0805-100UF,4V,20%,X6S,CA':;

SECTION_NUMBER 1
 '@S9S_MB_2U_LIB.S9S_MB_2U(SCH_1):PAGE79_I146@PURE_QUANTA.Q_CAP(CHIPS)':
 C_PATH='@s9s_mb_2u_lib.s9s_mb_2u(sch_1):page79_i146@pure_quanta.q_cap(chips)';

PART_NAME
 C1353 'Q_CAP_C0402-22UF,4V,20%,X6S,CHA':;

SECTION_NUMBER 1
 '@S9S_MB_2U_LIB.S9S_MB_2U(SCH_1):PAGE79_I149@PURE_QUANTA.Q_CAP(CHIPS)':
 C_PATH='@s9s_mb_2u_lib.s9s_mb_2u(sch_1):page79_i149@pure_quanta.q_cap(chips)';

PART_NAME
 C487 'Q_CAP_C0805-100UF,4V,20%,X6S,CA':;

SECTION_NUMBER 1
 '@S9S_MB_2U_LIB.S9S_MB_2U(SCH_1):PAGE79_I80@PURE_QUANTA.Q_CAP(CHIPS)':
 C_PATH='@s9s_mb_2u_lib.s9s_mb_2u(sch_1):page79_i80@pure_quanta.q_cap(chips)';

PART_NAME
 C486 'Q_CAP_C0805-100UF,4V,20%,X6S,CA':;

SECTION_NUMBER 1
 '@S9S_MB_2U_LIB.S9S_MB_2U(SCH_1):PAGE79_I79@PURE_QUANTA.Q_CAP(CHIPS)':
 C_PATH='@s9s_mb_2u_lib.s9s_mb_2u(sch_1):page79_i79@pure_quanta.q_cap(chips)';

PART_NAME
 C485 'Q_CAP_C0805-100UF,4V,20%,X6S,CA':;

SECTION_NUMBER 1
 '@S9S_MB_2U_LIB.S9S_MB_2U(SCH_1):PAGE79_I76@PURE_QUANTA.Q_CAP(CHIPS)':
 C_PATH='@s9s_mb_2u_lib.s9s_mb_2u(sch_1):page79_i76@pure_quanta.q_cap(chips)';

PART_NAME
 C484 'Q_CAP_C0805-100UF,4V,20%,X6S,CA':;

SECTION_NUMBER 1
 '@S9S_MB_2U_LIB.S9S_MB_2U(SCH_1):PAGE79_I78@PURE_QUANTA.Q_CAP(CHIPS)':
 C_PATH='@s9s_mb_2u_lib.s9s_mb_2u(sch_1):page79_i78@pure_quanta.q_cap(chips)';

PART_NAME
 C482 'Q_CAP_C0805-100UF,4V,20%,X6S,CA':;

SECTION_NUMBER 1
 '@S9S_MB_2U_LIB.S9S_MB_2U(SCH_1):PAGE79_I74@PURE_QUANTA.Q_CAP(CHIPS)':
 C_PATH='@s9s_mb_2u_lib.s9s_mb_2u(sch_1):page79_i74@pure_quanta.q_cap(chips)';

PART_NAME
 C481 'Q_CAP_C0805-100UF,4V,20%,X6S,CA':;

SECTION_NUMBER 1
 '@S9S_MB_2U_LIB.S9S_MB_2U(SCH_1):PAGE79_I77@PURE_QUANTA.Q_CAP(CHIPS)':
 C_PATH='@s9s_mb_2u_lib.s9s_mb_2u(sch_1):page79_i77@pure_quanta.q_cap(chips)';

PART_NAME
 C479 'Q_CAP_C0805-100UF,4V,20%,X6S,CA':;

SECTION_NUMBER 1
 '@S9S_MB_2U_LIB.S9S_MB_2U(SCH_1):PAGE79_I11@PURE_QUANTA.Q_CAP(CHIPS)':
 C_PATH='@s9s_mb_2u_lib.s9s_mb_2u(sch_1):page79_i11@pure_quanta.q_cap(chips)';

PART_NAME
 C477 'Q_CAP_C0805-100UF,4V,20%,X6S,CA':;

SECTION_NUMBER 1
 '@S9S_MB_2U_LIB.S9S_MB_2U(SCH_1):PAGE79_I10@PURE_QUANTA.Q_CAP(CHIPS)':
 C_PATH='@s9s_mb_2u_lib.s9s_mb_2u(sch_1):page79_i10@pure_quanta.q_cap(chips)';

PART_NAME
 C476 'Q_CAP_C0805-100UF,4V,20%,X6S,CA':;

SECTION_NUMBER 1
 '@S9S_MB_2U_LIB.S9S_MB_2U(SCH_1):PAGE79_I9@PURE_QUANTA.Q_CAP(CHIPS)':
 C_PATH='@s9s_mb_2u_lib.s9s_mb_2u(sch_1):page79_i9@pure_quanta.q_cap(chips)';

PART_NAME
 C475 'Q_CAP_C0603-47UF,2.5V,20%,X6S,A':;

SECTION_NUMBER 1
 '@S9S_MB_2U_LIB.S9S_MB_2U(SCH_1):PAGE79_I131@PURE_QUANTA.Q_CAP(CHIPS)':
 C_PATH='@s9s_mb_2u_lib.s9s_mb_2u(sch_1):page79_i131@pure_quanta.q_cap(chips)';

PART_NAME
 C473 'Q_CAP_C0805-100UF,4V,20%,X6S,CA':;

SECTION_NUMBER 1
 '@S9S_MB_2U_LIB.S9S_MB_2U(SCH_1):PAGE79_I8@PURE_QUANTA.Q_CAP(CHIPS)':
 C_PATH='@s9s_mb_2u_lib.s9s_mb_2u(sch_1):page79_i8@pure_quanta.q_cap(chips)';

PART_NAME
 C472 'Q_CAP_C0603-47UF,2.5V,20%,X6S,A':;

SECTION_NUMBER 1
 '@S9S_MB_2U_LIB.S9S_MB_2U(SCH_1):PAGE79_I132@PURE_QUANTA.Q_CAP(CHIPS)':
 C_PATH='@s9s_mb_2u_lib.s9s_mb_2u(sch_1):page79_i132@pure_quanta.q_cap(chips)';

PART_NAME
 C470 'Q_CAP_C0805-100UF,4V,20%,X6S,CA':;

SECTION_NUMBER 1
 '@S9S_MB_2U_LIB.S9S_MB_2U(SCH_1):PAGE79_I7@PURE_QUANTA.Q_CAP(CHIPS)':
 C_PATH='@s9s_mb_2u_lib.s9s_mb_2u(sch_1):page79_i7@pure_quanta.q_cap(chips)';

PART_NAME
 C468 'Q_CAP_C0805-100UF,4V,20%,X6S,CA':;

SECTION_NUMBER 1
 '@S9S_MB_2U_LIB.S9S_MB_2U(SCH_1):PAGE79_I133@PURE_QUANTA.Q_CAP(CHIPS)':
 C_PATH='@s9s_mb_2u_lib.s9s_mb_2u(sch_1):page79_i133@pure_quanta.q_cap(chips)';

PART_NAME
 C467 'Q_CAP_C0805-100UF,4V,20%,X6S,CA':;

SECTION_NUMBER 1
 '@S9S_MB_2U_LIB.S9S_MB_2U(SCH_1):PAGE79_I126@PURE_QUANTA.Q_CAP(CHIPS)':
 C_PATH='@s9s_mb_2u_lib.s9s_mb_2u(sch_1):page79_i126@pure_quanta.q_cap(chips)';

PART_NAME
 C466 'Q_CAP_C0805-100UF,4V,20%,X6S,CA':;

SECTION_NUMBER 1
 '@S9S_MB_2U_LIB.S9S_MB_2U(SCH_1):PAGE79_I6@PURE_QUANTA.Q_CAP(CHIPS)':
 C_PATH='@s9s_mb_2u_lib.s9s_mb_2u(sch_1):page79_i6@pure_quanta.q_cap(chips)';

PART_NAME
 C464 'Q_CAP_C0805-100UF,4V,20%,X6S,CA':;

SECTION_NUMBER 1
 '@S9S_MB_2U_LIB.S9S_MB_2U(SCH_1):PAGE79_I134@PURE_QUANTA.Q_CAP(CHIPS)':
 C_PATH='@s9s_mb_2u_lib.s9s_mb_2u(sch_1):page79_i134@pure_quanta.q_cap(chips)';

PART_NAME
 C463 'Q_CAP_C0805-100UF,4V,20%,X6S,CA':;

SECTION_NUMBER 1
 '@S9S_MB_2U_LIB.S9S_MB_2U(SCH_1):PAGE79_I127@PURE_QUANTA.Q_CAP(CHIPS)':
 C_PATH='@s9s_mb_2u_lib.s9s_mb_2u(sch_1):page79_i127@pure_quanta.q_cap(chips)';

PART_NAME
 C462 'Q_CAP_C0805-100UF,4V,20%,X6S,CA':;

SECTION_NUMBER 1
 '@S9S_MB_2U_LIB.S9S_MB_2U(SCH_1):PAGE79_I5@PURE_QUANTA.Q_CAP(CHIPS)':
 C_PATH='@s9s_mb_2u_lib.s9s_mb_2u(sch_1):page79_i5@pure_quanta.q_cap(chips)';

PART_NAME
 C460 'Q_CAP_C0805-100UF,4V,20%,X6S,CA':;

SECTION_NUMBER 1
 '@S9S_MB_2U_LIB.S9S_MB_2U(SCH_1):PAGE79_I135@PURE_QUANTA.Q_CAP(CHIPS)':
 C_PATH='@s9s_mb_2u_lib.s9s_mb_2u(sch_1):page79_i135@pure_quanta.q_cap(chips)';

PART_NAME
 C459 'Q_CAP_C0805-100UF,4V,20%,X6S,CA':;

SECTION_NUMBER 1
 '@S9S_MB_2U_LIB.S9S_MB_2U(SCH_1):PAGE79_I128@PURE_QUANTA.Q_CAP(CHIPS)':
 C_PATH='@s9s_mb_2u_lib.s9s_mb_2u(sch_1):page79_i128@pure_quanta.q_cap(chips)';

PART_NAME
 C458 'Q_CAP_C0805-100UF,4V,20%,X6S,CA':;

SECTION_NUMBER 1
 '@S9S_MB_2U_LIB.S9S_MB_2U(SCH_1):PAGE79_I4@PURE_QUANTA.Q_CAP(CHIPS)':
 C_PATH='@s9s_mb_2u_lib.s9s_mb_2u(sch_1):page79_i4@pure_quanta.q_cap(chips)';

PART_NAME
 C456 'Q_CAP_C0805-100UF,4V,20%,X6S,CA':;

SECTION_NUMBER 1
 '@S9S_MB_2U_LIB.S9S_MB_2U(SCH_1):PAGE79_I136@PURE_QUANTA.Q_CAP(CHIPS)':
 C_PATH='@s9s_mb_2u_lib.s9s_mb_2u(sch_1):page79_i136@pure_quanta.q_cap(chips)';

PART_NAME
 C455 'Q_CAP_C0805-100UF,4V,20%,X6S,CA':;

SECTION_NUMBER 1
 '@S9S_MB_2U_LIB.S9S_MB_2U(SCH_1):PAGE79_I129@PURE_QUANTA.Q_CAP(CHIPS)':
 C_PATH='@s9s_mb_2u_lib.s9s_mb_2u(sch_1):page79_i129@pure_quanta.q_cap(chips)';

PART_NAME
 C454 'Q_CAP_C0805-100UF,4V,20%,X6S,CA':;

SECTION_NUMBER 1
 '@S9S_MB_2U_LIB.S9S_MB_2U(SCH_1):PAGE79_I3@PURE_QUANTA.Q_CAP(CHIPS)':
 C_PATH='@s9s_mb_2u_lib.s9s_mb_2u(sch_1):page79_i3@pure_quanta.q_cap(chips)';

PART_NAME
 C450 'Q_CAP_C0805-100UF,4V,20%,X6S,CA':;

SECTION_NUMBER 1
 '@S9S_MB_2U_LIB.S9S_MB_2U(SCH_1):PAGE79_I1@PURE_QUANTA.Q_CAP(CHIPS)':
 C_PATH='@s9s_mb_2u_lib.s9s_mb_2u(sch_1):page79_i1@pure_quanta.q_cap(chips)';

PART_NAME
 C354 'Q_CAP_C0805-100UF,4V,20%,X6S,CA':;

SECTION_NUMBER 1
 '@S9S_MB_2U_LIB.S9S_MB_2U(SCH_1):PAGE79_I116@PURE_QUANTA.Q_CAP(CHIPS)':
 C_PATH='@s9s_mb_2u_lib.s9s_mb_2u(sch_1):page79_i116@pure_quanta.q_cap(chips)';

PART_NAME
 C352 'Q_CAP_C0805-100UF,4V,20%,X6S,CA':;

SECTION_NUMBER 1
 '@S9S_MB_2U_LIB.S9S_MB_2U(SCH_1):PAGE79_I117@PURE_QUANTA.Q_CAP(CHIPS)':
 C_PATH='@s9s_mb_2u_lib.s9s_mb_2u(sch_1):page79_i117@pure_quanta.q_cap(chips)';

PART_NAME
 C350 'Q_CAP_C0805-100UF,4V,20%,X6S,CA':;

SECTION_NUMBER 1
 '@S9S_MB_2U_LIB.S9S_MB_2U(SCH_1):PAGE79_I118@PURE_QUANTA.Q_CAP(CHIPS)':
 C_PATH='@s9s_mb_2u_lib.s9s_mb_2u(sch_1):page79_i118@pure_quanta.q_cap(chips)';

PART_NAME
 C348 'Q_CAP_C0805-100UF,4V,20%,X6S,CA':;

SECTION_NUMBER 1
 '@S9S_MB_2U_LIB.S9S_MB_2U(SCH_1):PAGE79_I119@PURE_QUANTA.Q_CAP(CHIPS)':
 C_PATH='@s9s_mb_2u_lib.s9s_mb_2u(sch_1):page79_i119@pure_quanta.q_cap(chips)';

PART_NAME
 C347 'Q_CAP_C0805-100UF,4V,20%,X6S,CA':;

SECTION_NUMBER 1
 '@S9S_MB_2U_LIB.S9S_MB_2U(SCH_1):PAGE79_I122@PURE_QUANTA.Q_CAP(CHIPS)':
 C_PATH='@s9s_mb_2u_lib.s9s_mb_2u(sch_1):page79_i122@pure_quanta.q_cap(chips)';

PART_NAME
 C346 'Q_CAP_C0805-100UF,4V,20%,X6S,CA':;

SECTION_NUMBER 1
 '@S9S_MB_2U_LIB.S9S_MB_2U(SCH_1):PAGE79_I111@PURE_QUANTA.Q_CAP(CHIPS)':
 C_PATH='@s9s_mb_2u_lib.s9s_mb_2u(sch_1):page79_i111@pure_quanta.q_cap(chips)';

PART_NAME
 C345 'Q_CAP_C0805-100UF,4V,20%,X6S,CA':;

SECTION_NUMBER 1
 '@S9S_MB_2U_LIB.S9S_MB_2U(SCH_1):PAGE79_I123@PURE_QUANTA.Q_CAP(CHIPS)':
 C_PATH='@s9s_mb_2u_lib.s9s_mb_2u(sch_1):page79_i123@pure_quanta.q_cap(chips)';

PART_NAME
 C344 'Q_CAP_C0805-100UF,4V,20%,X6S,CA':;

SECTION_NUMBER 1
 '@S9S_MB_2U_LIB.S9S_MB_2U(SCH_1):PAGE79_I110@PURE_QUANTA.Q_CAP(CHIPS)':
 C_PATH='@s9s_mb_2u_lib.s9s_mb_2u(sch_1):page79_i110@pure_quanta.q_cap(chips)';

PART_NAME
 C343 'Q_CAP_C0805-100UF,4V,20%,X6S,CA':;

SECTION_NUMBER 1
 '@S9S_MB_2U_LIB.S9S_MB_2U(SCH_1):PAGE79_I124@PURE_QUANTA.Q_CAP(CHIPS)':
 C_PATH='@s9s_mb_2u_lib.s9s_mb_2u(sch_1):page79_i124@pure_quanta.q_cap(chips)';

PART_NAME
 C342 'Q_CAP_C0805-100UF,4V,20%,X6S,CA':;

SECTION_NUMBER 1
 '@S9S_MB_2U_LIB.S9S_MB_2U(SCH_1):PAGE79_I109@PURE_QUANTA.Q_CAP(CHIPS)':
 C_PATH='@s9s_mb_2u_lib.s9s_mb_2u(sch_1):page79_i109@pure_quanta.q_cap(chips)';

PART_NAME
 C341 'Q_CAP_C0805-100UF,4V,20%,X6S,CA':;

SECTION_NUMBER 1
 '@S9S_MB_2U_LIB.S9S_MB_2U(SCH_1):PAGE79_I125@PURE_QUANTA.Q_CAP(CHIPS)':
 C_PATH='@s9s_mb_2u_lib.s9s_mb_2u(sch_1):page79_i125@pure_quanta.q_cap(chips)';

PART_NAME
 C328 'Q_CAP_C0805-100UF,4V,20%,X6S,CA':;

SECTION_NUMBER 1
 '@S9S_MB_2U_LIB.S9S_MB_2U(SCH_1):PAGE79_I112@PURE_QUANTA.Q_CAP(CHIPS)':
 C_PATH='@s9s_mb_2u_lib.s9s_mb_2u(sch_1):page79_i112@pure_quanta.q_cap(chips)';

PART_NAME
 C325 'Q_CAP_C0805-100UF,4V,20%,X6S,CA':;

SECTION_NUMBER 1
 '@S9S_MB_2U_LIB.S9S_MB_2U(SCH_1):PAGE79_I114@PURE_QUANTA.Q_CAP(CHIPS)':
 C_PATH='@s9s_mb_2u_lib.s9s_mb_2u(sch_1):page79_i114@pure_quanta.q_cap(chips)';

PART_NAME
 C322 'Q_CAP_C0805-100UF,4V,20%,X6S,CA':;

SECTION_NUMBER 1
 '@S9S_MB_2U_LIB.S9S_MB_2U(SCH_1):PAGE79_I115@PURE_QUANTA.Q_CAP(CHIPS)':
 C_PATH='@s9s_mb_2u_lib.s9s_mb_2u(sch_1):page79_i115@pure_quanta.q_cap(chips)';

PART_NAME
 C1393 'Q_CAP_C0603-47UF,2.5V,20%,X6S,A':;

SECTION_NUMBER 1
 '@S9S_MB_2U_LIB.S9S_MB_2U(SCH_1):PAGE616_I148@PURE_QUANTA.Q_CAP(CHIPS)':
 C_PATH='@s9s_mb_2u_lib.s9s_mb_2u(sch_1):page616_i148@pure_quanta.q_cap(chips)';

PART_NAME
 C1392 'Q_CAP_C0805-100UF,4V,20%,X6S,CA':;

SECTION_NUMBER 1
 '@S9S_MB_2U_LIB.S9S_MB_2U(SCH_1):PAGE616_I145@PURE_QUANTA.Q_CAP(CHIPS)':
 C_PATH='@s9s_mb_2u_lib.s9s_mb_2u(sch_1):page616_i145@pure_quanta.q_cap(chips)';

PART_NAME
 C1391 'Q_CAP_C0603-47UF,2.5V,20%,X6S,A':;

SECTION_NUMBER 1
 '@S9S_MB_2U_LIB.S9S_MB_2U(SCH_1):PAGE616_I147@PURE_QUANTA.Q_CAP(CHIPS)':
 C_PATH='@s9s_mb_2u_lib.s9s_mb_2u(sch_1):page616_i147@pure_quanta.q_cap(chips)';

PART_NAME
 C1390 'Q_CAP_C0805-100UF,4V,20%,X6S,CA':;

SECTION_NUMBER 1
 '@S9S_MB_2U_LIB.S9S_MB_2U(SCH_1):PAGE616_I140@PURE_QUANTA.Q_CAP(CHIPS)':
 C_PATH='@s9s_mb_2u_lib.s9s_mb_2u(sch_1):page616_i140@pure_quanta.q_cap(chips)';

PART_NAME
 C1389 'Q_CAP_C0603-47UF,2.5V,20%,X6S,A':;

SECTION_NUMBER 1
 '@S9S_MB_2U_LIB.S9S_MB_2U(SCH_1):PAGE616_I143@PURE_QUANTA.Q_CAP(CHIPS)':
 C_PATH='@s9s_mb_2u_lib.s9s_mb_2u(sch_1):page616_i143@pure_quanta.q_cap(chips)';

PART_NAME
 C1388 'Q_CAP_C0805-100UF,4V,20%,X6S,CA':;

SECTION_NUMBER 1
 '@S9S_MB_2U_LIB.S9S_MB_2U(SCH_1):PAGE616_I139@PURE_QUANTA.Q_CAP(CHIPS)':
 C_PATH='@s9s_mb_2u_lib.s9s_mb_2u(sch_1):page616_i139@pure_quanta.q_cap(chips)';

PART_NAME
 C1387 'Q_CAP_C0805-100UF,4V,20%,X6S,CA':;

SECTION_NUMBER 1
 '@S9S_MB_2U_LIB.S9S_MB_2U(SCH_1):PAGE616_I141@PURE_QUANTA.Q_CAP(CHIPS)':
 C_PATH='@s9s_mb_2u_lib.s9s_mb_2u(sch_1):page616_i141@pure_quanta.q_cap(chips)';

PART_NAME
 C490 'Q_CAP_C0402-22UF,4V,20%,X6S,CHA':;

SECTION_NUMBER 1
 '@S9S_MB_2U_LIB.S9S_MB_2U(SCH_1):PAGE616_I132@PURE_QUANTA.Q_CAP(CHIPS)':
 C_PATH='@s9s_mb_2u_lib.s9s_mb_2u(sch_1):page616_i132@pure_quanta.q_cap(chips)';

PART_NAME
 C489 'Q_CAP_C0603-47UF,2.5V,20%,X6S,A':;

SECTION_NUMBER 1
 '@S9S_MB_2U_LIB.S9S_MB_2U(SCH_1):PAGE616_I133@PURE_QUANTA.Q_CAP(CHIPS)':
 C_PATH='@s9s_mb_2u_lib.s9s_mb_2u(sch_1):page616_i133@pure_quanta.q_cap(chips)';

PART_NAME
 C488 'Q_CAP_C0603-47UF,2.5V,20%,X6S,A':;

SECTION_NUMBER 1
 '@S9S_MB_2U_LIB.S9S_MB_2U(SCH_1):PAGE616_I134@PURE_QUANTA.Q_CAP(CHIPS)':
 C_PATH='@s9s_mb_2u_lib.s9s_mb_2u(sch_1):page616_i134@pure_quanta.q_cap(chips)';

PART_NAME
 C483 'Q_CAP_C0603-47UF,2.5V,20%,X6S,A':;

SECTION_NUMBER 1
 '@S9S_MB_2U_LIB.S9S_MB_2U(SCH_1):PAGE616_I118@PURE_QUANTA.Q_CAP(CHIPS)':
 C_PATH='@s9s_mb_2u_lib.s9s_mb_2u(sch_1):page616_i118@pure_quanta.q_cap(chips)';

PART_NAME
 C480 'Q_CAP_C0603-47UF,2.5V,20%,X6S,A':;

SECTION_NUMBER 1
 '@S9S_MB_2U_LIB.S9S_MB_2U(SCH_1):PAGE616_I119@PURE_QUANTA.Q_CAP(CHIPS)':
 C_PATH='@s9s_mb_2u_lib.s9s_mb_2u(sch_1):page616_i119@pure_quanta.q_cap(chips)';

PART_NAME
 C478 'Q_CAP_C0805-100UF,4V,20%,X6S,CA':;

SECTION_NUMBER 1
 '@S9S_MB_2U_LIB.S9S_MB_2U(SCH_1):PAGE616_I70@PURE_QUANTA.Q_CAP(CHIPS)':
 C_PATH='@s9s_mb_2u_lib.s9s_mb_2u(sch_1):page616_i70@pure_quanta.q_cap(chips)';

PART_NAME
 C474 'Q_CAP_C0603-47UF,2.5V,20%,X6S,A':;

SECTION_NUMBER 1
 '@S9S_MB_2U_LIB.S9S_MB_2U(SCH_1):PAGE616_I54@PURE_QUANTA.Q_CAP(CHIPS)':
 C_PATH='@s9s_mb_2u_lib.s9s_mb_2u(sch_1):page616_i54@pure_quanta.q_cap(chips)';

PART_NAME
 C471 'Q_CAP_C0603-47UF,2.5V,20%,X6S,A':;

SECTION_NUMBER 1
 '@S9S_MB_2U_LIB.S9S_MB_2U(SCH_1):PAGE616_I52@PURE_QUANTA.Q_CAP(CHIPS)':
 C_PATH='@s9s_mb_2u_lib.s9s_mb_2u(sch_1):page616_i52@pure_quanta.q_cap(chips)';

PART_NAME
 C465 'Q_CAP_C0603-47UF,2.5V,20%,X6S,A':;

SECTION_NUMBER 1
 '@S9S_MB_2U_LIB.S9S_MB_2U(SCH_1):PAGE616_I11@PURE_QUANTA.Q_CAP(CHIPS)':
 C_PATH='@s9s_mb_2u_lib.s9s_mb_2u(sch_1):page616_i11@pure_quanta.q_cap(chips)';

PART_NAME
 C461 'Q_CAP_C0805-100UF,4V,20%,X6S,CA':;

SECTION_NUMBER 1
 '@S9S_MB_2U_LIB.S9S_MB_2U(SCH_1):PAGE616_I9@PURE_QUANTA.Q_CAP(CHIPS)':
 C_PATH='@s9s_mb_2u_lib.s9s_mb_2u(sch_1):page616_i9@pure_quanta.q_cap(chips)';

PART_NAME
 C457 'Q_CAP_C0805-100UF,4V,20%,X6S,CA':;

SECTION_NUMBER 1
 '@S9S_MB_2U_LIB.S9S_MB_2U(SCH_1):PAGE616_I7@PURE_QUANTA.Q_CAP(CHIPS)':
 C_PATH='@s9s_mb_2u_lib.s9s_mb_2u(sch_1):page616_i7@pure_quanta.q_cap(chips)';

PART_NAME
 C453 'Q_CAP_C0805-100UF,4V,20%,X6S,CA':;

SECTION_NUMBER 1
 '@S9S_MB_2U_LIB.S9S_MB_2U(SCH_1):PAGE616_I5@PURE_QUANTA.Q_CAP(CHIPS)':
 C_PATH='@s9s_mb_2u_lib.s9s_mb_2u(sch_1):page616_i5@pure_quanta.q_cap(chips)';

PART_NAME
 C452 'Q_CAP_C0805-100UF,4V,20%,X6S,CA':;

SECTION_NUMBER 1
 '@S9S_MB_2U_LIB.S9S_MB_2U(SCH_1):PAGE616_I27@PURE_QUANTA.Q_CAP(CHIPS)':
 C_PATH='@s9s_mb_2u_lib.s9s_mb_2u(sch_1):page616_i27@pure_quanta.q_cap(chips)';

PART_NAME
 C451 'Q_CAP_C0805-100UF,4V,20%,X6S,CA':;

SECTION_NUMBER 1
 '@S9S_MB_2U_LIB.S9S_MB_2U(SCH_1):PAGE616_I29@PURE_QUANTA.Q_CAP(CHIPS)':
 C_PATH='@s9s_mb_2u_lib.s9s_mb_2u(sch_1):page616_i29@pure_quanta.q_cap(chips)';

PART_NAME
 C449 'Q_CAP_C0805-100UF,4V,20%,X6S,CA':;

SECTION_NUMBER 1
 '@S9S_MB_2U_LIB.S9S_MB_2U(SCH_1):PAGE616_I3@PURE_QUANTA.Q_CAP(CHIPS)':
 C_PATH='@s9s_mb_2u_lib.s9s_mb_2u(sch_1):page616_i3@pure_quanta.q_cap(chips)';

PART_NAME
 C448 'Q_CAP_C0805-100UF,4V,20%,X6S,CA':;

SECTION_NUMBER 1
 '@S9S_MB_2U_LIB.S9S_MB_2U(SCH_1):PAGE616_I23@PURE_QUANTA.Q_CAP(CHIPS)':
 C_PATH='@s9s_mb_2u_lib.s9s_mb_2u(sch_1):page616_i23@pure_quanta.q_cap(chips)';

PART_NAME
 C447 'Q_CAP_C0805-100UF,4V,20%,X6S,CA':;

SECTION_NUMBER 1
 '@S9S_MB_2U_LIB.S9S_MB_2U(SCH_1):PAGE616_I24@PURE_QUANTA.Q_CAP(CHIPS)':
 C_PATH='@s9s_mb_2u_lib.s9s_mb_2u(sch_1):page616_i24@pure_quanta.q_cap(chips)';

PART_NAME
 C353 'Q_CAP_C0805-100UF,4V,20%,X6S,CA':;

SECTION_NUMBER 1
 '@S9S_MB_2U_LIB.S9S_MB_2U(SCH_1):PAGE616_I125@PURE_QUANTA.Q_CAP(CHIPS)':
 C_PATH='@s9s_mb_2u_lib.s9s_mb_2u(sch_1):page616_i125@pure_quanta.q_cap(chips)';

PART_NAME
 C351 'Q_CAP_C0805-100UF,4V,20%,X6S,CA':;

SECTION_NUMBER 1
 '@S9S_MB_2U_LIB.S9S_MB_2U(SCH_1):PAGE616_I126@PURE_QUANTA.Q_CAP(CHIPS)':
 C_PATH='@s9s_mb_2u_lib.s9s_mb_2u(sch_1):page616_i126@pure_quanta.q_cap(chips)';

PART_NAME
 C349 'Q_CAP_C0805-100UF,4V,20%,X6S,CA':;

SECTION_NUMBER 1
 '@S9S_MB_2U_LIB.S9S_MB_2U(SCH_1):PAGE616_I124@PURE_QUANTA.Q_CAP(CHIPS)':
 C_PATH='@s9s_mb_2u_lib.s9s_mb_2u(sch_1):page616_i124@pure_quanta.q_cap(chips)';

PART_NAME
 C340 'Q_CAP_C0603-47UF,2.5V,20%,X6S,A':;

SECTION_NUMBER 1
 '@S9S_MB_2U_LIB.S9S_MB_2U(SCH_1):PAGE616_I120@PURE_QUANTA.Q_CAP(CHIPS)':
 C_PATH='@s9s_mb_2u_lib.s9s_mb_2u(sch_1):page616_i120@pure_quanta.q_cap(chips)';

PART_NAME
 C339 'Q_CAP_C0805-100UF,4V,20%,X6S,CA':;

SECTION_NUMBER 1
 '@S9S_MB_2U_LIB.S9S_MB_2U(SCH_1):PAGE616_I79@PURE_QUANTA.Q_CAP(CHIPS)':
 C_PATH='@s9s_mb_2u_lib.s9s_mb_2u(sch_1):page616_i79@pure_quanta.q_cap(chips)';

PART_NAME
 C338 'Q_CAP_C0805-100UF,4V,20%,X6S,CA':;

SECTION_NUMBER 1
 '@S9S_MB_2U_LIB.S9S_MB_2U(SCH_1):PAGE616_I82@PURE_QUANTA.Q_CAP(CHIPS)':
 C_PATH='@s9s_mb_2u_lib.s9s_mb_2u(sch_1):page616_i82@pure_quanta.q_cap(chips)';

PART_NAME
 C337 'Q_CAP_C0603-47UF,2.5V,20%,X6S,A':;

SECTION_NUMBER 1
 '@S9S_MB_2U_LIB.S9S_MB_2U(SCH_1):PAGE616_I121@PURE_QUANTA.Q_CAP(CHIPS)':
 C_PATH='@s9s_mb_2u_lib.s9s_mb_2u(sch_1):page616_i121@pure_quanta.q_cap(chips)';

PART_NAME
 C336 'Q_CAP_C0805-100UF,4V,20%,X6S,CA':;

SECTION_NUMBER 1
 '@S9S_MB_2U_LIB.S9S_MB_2U(SCH_1):PAGE616_I76@PURE_QUANTA.Q_CAP(CHIPS)':
 C_PATH='@s9s_mb_2u_lib.s9s_mb_2u(sch_1):page616_i76@pure_quanta.q_cap(chips)';

PART_NAME
 C335 'Q_CAP_C0805-100UF,4V,20%,X6S,CA':;

SECTION_NUMBER 1
 '@S9S_MB_2U_LIB.S9S_MB_2U(SCH_1):PAGE616_I80@PURE_QUANTA.Q_CAP(CHIPS)':
 C_PATH='@s9s_mb_2u_lib.s9s_mb_2u(sch_1):page616_i80@pure_quanta.q_cap(chips)';

PART_NAME
 C333 'Q_CAP_C0805-100UF,4V,20%,X6S,CA':;

SECTION_NUMBER 1
 '@S9S_MB_2U_LIB.S9S_MB_2U(SCH_1):PAGE616_I66@PURE_QUANTA.Q_CAP(CHIPS)':
 C_PATH='@s9s_mb_2u_lib.s9s_mb_2u(sch_1):page616_i66@pure_quanta.q_cap(chips)';

PART_NAME
 C332 'Q_CAP_C0805-100UF,4V,20%,X6S,CA':;

SECTION_NUMBER 1
 '@S9S_MB_2U_LIB.S9S_MB_2U(SCH_1):PAGE616_I69@PURE_QUANTA.Q_CAP(CHIPS)':
 C_PATH='@s9s_mb_2u_lib.s9s_mb_2u(sch_1):page616_i69@pure_quanta.q_cap(chips)';

PART_NAME
 C330 'Q_CAP_C0805-100UF,4V,20%,X6S,CA':;

SECTION_NUMBER 1
 '@S9S_MB_2U_LIB.S9S_MB_2U(SCH_1):PAGE616_I65@PURE_QUANTA.Q_CAP(CHIPS)':
 C_PATH='@s9s_mb_2u_lib.s9s_mb_2u(sch_1):page616_i65@pure_quanta.q_cap(chips)';

PART_NAME
 C329 'Q_CAP_C0805-100UF,4V,20%,X6S,CA':;

SECTION_NUMBER 1
 '@S9S_MB_2U_LIB.S9S_MB_2U(SCH_1):PAGE616_I68@PURE_QUANTA.Q_CAP(CHIPS)':
 C_PATH='@s9s_mb_2u_lib.s9s_mb_2u(sch_1):page616_i68@pure_quanta.q_cap(chips)';

PART_NAME
 C327 'Q_CAP_C0805-100UF,4V,20%,X6S,CA':;

SECTION_NUMBER 1
 '@S9S_MB_2U_LIB.S9S_MB_2U(SCH_1):PAGE616_I62@PURE_QUANTA.Q_CAP(CHIPS)':
 C_PATH='@s9s_mb_2u_lib.s9s_mb_2u(sch_1):page616_i62@pure_quanta.q_cap(chips)';

PART_NAME
 C326 'Q_CAP_C0805-100UF,4V,20%,X6S,CA':;

SECTION_NUMBER 1
 '@S9S_MB_2U_LIB.S9S_MB_2U(SCH_1):PAGE616_I67@PURE_QUANTA.Q_CAP(CHIPS)':
 C_PATH='@s9s_mb_2u_lib.s9s_mb_2u(sch_1):page616_i67@pure_quanta.q_cap(chips)';

PART_NAME
 C324 'Q_CAP_C0805-100UF,4V,20%,X6S,CA':;

SECTION_NUMBER 1
 '@S9S_MB_2U_LIB.S9S_MB_2U(SCH_1):PAGE616_I58@PURE_QUANTA.Q_CAP(CHIPS)':
 C_PATH='@s9s_mb_2u_lib.s9s_mb_2u(sch_1):page616_i58@pure_quanta.q_cap(chips)';

PART_NAME
 C323 'Q_CAP_C0805-100UF,4V,20%,X6S,CA':;

SECTION_NUMBER 1
 '@S9S_MB_2U_LIB.S9S_MB_2U(SCH_1):PAGE616_I60@PURE_QUANTA.Q_CAP(CHIPS)':
 C_PATH='@s9s_mb_2u_lib.s9s_mb_2u(sch_1):page616_i60@pure_quanta.q_cap(chips)';

PART_NAME
 C321 'Q_CAP_C0805-100UF,4V,20%,X6S,CA':;

SECTION_NUMBER 1
 '@S9S_MB_2U_LIB.S9S_MB_2U(SCH_1):PAGE616_I56@PURE_QUANTA.Q_CAP(CHIPS)':
 C_PATH='@s9s_mb_2u_lib.s9s_mb_2u(sch_1):page616_i56@pure_quanta.q_cap(chips)';

PART_NAME
 C320 'Q_CAP_C0805-100UF,4V,20%,X6S,CA':;

SECTION_NUMBER 1
 '@S9S_MB_2U_LIB.S9S_MB_2U(SCH_1):PAGE616_I59@PURE_QUANTA.Q_CAP(CHIPS)':
 C_PATH='@s9s_mb_2u_lib.s9s_mb_2u(sch_1):page616_i59@pure_quanta.q_cap(chips)';

PART_NAME
 C318 'Q_CAP_C0805-100UF,4V,20%,X6S,CA':;

SECTION_NUMBER 1
 '@S9S_MB_2U_LIB.S9S_MB_2U(SCH_1):PAGE616_I39@PURE_QUANTA.Q_CAP(CHIPS)':
 C_PATH='@s9s_mb_2u_lib.s9s_mb_2u(sch_1):page616_i39@pure_quanta.q_cap(chips)';

PART_NAME
 C317 'Q_CAP_C0805-100UF,4V,20%,X6S,CA':;

SECTION_NUMBER 1
 '@S9S_MB_2U_LIB.S9S_MB_2U(SCH_1):PAGE616_I41@PURE_QUANTA.Q_CAP(CHIPS)':
 C_PATH='@s9s_mb_2u_lib.s9s_mb_2u(sch_1):page616_i41@pure_quanta.q_cap(chips)';

PART_NAME
 C316 'Q_CAP_C0805-100UF,4V,20%,X6S,CA':;

SECTION_NUMBER 1
 '@S9S_MB_2U_LIB.S9S_MB_2U(SCH_1):PAGE616_I129@PURE_QUANTA.Q_CAP(CHIPS)':
 C_PATH='@s9s_mb_2u_lib.s9s_mb_2u(sch_1):page616_i129@pure_quanta.q_cap(chips)';

PART_NAME
 C315 'Q_CAP_C0805-100UF,4V,20%,X6S,CA':;

SECTION_NUMBER 1
 '@S9S_MB_2U_LIB.S9S_MB_2U(SCH_1):PAGE616_I37@PURE_QUANTA.Q_CAP(CHIPS)':
 C_PATH='@s9s_mb_2u_lib.s9s_mb_2u(sch_1):page616_i37@pure_quanta.q_cap(chips)';

PART_NAME
 C314 'Q_CAP_C0805-100UF,4V,20%,X6S,CA':;

SECTION_NUMBER 1
 '@S9S_MB_2U_LIB.S9S_MB_2U(SCH_1):PAGE616_I40@PURE_QUANTA.Q_CAP(CHIPS)':
 C_PATH='@s9s_mb_2u_lib.s9s_mb_2u(sch_1):page616_i40@pure_quanta.q_cap(chips)';

PART_NAME
 C313 'Q_CAP_C0805-100UF,4V,20%,X6S,CA':;

SECTION_NUMBER 1
 '@S9S_MB_2U_LIB.S9S_MB_2U(SCH_1):PAGE616_I128@PURE_QUANTA.Q_CAP(CHIPS)':
 C_PATH='@s9s_mb_2u_lib.s9s_mb_2u(sch_1):page616_i128@pure_quanta.q_cap(chips)';

PART_NAME
 C312 'Q_CAP_C0805-100UF,4V,20%,X6S,CA':;

SECTION_NUMBER 1
 '@S9S_MB_2U_LIB.S9S_MB_2U(SCH_1):PAGE616_I32@PURE_QUANTA.Q_CAP(CHIPS)':
 C_PATH='@s9s_mb_2u_lib.s9s_mb_2u(sch_1):page616_i32@pure_quanta.q_cap(chips)';

PART_NAME
 C311 'Q_CAP_C0805-100UF,4V,20%,X6S,CA':;

SECTION_NUMBER 1
 '@S9S_MB_2U_LIB.S9S_MB_2U(SCH_1):PAGE616_I35@PURE_QUANTA.Q_CAP(CHIPS)':
 C_PATH='@s9s_mb_2u_lib.s9s_mb_2u(sch_1):page616_i35@pure_quanta.q_cap(chips)';

PART_NAME
 C446 'Q_CAP_C0402-22UF,4V,20%,X6S,CHA':;

SECTION_NUMBER 1
 '@S9S_MB_2U_LIB.S9S_MB_2U(SCH_1):PAGE615_I105@PURE_QUANTA.Q_CAP(CHIPS)':
 C_PATH='@s9s_mb_2u_lib.s9s_mb_2u(sch_1):page615_i105@pure_quanta.q_cap(chips)';

PART_NAME
 C445 'Q_CAP_C0402-22UF,4V,20%,X6S,CHA':;

SECTION_NUMBER 1
 '@S9S_MB_2U_LIB.S9S_MB_2U(SCH_1):PAGE615_I102@PURE_QUANTA.Q_CAP(CHIPS)':
 C_PATH='@s9s_mb_2u_lib.s9s_mb_2u(sch_1):page615_i102@pure_quanta.q_cap(chips)';

PART_NAME
 C444 'Q_CAP_C0402-22UF,4V,20%,X6S,CHA':;

SECTION_NUMBER 1
 '@S9S_MB_2U_LIB.S9S_MB_2U(SCH_1):PAGE615_I101@PURE_QUANTA.Q_CAP(CHIPS)':
 C_PATH='@s9s_mb_2u_lib.s9s_mb_2u(sch_1):page615_i101@pure_quanta.q_cap(chips)';

PART_NAME
 C443 'Q_CAP_C0402-22UF,4V,20%,X6S,CHA':;

SECTION_NUMBER 1
 '@S9S_MB_2U_LIB.S9S_MB_2U(SCH_1):PAGE615_I79@PURE_QUANTA.Q_CAP(CHIPS)':
 C_PATH='@s9s_mb_2u_lib.s9s_mb_2u(sch_1):page615_i79@pure_quanta.q_cap(chips)';

PART_NAME
 C442 'Q_CAP_C0402-22UF,4V,20%,X6S,CHA':;

SECTION_NUMBER 1
 '@S9S_MB_2U_LIB.S9S_MB_2U(SCH_1):PAGE615_I69@PURE_QUANTA.Q_CAP(CHIPS)':
 C_PATH='@s9s_mb_2u_lib.s9s_mb_2u(sch_1):page615_i69@pure_quanta.q_cap(chips)';

PART_NAME
 C441 'Q_CAP_C0402-22UF,4V,20%,X6S,CHA':;

SECTION_NUMBER 1
 '@S9S_MB_2U_LIB.S9S_MB_2U(SCH_1):PAGE615_I66@PURE_QUANTA.Q_CAP(CHIPS)':
 C_PATH='@s9s_mb_2u_lib.s9s_mb_2u(sch_1):page615_i66@pure_quanta.q_cap(chips)';

PART_NAME
 C440 'Q_CAP_C0402-22UF,4V,20%,X6S,CHA':;

SECTION_NUMBER 1
 '@S9S_MB_2U_LIB.S9S_MB_2U(SCH_1):PAGE615_I73@PURE_QUANTA.Q_CAP(CHIPS)':
 C_PATH='@s9s_mb_2u_lib.s9s_mb_2u(sch_1):page615_i73@pure_quanta.q_cap(chips)';

PART_NAME
 C439 'Q_CAP_C0402-22UF,4V,20%,X6S,CHA':;

SECTION_NUMBER 1
 '@S9S_MB_2U_LIB.S9S_MB_2U(SCH_1):PAGE615_I65@PURE_QUANTA.Q_CAP(CHIPS)':
 C_PATH='@s9s_mb_2u_lib.s9s_mb_2u(sch_1):page615_i65@pure_quanta.q_cap(chips)';

PART_NAME
 C438 'Q_CAP_C0402-22UF,4V,20%,X6S,CHA':;

SECTION_NUMBER 1
 '@S9S_MB_2U_LIB.S9S_MB_2U(SCH_1):PAGE615_I71@PURE_QUANTA.Q_CAP(CHIPS)':
 C_PATH='@s9s_mb_2u_lib.s9s_mb_2u(sch_1):page615_i71@pure_quanta.q_cap(chips)';

PART_NAME
 C437 'Q_CAP_C0402-22UF,4V,20%,X6S,CHA':;

SECTION_NUMBER 1
 '@S9S_MB_2U_LIB.S9S_MB_2U(SCH_1):PAGE615_I10@PURE_QUANTA.Q_CAP(CHIPS)':
 C_PATH='@s9s_mb_2u_lib.s9s_mb_2u(sch_1):page615_i10@pure_quanta.q_cap(chips)';

PART_NAME
 C436 'Q_CAP_C0402-22UF,4V,20%,X6S,CHA':;

SECTION_NUMBER 1
 '@S9S_MB_2U_LIB.S9S_MB_2U(SCH_1):PAGE615_I43@PURE_QUANTA.Q_CAP(CHIPS)':
 C_PATH='@s9s_mb_2u_lib.s9s_mb_2u(sch_1):page615_i43@pure_quanta.q_cap(chips)';

PART_NAME
 C435 'Q_CAP_C0402-22UF,4V,20%,X6S,CHA':;

SECTION_NUMBER 1
 '@S9S_MB_2U_LIB.S9S_MB_2U(SCH_1):PAGE615_I9@PURE_QUANTA.Q_CAP(CHIPS)':
 C_PATH='@s9s_mb_2u_lib.s9s_mb_2u(sch_1):page615_i9@pure_quanta.q_cap(chips)';

PART_NAME
 C434 'Q_CAP_C0402-22UF,4V,20%,X6S,CHA':;

SECTION_NUMBER 1
 '@S9S_MB_2U_LIB.S9S_MB_2U(SCH_1):PAGE615_I42@PURE_QUANTA.Q_CAP(CHIPS)':
 C_PATH='@s9s_mb_2u_lib.s9s_mb_2u(sch_1):page615_i42@pure_quanta.q_cap(chips)';

PART_NAME
 C433 'Q_CAP_C0402-22UF,4V,20%,X6S,CHA':;

SECTION_NUMBER 1
 '@S9S_MB_2U_LIB.S9S_MB_2U(SCH_1):PAGE615_I8@PURE_QUANTA.Q_CAP(CHIPS)':
 C_PATH='@s9s_mb_2u_lib.s9s_mb_2u(sch_1):page615_i8@pure_quanta.q_cap(chips)';

PART_NAME
 C432 'Q_CAP_C0402-22UF,4V,20%,X6S,CHA':;

SECTION_NUMBER 1
 '@S9S_MB_2U_LIB.S9S_MB_2U(SCH_1):PAGE615_I39@PURE_QUANTA.Q_CAP(CHIPS)':
 C_PATH='@s9s_mb_2u_lib.s9s_mb_2u(sch_1):page615_i39@pure_quanta.q_cap(chips)';

PART_NAME
 C431 'Q_CAP_C0402-22UF,4V,20%,X6S,CHA':;

SECTION_NUMBER 1
 '@S9S_MB_2U_LIB.S9S_MB_2U(SCH_1):PAGE615_I7@PURE_QUANTA.Q_CAP(CHIPS)':
 C_PATH='@s9s_mb_2u_lib.s9s_mb_2u(sch_1):page615_i7@pure_quanta.q_cap(chips)';

PART_NAME
 C430 'Q_CAP_C0402-22UF,4V,20%,X6S,CHA':;

SECTION_NUMBER 1
 '@S9S_MB_2U_LIB.S9S_MB_2U(SCH_1):PAGE615_I5@PURE_QUANTA.Q_CAP(CHIPS)':
 C_PATH='@s9s_mb_2u_lib.s9s_mb_2u(sch_1):page615_i5@pure_quanta.q_cap(chips)';

PART_NAME
 C429 'Q_CAP_C0402-22UF,4V,20%,X6S,CHA':;

SECTION_NUMBER 1
 '@S9S_MB_2U_LIB.S9S_MB_2U(SCH_1):PAGE615_I34@PURE_QUANTA.Q_CAP(CHIPS)':
 C_PATH='@s9s_mb_2u_lib.s9s_mb_2u(sch_1):page615_i34@pure_quanta.q_cap(chips)';

PART_NAME
 C428 'Q_CAP_C0402-22UF,4V,20%,X6S,CHA':;

SECTION_NUMBER 1
 '@S9S_MB_2U_LIB.S9S_MB_2U(SCH_1):PAGE615_I4@PURE_QUANTA.Q_CAP(CHIPS)':
 C_PATH='@s9s_mb_2u_lib.s9s_mb_2u(sch_1):page615_i4@pure_quanta.q_cap(chips)';

PART_NAME
 C427 'Q_CAP_C0402-22UF,4V,20%,X6S,CHA':;

SECTION_NUMBER 1
 '@S9S_MB_2U_LIB.S9S_MB_2U(SCH_1):PAGE615_I19@PURE_QUANTA.Q_CAP(CHIPS)':
 C_PATH='@s9s_mb_2u_lib.s9s_mb_2u(sch_1):page615_i19@pure_quanta.q_cap(chips)';

PART_NAME
 C426 'Q_CAP_C0402-22UF,4V,20%,X6S,CHA':;

SECTION_NUMBER 1
 '@S9S_MB_2U_LIB.S9S_MB_2U(SCH_1):PAGE615_I3@PURE_QUANTA.Q_CAP(CHIPS)':
 C_PATH='@s9s_mb_2u_lib.s9s_mb_2u(sch_1):page615_i3@pure_quanta.q_cap(chips)';

PART_NAME
 C425 'Q_CAP_C0402-22UF,4V,20%,X6S,CHA':;

SECTION_NUMBER 1
 '@S9S_MB_2U_LIB.S9S_MB_2U(SCH_1):PAGE615_I17@PURE_QUANTA.Q_CAP(CHIPS)':
 C_PATH='@s9s_mb_2u_lib.s9s_mb_2u(sch_1):page615_i17@pure_quanta.q_cap(chips)';

PART_NAME
 C424 'Q_CAP_C0402-22UF,4V,20%,X6S,CHA':;

SECTION_NUMBER 1
 '@S9S_MB_2U_LIB.S9S_MB_2U(SCH_1):PAGE615_I1@PURE_QUANTA.Q_CAP(CHIPS)':
 C_PATH='@s9s_mb_2u_lib.s9s_mb_2u(sch_1):page615_i1@pure_quanta.q_cap(chips)';

PART_NAME
 C423 'Q_CAP_C0402-22UF,4V,20%,X6S,CHA':;

SECTION_NUMBER 1
 '@S9S_MB_2U_LIB.S9S_MB_2U(SCH_1):PAGE615_I11@PURE_QUANTA.Q_CAP(CHIPS)':
 C_PATH='@s9s_mb_2u_lib.s9s_mb_2u(sch_1):page615_i11@pure_quanta.q_cap(chips)';

PART_NAME
 C310 'Q_CAP_C0402-22UF,4V,20%,X6S,CHA':;

SECTION_NUMBER 1
 '@S9S_MB_2U_LIB.S9S_MB_2U(SCH_1):PAGE615_I148@PURE_QUANTA.Q_CAP(CHIPS)':
 C_PATH='@s9s_mb_2u_lib.s9s_mb_2u(sch_1):page615_i148@pure_quanta.q_cap(chips)';

PART_NAME
 C309 'Q_CAP_C0402-22UF,4V,20%,X6S,CHA':;

SECTION_NUMBER 1
 '@S9S_MB_2U_LIB.S9S_MB_2U(SCH_1):PAGE615_I136@PURE_QUANTA.Q_CAP(CHIPS)':
 C_PATH='@s9s_mb_2u_lib.s9s_mb_2u(sch_1):page615_i136@pure_quanta.q_cap(chips)';

PART_NAME
 C308 'Q_CAP_C0402-22UF,4V,20%,X6S,CHA':;

SECTION_NUMBER 1
 '@S9S_MB_2U_LIB.S9S_MB_2U(SCH_1):PAGE615_I138@PURE_QUANTA.Q_CAP(CHIPS)':
 C_PATH='@s9s_mb_2u_lib.s9s_mb_2u(sch_1):page615_i138@pure_quanta.q_cap(chips)';

PART_NAME
 C307 'Q_CAP_C0402-22UF,4V,20%,X6S,CHA':;

SECTION_NUMBER 1
 '@S9S_MB_2U_LIB.S9S_MB_2U(SCH_1):PAGE615_I140@PURE_QUANTA.Q_CAP(CHIPS)':
 C_PATH='@s9s_mb_2u_lib.s9s_mb_2u(sch_1):page615_i140@pure_quanta.q_cap(chips)';

PART_NAME
 C306 'Q_CAP_C0402-22UF,4V,20%,X6S,CHA':;

SECTION_NUMBER 1
 '@S9S_MB_2U_LIB.S9S_MB_2U(SCH_1):PAGE615_I126@PURE_QUANTA.Q_CAP(CHIPS)':
 C_PATH='@s9s_mb_2u_lib.s9s_mb_2u(sch_1):page615_i126@pure_quanta.q_cap(chips)';

PART_NAME
 C305 'Q_CAP_C0402-22UF,4V,20%,X6S,CHA':;

SECTION_NUMBER 1
 '@S9S_MB_2U_LIB.S9S_MB_2U(SCH_1):PAGE615_I130@PURE_QUANTA.Q_CAP(CHIPS)':
 C_PATH='@s9s_mb_2u_lib.s9s_mb_2u(sch_1):page615_i130@pure_quanta.q_cap(chips)';

PART_NAME
 C304 'Q_CAP_C0402-22UF,4V,20%,X6S,CHA':;

SECTION_NUMBER 1
 '@S9S_MB_2U_LIB.S9S_MB_2U(SCH_1):PAGE615_I133@PURE_QUANTA.Q_CAP(CHIPS)':
 C_PATH='@s9s_mb_2u_lib.s9s_mb_2u(sch_1):page615_i133@pure_quanta.q_cap(chips)';

PART_NAME
 C303 'Q_CAP_C0402-22UF,4V,20%,X6S,CHA':;

SECTION_NUMBER 1
 '@S9S_MB_2U_LIB.S9S_MB_2U(SCH_1):PAGE615_I134@PURE_QUANTA.Q_CAP(CHIPS)':
 C_PATH='@s9s_mb_2u_lib.s9s_mb_2u(sch_1):page615_i134@pure_quanta.q_cap(chips)';

PART_NAME
 C302 'Q_CAP_C0402-22UF,4V,20%,X6S,CHA':;

SECTION_NUMBER 1
 '@S9S_MB_2U_LIB.S9S_MB_2U(SCH_1):PAGE615_I125@PURE_QUANTA.Q_CAP(CHIPS)':
 C_PATH='@s9s_mb_2u_lib.s9s_mb_2u(sch_1):page615_i125@pure_quanta.q_cap(chips)';

PART_NAME
 C301 'Q_CAP_C0402-22UF,4V,20%,X6S,CHA':;

SECTION_NUMBER 1
 '@S9S_MB_2U_LIB.S9S_MB_2U(SCH_1):PAGE615_I129@PURE_QUANTA.Q_CAP(CHIPS)':
 C_PATH='@s9s_mb_2u_lib.s9s_mb_2u(sch_1):page615_i129@pure_quanta.q_cap(chips)';

PART_NAME
 C300 'Q_CAP_C0402-22UF,4V,20%,X6S,CHA':;

SECTION_NUMBER 1
 '@S9S_MB_2U_LIB.S9S_MB_2U(SCH_1):PAGE615_I131@PURE_QUANTA.Q_CAP(CHIPS)':
 C_PATH='@s9s_mb_2u_lib.s9s_mb_2u(sch_1):page615_i131@pure_quanta.q_cap(chips)';

PART_NAME
 C299 'Q_CAP_C0402-22UF,4V,20%,X6S,CHA':;

SECTION_NUMBER 1
 '@S9S_MB_2U_LIB.S9S_MB_2U(SCH_1):PAGE615_I132@PURE_QUANTA.Q_CAP(CHIPS)':
 C_PATH='@s9s_mb_2u_lib.s9s_mb_2u(sch_1):page615_i132@pure_quanta.q_cap(chips)';

PART_NAME
 C298 'Q_CAP_C0402-22UF,4V,20%,X6S,CHA':;

SECTION_NUMBER 1
 '@S9S_MB_2U_LIB.S9S_MB_2U(SCH_1):PAGE615_I108@PURE_QUANTA.Q_CAP(CHIPS)':
 C_PATH='@s9s_mb_2u_lib.s9s_mb_2u(sch_1):page615_i108@pure_quanta.q_cap(chips)';

PART_NAME
 C297 'Q_CAP_C0402-22UF,4V,20%,X6S,CHA':;

SECTION_NUMBER 1
 '@S9S_MB_2U_LIB.S9S_MB_2U(SCH_1):PAGE615_I117@PURE_QUANTA.Q_CAP(CHIPS)':
 C_PATH='@s9s_mb_2u_lib.s9s_mb_2u(sch_1):page615_i117@pure_quanta.q_cap(chips)';

PART_NAME
 C296 'Q_CAP_C0402-22UF,4V,20%,X6S,CHA':;

SECTION_NUMBER 1
 '@S9S_MB_2U_LIB.S9S_MB_2U(SCH_1):PAGE615_I122@PURE_QUANTA.Q_CAP(CHIPS)':
 C_PATH='@s9s_mb_2u_lib.s9s_mb_2u(sch_1):page615_i122@pure_quanta.q_cap(chips)';

PART_NAME
 C295 'Q_CAP_C0402-22UF,4V,20%,X6S,CHA':;

SECTION_NUMBER 1
 '@S9S_MB_2U_LIB.S9S_MB_2U(SCH_1):PAGE615_I123@PURE_QUANTA.Q_CAP(CHIPS)':
 C_PATH='@s9s_mb_2u_lib.s9s_mb_2u(sch_1):page615_i123@pure_quanta.q_cap(chips)';

PART_NAME
 C294 'Q_CAP_C0402-22UF,4V,20%,X6S,CHA':;

SECTION_NUMBER 1
 '@S9S_MB_2U_LIB.S9S_MB_2U(SCH_1):PAGE615_I107@PURE_QUANTA.Q_CAP(CHIPS)':
 C_PATH='@s9s_mb_2u_lib.s9s_mb_2u(sch_1):page615_i107@pure_quanta.q_cap(chips)';

PART_NAME
 C293 'Q_CAP_C0402-22UF,4V,20%,X6S,CHA':;

SECTION_NUMBER 1
 '@S9S_MB_2U_LIB.S9S_MB_2U(SCH_1):PAGE615_I116@PURE_QUANTA.Q_CAP(CHIPS)':
 C_PATH='@s9s_mb_2u_lib.s9s_mb_2u(sch_1):page615_i116@pure_quanta.q_cap(chips)';

PART_NAME
 C292 'Q_CAP_C0402-22UF,4V,20%,X6S,CHA':;

SECTION_NUMBER 1
 '@S9S_MB_2U_LIB.S9S_MB_2U(SCH_1):PAGE615_I119@PURE_QUANTA.Q_CAP(CHIPS)':
 C_PATH='@s9s_mb_2u_lib.s9s_mb_2u(sch_1):page615_i119@pure_quanta.q_cap(chips)';

PART_NAME
 C291 'Q_CAP_C0402-22UF,4V,20%,X6S,CHA':;

SECTION_NUMBER 1
 '@S9S_MB_2U_LIB.S9S_MB_2U(SCH_1):PAGE615_I121@PURE_QUANTA.Q_CAP(CHIPS)':
 C_PATH='@s9s_mb_2u_lib.s9s_mb_2u(sch_1):page615_i121@pure_quanta.q_cap(chips)';

PART_NAME
 C290 'Q_CAP_C0402-22UF,4V,20%,X6S,CHA':;

SECTION_NUMBER 1
 '@S9S_MB_2U_LIB.S9S_MB_2U(SCH_1):PAGE615_I106@PURE_QUANTA.Q_CAP(CHIPS)':
 C_PATH='@s9s_mb_2u_lib.s9s_mb_2u(sch_1):page615_i106@pure_quanta.q_cap(chips)';

PART_NAME
 C289 'Q_CAP_C0402-22UF,4V,20%,X6S,CHA':;

SECTION_NUMBER 1
 '@S9S_MB_2U_LIB.S9S_MB_2U(SCH_1):PAGE615_I115@PURE_QUANTA.Q_CAP(CHIPS)':
 C_PATH='@s9s_mb_2u_lib.s9s_mb_2u(sch_1):page615_i115@pure_quanta.q_cap(chips)';

PART_NAME
 C288 'Q_CAP_C0402-22UF,4V,20%,X6S,CHA':;

SECTION_NUMBER 1
 '@S9S_MB_2U_LIB.S9S_MB_2U(SCH_1):PAGE615_I118@PURE_QUANTA.Q_CAP(CHIPS)':
 C_PATH='@s9s_mb_2u_lib.s9s_mb_2u(sch_1):page615_i118@pure_quanta.q_cap(chips)';

PART_NAME
 C287 'Q_CAP_C0402-22UF,4V,20%,X6S,CHA':;

SECTION_NUMBER 1
 '@S9S_MB_2U_LIB.S9S_MB_2U(SCH_1):PAGE615_I120@PURE_QUANTA.Q_CAP(CHIPS)':
 C_PATH='@s9s_mb_2u_lib.s9s_mb_2u(sch_1):page615_i120@pure_quanta.q_cap(chips)';

PART_NAME
 C286 'Q_CAP_C0402-22UF,4V,20%,X6S,CHA':;

SECTION_NUMBER 1
 '@S9S_MB_2U_LIB.S9S_MB_2U(SCH_1):PAGE615_I104@PURE_QUANTA.Q_CAP(CHIPS)':
 C_PATH='@s9s_mb_2u_lib.s9s_mb_2u(sch_1):page615_i104@pure_quanta.q_cap(chips)';

PART_NAME
 C285 'Q_CAP_C0402-22UF,4V,20%,X6S,CHA':;

SECTION_NUMBER 1
 '@S9S_MB_2U_LIB.S9S_MB_2U(SCH_1):PAGE615_I110@PURE_QUANTA.Q_CAP(CHIPS)':
 C_PATH='@s9s_mb_2u_lib.s9s_mb_2u(sch_1):page615_i110@pure_quanta.q_cap(chips)';

PART_NAME
 C284 'Q_CAP_C0402-22UF,4V,20%,X6S,CHA':;

SECTION_NUMBER 1
 '@S9S_MB_2U_LIB.S9S_MB_2U(SCH_1):PAGE615_I113@PURE_QUANTA.Q_CAP(CHIPS)':
 C_PATH='@s9s_mb_2u_lib.s9s_mb_2u(sch_1):page615_i113@pure_quanta.q_cap(chips)';

PART_NAME
 C283 'Q_CAP_C0402-22UF,4V,20%,X6S,CHA':;

SECTION_NUMBER 1
 '@S9S_MB_2U_LIB.S9S_MB_2U(SCH_1):PAGE615_I114@PURE_QUANTA.Q_CAP(CHIPS)':
 C_PATH='@s9s_mb_2u_lib.s9s_mb_2u(sch_1):page615_i114@pure_quanta.q_cap(chips)';

PART_NAME
 C282 'Q_CAP_C0402-22UF,4V,20%,X6S,CHA':;

SECTION_NUMBER 1
 '@S9S_MB_2U_LIB.S9S_MB_2U(SCH_1):PAGE615_I103@PURE_QUANTA.Q_CAP(CHIPS)':
 C_PATH='@s9s_mb_2u_lib.s9s_mb_2u(sch_1):page615_i103@pure_quanta.q_cap(chips)';

PART_NAME
 C281 'Q_CAP_C0402-22UF,4V,20%,X6S,CHA':;

SECTION_NUMBER 1
 '@S9S_MB_2U_LIB.S9S_MB_2U(SCH_1):PAGE615_I109@PURE_QUANTA.Q_CAP(CHIPS)':
 C_PATH='@s9s_mb_2u_lib.s9s_mb_2u(sch_1):page615_i109@pure_quanta.q_cap(chips)';

PART_NAME
 C280 'Q_CAP_C0402-22UF,4V,20%,X6S,CHA':;

SECTION_NUMBER 1
 '@S9S_MB_2U_LIB.S9S_MB_2U(SCH_1):PAGE615_I111@PURE_QUANTA.Q_CAP(CHIPS)':
 C_PATH='@s9s_mb_2u_lib.s9s_mb_2u(sch_1):page615_i111@pure_quanta.q_cap(chips)';

PART_NAME
 C279 'Q_CAP_C0402-22UF,4V,20%,X6S,CHA':;

SECTION_NUMBER 1
 '@S9S_MB_2U_LIB.S9S_MB_2U(SCH_1):PAGE615_I112@PURE_QUANTA.Q_CAP(CHIPS)':
 C_PATH='@s9s_mb_2u_lib.s9s_mb_2u(sch_1):page615_i112@pure_quanta.q_cap(chips)';

PART_NAME
 C278 'Q_CAP_C0402-22UF,4V,20%,X6S,CHA':;

SECTION_NUMBER 1
 '@S9S_MB_2U_LIB.S9S_MB_2U(SCH_1):PAGE615_I83@PURE_QUANTA.Q_CAP(CHIPS)':
 C_PATH='@s9s_mb_2u_lib.s9s_mb_2u(sch_1):page615_i83@pure_quanta.q_cap(chips)';

PART_NAME
 C277 'Q_CAP_C0402-22UF,4V,20%,X6S,CHA':;

SECTION_NUMBER 1
 '@S9S_MB_2U_LIB.S9S_MB_2U(SCH_1):PAGE615_I95@PURE_QUANTA.Q_CAP(CHIPS)':
 C_PATH='@s9s_mb_2u_lib.s9s_mb_2u(sch_1):page615_i95@pure_quanta.q_cap(chips)';

PART_NAME
 C276 'Q_CAP_C0402-22UF,4V,20%,X6S,CHA':;

SECTION_NUMBER 1
 '@S9S_MB_2U_LIB.S9S_MB_2U(SCH_1):PAGE615_I99@PURE_QUANTA.Q_CAP(CHIPS)':
 C_PATH='@s9s_mb_2u_lib.s9s_mb_2u(sch_1):page615_i99@pure_quanta.q_cap(chips)';

PART_NAME
 C275 'Q_CAP_C0402-22UF,4V,20%,X6S,CHA':;

SECTION_NUMBER 1
 '@S9S_MB_2U_LIB.S9S_MB_2U(SCH_1):PAGE615_I100@PURE_QUANTA.Q_CAP(CHIPS)':
 C_PATH='@s9s_mb_2u_lib.s9s_mb_2u(sch_1):page615_i100@pure_quanta.q_cap(chips)';

PART_NAME
 C274 'Q_CAP_C0402-22UF,4V,20%,X6S,CHA':;

SECTION_NUMBER 1
 '@S9S_MB_2U_LIB.S9S_MB_2U(SCH_1):PAGE615_I81@PURE_QUANTA.Q_CAP(CHIPS)':
 C_PATH='@s9s_mb_2u_lib.s9s_mb_2u(sch_1):page615_i81@pure_quanta.q_cap(chips)';

PART_NAME
 C273 'Q_CAP_C0402-22UF,4V,20%,X6S,CHA':;

SECTION_NUMBER 1
 '@S9S_MB_2U_LIB.S9S_MB_2U(SCH_1):PAGE615_I93@PURE_QUANTA.Q_CAP(CHIPS)':
 C_PATH='@s9s_mb_2u_lib.s9s_mb_2u(sch_1):page615_i93@pure_quanta.q_cap(chips)';

PART_NAME
 C272 'Q_CAP_C0402-22UF,4V,20%,X6S,CHA':;

SECTION_NUMBER 1
 '@S9S_MB_2U_LIB.S9S_MB_2U(SCH_1):PAGE615_I96@PURE_QUANTA.Q_CAP(CHIPS)':
 C_PATH='@s9s_mb_2u_lib.s9s_mb_2u(sch_1):page615_i96@pure_quanta.q_cap(chips)';

PART_NAME
 C271 'Q_CAP_C0402-22UF,4V,20%,X6S,CHA':;

SECTION_NUMBER 1
 '@S9S_MB_2U_LIB.S9S_MB_2U(SCH_1):PAGE615_I98@PURE_QUANTA.Q_CAP(CHIPS)':
 C_PATH='@s9s_mb_2u_lib.s9s_mb_2u(sch_1):page615_i98@pure_quanta.q_cap(chips)';

PART_NAME
 C270 'Q_CAP_0805-47UF,4V,20%,X6S,CH6A':;

SECTION_NUMBER 1
 '@S9S_MB_2U_LIB.S9S_MB_2U(SCH_1):PAGE615_I75@PURE_QUANTA.Q_CAP(CHIPS)':
 C_PATH='@s9s_mb_2u_lib.s9s_mb_2u(sch_1):page615_i75@pure_quanta.q_cap(chips)';

PART_NAME
 C269 'Q_CAP_C0402-22UF,4V,20%,X6S,CHA':;

SECTION_NUMBER 1
 '@S9S_MB_2U_LIB.S9S_MB_2U(SCH_1):PAGE615_I78@PURE_QUANTA.Q_CAP(CHIPS)':
 C_PATH='@s9s_mb_2u_lib.s9s_mb_2u(sch_1):page615_i78@pure_quanta.q_cap(chips)';

PART_NAME
 C268 'Q_CAP_C0402-22UF,4V,20%,X6S,CHA':;

SECTION_NUMBER 1
 '@S9S_MB_2U_LIB.S9S_MB_2U(SCH_1):PAGE615_I86@PURE_QUANTA.Q_CAP(CHIPS)':
 C_PATH='@s9s_mb_2u_lib.s9s_mb_2u(sch_1):page615_i86@pure_quanta.q_cap(chips)';

PART_NAME
 C267 'Q_CAP_C0402-22UF,4V,20%,X6S,CHA':;

SECTION_NUMBER 1
 '@S9S_MB_2U_LIB.S9S_MB_2U(SCH_1):PAGE615_I90@PURE_QUANTA.Q_CAP(CHIPS)':
 C_PATH='@s9s_mb_2u_lib.s9s_mb_2u(sch_1):page615_i90@pure_quanta.q_cap(chips)';

PART_NAME
 C266 'Q_CAP_C0402-22UF,4V,20%,X6S,CHA':;

SECTION_NUMBER 1
 '@S9S_MB_2U_LIB.S9S_MB_2U(SCH_1):PAGE615_I92@PURE_QUANTA.Q_CAP(CHIPS)':
 C_PATH='@s9s_mb_2u_lib.s9s_mb_2u(sch_1):page615_i92@pure_quanta.q_cap(chips)';

PART_NAME
 C265 'Q_CAP_0805-47UF,4V,20%,X6S,CH6A':;

SECTION_NUMBER 1
 '@S9S_MB_2U_LIB.S9S_MB_2U(SCH_1):PAGE615_I72@PURE_QUANTA.Q_CAP(CHIPS)':
 C_PATH='@s9s_mb_2u_lib.s9s_mb_2u(sch_1):page615_i72@pure_quanta.q_cap(chips)';

PART_NAME
 C264 'Q_CAP_C0402-22UF,4V,20%,X6S,CHA':;

SECTION_NUMBER 1
 '@S9S_MB_2U_LIB.S9S_MB_2U(SCH_1):PAGE615_I76@PURE_QUANTA.Q_CAP(CHIPS)':
 C_PATH='@s9s_mb_2u_lib.s9s_mb_2u(sch_1):page615_i76@pure_quanta.q_cap(chips)';

PART_NAME
 C263 'Q_CAP_C0402-22UF,4V,20%,X6S,CHA':;

SECTION_NUMBER 1
 '@S9S_MB_2U_LIB.S9S_MB_2U(SCH_1):PAGE615_I84@PURE_QUANTA.Q_CAP(CHIPS)':
 C_PATH='@s9s_mb_2u_lib.s9s_mb_2u(sch_1):page615_i84@pure_quanta.q_cap(chips)';

PART_NAME
 C262 'Q_CAP_C0402-22UF,4V,20%,X6S,CHA':;

SECTION_NUMBER 1
 '@S9S_MB_2U_LIB.S9S_MB_2U(SCH_1):PAGE615_I88@PURE_QUANTA.Q_CAP(CHIPS)':
 C_PATH='@s9s_mb_2u_lib.s9s_mb_2u(sch_1):page615_i88@pure_quanta.q_cap(chips)';

PART_NAME
 C261 'Q_CAP_C0402-22UF,4V,20%,X6S,CHA':;

SECTION_NUMBER 1
 '@S9S_MB_2U_LIB.S9S_MB_2U(SCH_1):PAGE615_I89@PURE_QUANTA.Q_CAP(CHIPS)':
 C_PATH='@s9s_mb_2u_lib.s9s_mb_2u(sch_1):page615_i89@pure_quanta.q_cap(chips)';

PART_NAME
 C260 'Q_CAP_0805-47UF,4V,20%,X6S,CH6A':;

SECTION_NUMBER 1
 '@S9S_MB_2U_LIB.S9S_MB_2U(SCH_1):PAGE615_I45@PURE_QUANTA.Q_CAP(CHIPS)':
 C_PATH='@s9s_mb_2u_lib.s9s_mb_2u(sch_1):page615_i45@pure_quanta.q_cap(chips)';

PART_NAME
 C259 'Q_CAP_C0402-22UF,4V,20%,X6S,CHA':;

SECTION_NUMBER 1
 '@S9S_MB_2U_LIB.S9S_MB_2U(SCH_1):PAGE615_I48@PURE_QUANTA.Q_CAP(CHIPS)':
 C_PATH='@s9s_mb_2u_lib.s9s_mb_2u(sch_1):page615_i48@pure_quanta.q_cap(chips)';

PART_NAME
 C258 'Q_CAP_C0402-22UF,4V,20%,X6S,CHA':;

SECTION_NUMBER 1
 '@S9S_MB_2U_LIB.S9S_MB_2U(SCH_1):PAGE615_I57@PURE_QUANTA.Q_CAP(CHIPS)':
 C_PATH='@s9s_mb_2u_lib.s9s_mb_2u(sch_1):page615_i57@pure_quanta.q_cap(chips)';

PART_NAME
 C257 'Q_CAP_C0402-22UF,4V,20%,X6S,CHA':;

SECTION_NUMBER 1
 '@S9S_MB_2U_LIB.S9S_MB_2U(SCH_1):PAGE615_I62@PURE_QUANTA.Q_CAP(CHIPS)':
 C_PATH='@s9s_mb_2u_lib.s9s_mb_2u(sch_1):page615_i62@pure_quanta.q_cap(chips)';

PART_NAME
 C256 'Q_CAP_C0402-22UF,4V,20%,X6S,CHA':;

SECTION_NUMBER 1
 '@S9S_MB_2U_LIB.S9S_MB_2U(SCH_1):PAGE615_I63@PURE_QUANTA.Q_CAP(CHIPS)':
 C_PATH='@s9s_mb_2u_lib.s9s_mb_2u(sch_1):page615_i63@pure_quanta.q_cap(chips)';

PART_NAME
 C255 'Q_CAP_0805-47UF,4V,20%,X6S,CH6A':;

SECTION_NUMBER 1
 '@S9S_MB_2U_LIB.S9S_MB_2U(SCH_1):PAGE615_I44@PURE_QUANTA.Q_CAP(CHIPS)':
 C_PATH='@s9s_mb_2u_lib.s9s_mb_2u(sch_1):page615_i44@pure_quanta.q_cap(chips)';

PART_NAME
 C254 'Q_CAP_C0402-22UF,4V,20%,X6S,CHA':;

SECTION_NUMBER 1
 '@S9S_MB_2U_LIB.S9S_MB_2U(SCH_1):PAGE615_I47@PURE_QUANTA.Q_CAP(CHIPS)':
 C_PATH='@s9s_mb_2u_lib.s9s_mb_2u(sch_1):page615_i47@pure_quanta.q_cap(chips)';

PART_NAME
 C253 'Q_CAP_C0402-22UF,4V,20%,X6S,CHA':;

SECTION_NUMBER 1
 '@S9S_MB_2U_LIB.S9S_MB_2U(SCH_1):PAGE615_I56@PURE_QUANTA.Q_CAP(CHIPS)':
 C_PATH='@s9s_mb_2u_lib.s9s_mb_2u(sch_1):page615_i56@pure_quanta.q_cap(chips)';

PART_NAME
 C252 'Q_CAP_C0402-22UF,4V,20%,X6S,CHA':;

SECTION_NUMBER 1
 '@S9S_MB_2U_LIB.S9S_MB_2U(SCH_1):PAGE615_I60@PURE_QUANTA.Q_CAP(CHIPS)':
 C_PATH='@s9s_mb_2u_lib.s9s_mb_2u(sch_1):page615_i60@pure_quanta.q_cap(chips)';

PART_NAME
 C251 'Q_CAP_C0402-22UF,4V,20%,X6S,CHA':;

SECTION_NUMBER 1
 '@S9S_MB_2U_LIB.S9S_MB_2U(SCH_1):PAGE615_I61@PURE_QUANTA.Q_CAP(CHIPS)':
 C_PATH='@s9s_mb_2u_lib.s9s_mb_2u(sch_1):page615_i61@pure_quanta.q_cap(chips)';

PART_NAME
 C250 'Q_CAP_0805-47UF,4V,20%,X6S,CH6A':;

SECTION_NUMBER 1
 '@S9S_MB_2U_LIB.S9S_MB_2U(SCH_1):PAGE615_I41@PURE_QUANTA.Q_CAP(CHIPS)':
 C_PATH='@s9s_mb_2u_lib.s9s_mb_2u(sch_1):page615_i41@pure_quanta.q_cap(chips)';

PART_NAME
 C249 'Q_CAP_C0402-22UF,4V,20%,X6S,CHA':;

SECTION_NUMBER 1
 '@S9S_MB_2U_LIB.S9S_MB_2U(SCH_1):PAGE615_I46@PURE_QUANTA.Q_CAP(CHIPS)':
 C_PATH='@s9s_mb_2u_lib.s9s_mb_2u(sch_1):page615_i46@pure_quanta.q_cap(chips)';

PART_NAME
 C248 'Q_CAP_C0402-22UF,4V,20%,X6S,CHA':;

SECTION_NUMBER 1
 '@S9S_MB_2U_LIB.S9S_MB_2U(SCH_1):PAGE615_I55@PURE_QUANTA.Q_CAP(CHIPS)':
 C_PATH='@s9s_mb_2u_lib.s9s_mb_2u(sch_1):page615_i55@pure_quanta.q_cap(chips)';

PART_NAME
 C247 'Q_CAP_C0402-22UF,4V,20%,X6S,CHA':;

SECTION_NUMBER 1
 '@S9S_MB_2U_LIB.S9S_MB_2U(SCH_1):PAGE615_I58@PURE_QUANTA.Q_CAP(CHIPS)':
 C_PATH='@s9s_mb_2u_lib.s9s_mb_2u(sch_1):page615_i58@pure_quanta.q_cap(chips)';

PART_NAME
 C246 'Q_CAP_C0402-22UF,4V,20%,X6S,CHA':;

SECTION_NUMBER 1
 '@S9S_MB_2U_LIB.S9S_MB_2U(SCH_1):PAGE615_I59@PURE_QUANTA.Q_CAP(CHIPS)':
 C_PATH='@s9s_mb_2u_lib.s9s_mb_2u(sch_1):page615_i59@pure_quanta.q_cap(chips)';

PART_NAME
 C245 'Q_CAP_0805-47UF,4V,20%,X6S,CH6A':;

SECTION_NUMBER 1
 '@S9S_MB_2U_LIB.S9S_MB_2U(SCH_1):PAGE615_I36@PURE_QUANTA.Q_CAP(CHIPS)':
 C_PATH='@s9s_mb_2u_lib.s9s_mb_2u(sch_1):page615_i36@pure_quanta.q_cap(chips)';

PART_NAME
 C244 'Q_CAP_C0402-22UF,4V,20%,X6S,CHA':;

SECTION_NUMBER 1
 '@S9S_MB_2U_LIB.S9S_MB_2U(SCH_1):PAGE615_I38@PURE_QUANTA.Q_CAP(CHIPS)':
 C_PATH='@s9s_mb_2u_lib.s9s_mb_2u(sch_1):page615_i38@pure_quanta.q_cap(chips)';

PART_NAME
 C243 'Q_CAP_C0402-22UF,4V,20%,X6S,CHA':;

SECTION_NUMBER 1
 '@S9S_MB_2U_LIB.S9S_MB_2U(SCH_1):PAGE615_I50@PURE_QUANTA.Q_CAP(CHIPS)':
 C_PATH='@s9s_mb_2u_lib.s9s_mb_2u(sch_1):page615_i50@pure_quanta.q_cap(chips)';

PART_NAME
 C242 'Q_CAP_C0402-22UF,4V,20%,X6S,CHA':;

SECTION_NUMBER 1
 '@S9S_MB_2U_LIB.S9S_MB_2U(SCH_1):PAGE615_I53@PURE_QUANTA.Q_CAP(CHIPS)':
 C_PATH='@s9s_mb_2u_lib.s9s_mb_2u(sch_1):page615_i53@pure_quanta.q_cap(chips)';

PART_NAME
 C241 'Q_CAP_C0402-22UF,4V,20%,X6S,CHA':;

SECTION_NUMBER 1
 '@S9S_MB_2U_LIB.S9S_MB_2U(SCH_1):PAGE615_I54@PURE_QUANTA.Q_CAP(CHIPS)':
 C_PATH='@s9s_mb_2u_lib.s9s_mb_2u(sch_1):page615_i54@pure_quanta.q_cap(chips)';

PART_NAME
 C240 'Q_CAP_0805-47UF,4V,20%,X6S,CH6A':;

SECTION_NUMBER 1
 '@S9S_MB_2U_LIB.S9S_MB_2U(SCH_1):PAGE615_I35@PURE_QUANTA.Q_CAP(CHIPS)':
 C_PATH='@s9s_mb_2u_lib.s9s_mb_2u(sch_1):page615_i35@pure_quanta.q_cap(chips)';

PART_NAME
 C239 'Q_CAP_C0402-22UF,4V,20%,X6S,CHA':;

SECTION_NUMBER 1
 '@S9S_MB_2U_LIB.S9S_MB_2U(SCH_1):PAGE615_I37@PURE_QUANTA.Q_CAP(CHIPS)':
 C_PATH='@s9s_mb_2u_lib.s9s_mb_2u(sch_1):page615_i37@pure_quanta.q_cap(chips)';

PART_NAME
 C238 'Q_CAP_C0402-22UF,4V,20%,X6S,CHA':;

SECTION_NUMBER 1
 '@S9S_MB_2U_LIB.S9S_MB_2U(SCH_1):PAGE615_I49@PURE_QUANTA.Q_CAP(CHIPS)':
 C_PATH='@s9s_mb_2u_lib.s9s_mb_2u(sch_1):page615_i49@pure_quanta.q_cap(chips)';

PART_NAME
 C237 'Q_CAP_C0402-22UF,4V,20%,X6S,CHA':;

SECTION_NUMBER 1
 '@S9S_MB_2U_LIB.S9S_MB_2U(SCH_1):PAGE615_I51@PURE_QUANTA.Q_CAP(CHIPS)':
 C_PATH='@s9s_mb_2u_lib.s9s_mb_2u(sch_1):page615_i51@pure_quanta.q_cap(chips)';

PART_NAME
 C236 'Q_CAP_C0402-22UF,4V,20%,X6S,CHA':;

SECTION_NUMBER 1
 '@S9S_MB_2U_LIB.S9S_MB_2U(SCH_1):PAGE615_I52@PURE_QUANTA.Q_CAP(CHIPS)':
 C_PATH='@s9s_mb_2u_lib.s9s_mb_2u(sch_1):page615_i52@pure_quanta.q_cap(chips)';

PART_NAME
 C235 'Q_CAP_0805-47UF,4V,20%,X6S,CH6A':;

SECTION_NUMBER 1
 '@S9S_MB_2U_LIB.S9S_MB_2U(SCH_1):PAGE615_I20@PURE_QUANTA.Q_CAP(CHIPS)':
 C_PATH='@s9s_mb_2u_lib.s9s_mb_2u(sch_1):page615_i20@pure_quanta.q_cap(chips)';

PART_NAME
 C234 'Q_CAP_C0402-22UF,4V,20%,X6S,CHA':;

SECTION_NUMBER 1
 '@S9S_MB_2U_LIB.S9S_MB_2U(SCH_1):PAGE615_I22@PURE_QUANTA.Q_CAP(CHIPS)':
 C_PATH='@s9s_mb_2u_lib.s9s_mb_2u(sch_1):page615_i22@pure_quanta.q_cap(chips)';

PART_NAME
 C233 'Q_CAP_C0402-22UF,4V,20%,X6S,CHA':;

SECTION_NUMBER 1
 '@S9S_MB_2U_LIB.S9S_MB_2U(SCH_1):PAGE615_I29@PURE_QUANTA.Q_CAP(CHIPS)':
 C_PATH='@s9s_mb_2u_lib.s9s_mb_2u(sch_1):page615_i29@pure_quanta.q_cap(chips)';

PART_NAME
 C232 'Q_CAP_C0402-22UF,4V,20%,X6S,CHA':;

SECTION_NUMBER 1
 '@S9S_MB_2U_LIB.S9S_MB_2U(SCH_1):PAGE615_I32@PURE_QUANTA.Q_CAP(CHIPS)':
 C_PATH='@s9s_mb_2u_lib.s9s_mb_2u(sch_1):page615_i32@pure_quanta.q_cap(chips)';

PART_NAME
 C231 'Q_CAP_C0402-22UF,4V,20%,X6S,CHA':;

SECTION_NUMBER 1
 '@S9S_MB_2U_LIB.S9S_MB_2U(SCH_1):PAGE615_I33@PURE_QUANTA.Q_CAP(CHIPS)':
 C_PATH='@s9s_mb_2u_lib.s9s_mb_2u(sch_1):page615_i33@pure_quanta.q_cap(chips)';

PART_NAME
 C230 'Q_CAP_0805-47UF,4V,20%,X6S,CH6A':;

SECTION_NUMBER 1
 '@S9S_MB_2U_LIB.S9S_MB_2U(SCH_1):PAGE615_I18@PURE_QUANTA.Q_CAP(CHIPS)':
 C_PATH='@s9s_mb_2u_lib.s9s_mb_2u(sch_1):page615_i18@pure_quanta.q_cap(chips)';

PART_NAME
 C229 'Q_CAP_C0402-22UF,4V,20%,X6S,CHA':;

SECTION_NUMBER 1
 '@S9S_MB_2U_LIB.S9S_MB_2U(SCH_1):PAGE615_I21@PURE_QUANTA.Q_CAP(CHIPS)':
 C_PATH='@s9s_mb_2u_lib.s9s_mb_2u(sch_1):page615_i21@pure_quanta.q_cap(chips)';

PART_NAME
 C228 'Q_CAP_C0402-22UF,4V,20%,X6S,CHA':;

SECTION_NUMBER 1
 '@S9S_MB_2U_LIB.S9S_MB_2U(SCH_1):PAGE615_I28@PURE_QUANTA.Q_CAP(CHIPS)':
 C_PATH='@s9s_mb_2u_lib.s9s_mb_2u(sch_1):page615_i28@pure_quanta.q_cap(chips)';

PART_NAME
 C227 'Q_CAP_C0402-22UF,4V,20%,X6S,CHA':;

SECTION_NUMBER 1
 '@S9S_MB_2U_LIB.S9S_MB_2U(SCH_1):PAGE615_I30@PURE_QUANTA.Q_CAP(CHIPS)':
 C_PATH='@s9s_mb_2u_lib.s9s_mb_2u(sch_1):page615_i30@pure_quanta.q_cap(chips)';

PART_NAME
 C226 'Q_CAP_C0402-22UF,4V,20%,X6S,CHA':;

SECTION_NUMBER 1
 '@S9S_MB_2U_LIB.S9S_MB_2U(SCH_1):PAGE615_I31@PURE_QUANTA.Q_CAP(CHIPS)':
 C_PATH='@s9s_mb_2u_lib.s9s_mb_2u(sch_1):page615_i31@pure_quanta.q_cap(chips)';

PART_NAME
 C225 'Q_CAP_0805-47UF,4V,20%,X6S,CH6A':;

SECTION_NUMBER 1
 '@S9S_MB_2U_LIB.S9S_MB_2U(SCH_1):PAGE615_I13@PURE_QUANTA.Q_CAP(CHIPS)':
 C_PATH='@s9s_mb_2u_lib.s9s_mb_2u(sch_1):page615_i13@pure_quanta.q_cap(chips)';

PART_NAME
 C224 'Q_CAP_C0402-22UF,4V,20%,X6S,CHA':;

SECTION_NUMBER 1
 '@S9S_MB_2U_LIB.S9S_MB_2U(SCH_1):PAGE615_I15@PURE_QUANTA.Q_CAP(CHIPS)':
 C_PATH='@s9s_mb_2u_lib.s9s_mb_2u(sch_1):page615_i15@pure_quanta.q_cap(chips)';

PART_NAME
 C223 'Q_CAP_C0402-22UF,4V,20%,X6S,CHA':;

SECTION_NUMBER 1
 '@S9S_MB_2U_LIB.S9S_MB_2U(SCH_1):PAGE615_I23@PURE_QUANTA.Q_CAP(CHIPS)':
 C_PATH='@s9s_mb_2u_lib.s9s_mb_2u(sch_1):page615_i23@pure_quanta.q_cap(chips)';

PART_NAME
 C222 'Q_CAP_C0402-22UF,4V,20%,X6S,CHA':;

SECTION_NUMBER 1
 '@S9S_MB_2U_LIB.S9S_MB_2U(SCH_1):PAGE615_I25@PURE_QUANTA.Q_CAP(CHIPS)':
 C_PATH='@s9s_mb_2u_lib.s9s_mb_2u(sch_1):page615_i25@pure_quanta.q_cap(chips)';

PART_NAME
 C221 'Q_CAP_C0402-22UF,4V,20%,X6S,CHA':;

SECTION_NUMBER 1
 '@S9S_MB_2U_LIB.S9S_MB_2U(SCH_1):PAGE615_I27@PURE_QUANTA.Q_CAP(CHIPS)':
 C_PATH='@s9s_mb_2u_lib.s9s_mb_2u(sch_1):page615_i27@pure_quanta.q_cap(chips)';

PART_NAME
 U38 '9QXL2001BNHGI8-9QXL2001BNHGI8,A':;

SECTION_NUMBER 1
 '@S9S_MB_2U_LIB.S9S_MB_2U(SCH_1):PAGE532_I119@PURE_QUANTA.9QXL2001BNHGI8(CHIPS)':
 C_PATH='@s9s_mb_2u_lib.s9s_mb_2u(sch_1):page532_i119@pure_quanta.\9qxl2001bnhgi8\~
(chips)';

PART_NAME
 R1544 'Q_RES_0402LF-0,5%,1/16W,CHIP,CA':;

SECTION_NUMBER 1
 '@S9S_MB_2U_LIB.S9S_MB_2U(SCH_1):PAGE532_I416@PURE_QUANTA.Q_RES(CHIPS)':
 C_PATH='@s9s_mb_2u_lib.s9s_mb_2u(sch_1):page532_i416@pure_quanta.q_res(chips)';

PART_NAME
 R1543 'Q_RES_0402LF-0,5%,1/16W,CHIP,CA':;

SECTION_NUMBER 1
 '@S9S_MB_2U_LIB.S9S_MB_2U(SCH_1):PAGE532_I411@PURE_QUANTA.Q_RES(CHIPS)':
 C_PATH='@s9s_mb_2u_lib.s9s_mb_2u(sch_1):page532_i411@pure_quanta.q_res(chips)';

PART_NAME
 R1542 'Q_RES_0402LF-10K,1%,1/16W,CHIPA':;

SECTION_NUMBER 1
 '@S9S_MB_2U_LIB.S9S_MB_2U(SCH_1):PAGE532_I418@PURE_QUANTA.Q_RES(CHIPS)':
 C_PATH='@s9s_mb_2u_lib.s9s_mb_2u(sch_1):page532_i418@pure_quanta.q_res(chips)';

PART_NAME
 R576 'Q_RES_0402LF-49.9     ,1%  ,1/A':;

SECTION_NUMBER 1
 '@S9S_MB_2U_LIB.S9S_MB_2U(SCH_1):PAGE532_I156@PURE_QUANTA.Q_RES(CHIPS)':
 C_PATH='@s9s_mb_2u_lib.s9s_mb_2u(sch_1):page532_i156@pure_quanta.q_res(chips)';

PART_NAME
 R575 'Q_RES_0402LF-49.9     ,1%  ,1/A':;

SECTION_NUMBER 1
 '@S9S_MB_2U_LIB.S9S_MB_2U(SCH_1):PAGE532_I199@PURE_QUANTA.Q_RES(CHIPS)':
 C_PATH='@s9s_mb_2u_lib.s9s_mb_2u(sch_1):page532_i199@pure_quanta.q_res(chips)';

PART_NAME
 R574 'Q_RES_0402LF-4.7K,1%,1/16W,CHIA':;

SECTION_NUMBER 1
 '@S9S_MB_2U_LIB.S9S_MB_2U(SCH_1):PAGE532_I197@PURE_QUANTA.Q_RES(CHIPS)':
 C_PATH='@s9s_mb_2u_lib.s9s_mb_2u(sch_1):page532_i197@pure_quanta.q_res(chips)';

PART_NAME
 R573 'Q_RES_0402LF-4.7K,1%,1/16W,EMPA':;

SECTION_NUMBER 1
 '@S9S_MB_2U_LIB.S9S_MB_2U(SCH_1):PAGE532_I194@PURE_QUANTA.Q_RES(CHIPS)':
 C_PATH='@s9s_mb_2u_lib.s9s_mb_2u(sch_1):page532_i194@pure_quanta.q_res(chips)';

PART_NAME
 R572 'Q_RES_0603LF-2.2,1%,1/10W,CHIPA':;

SECTION_NUMBER 1
 '@S9S_MB_2U_LIB.S9S_MB_2U(SCH_1):PAGE532_I162@PURE_QUANTA.Q_RES(CHIPS)':
 C_PATH='@s9s_mb_2u_lib.s9s_mb_2u(sch_1):page532_i162@pure_quanta.q_res(chips)';

PART_NAME
 R571 'Q_RES_0603LF-2.2,1%,1/10W,CHIPA':;

SECTION_NUMBER 1
 '@S9S_MB_2U_LIB.S9S_MB_2U(SCH_1):PAGE532_I163@PURE_QUANTA.Q_RES(CHIPS)':
 C_PATH='@s9s_mb_2u_lib.s9s_mb_2u(sch_1):page532_i163@pure_quanta.q_res(chips)';

PART_NAME
 R570 'Q_RES_0402LF-4.7K,1%,1/16W,CHIA':;

SECTION_NUMBER 1
 '@S9S_MB_2U_LIB.S9S_MB_2U(SCH_1):PAGE532_I187@PURE_QUANTA.Q_RES(CHIPS)':
 C_PATH='@s9s_mb_2u_lib.s9s_mb_2u(sch_1):page532_i187@pure_quanta.q_res(chips)';

PART_NAME
 R569 'Q_RES_0402LF-4.7K,1%,1/16W,EMPA':;

SECTION_NUMBER 1
 '@S9S_MB_2U_LIB.S9S_MB_2U(SCH_1):PAGE532_I185@PURE_QUANTA.Q_RES(CHIPS)':
 C_PATH='@s9s_mb_2u_lib.s9s_mb_2u(sch_1):page532_i185@pure_quanta.q_res(chips)';

PART_NAME
 R568 'Q_RES_0402LF-4.7K,1%,1/16W,CHIA':;

SECTION_NUMBER 1
 '@S9S_MB_2U_LIB.S9S_MB_2U(SCH_1):PAGE532_I178@PURE_QUANTA.Q_RES(CHIPS)':
 C_PATH='@s9s_mb_2u_lib.s9s_mb_2u(sch_1):page532_i178@pure_quanta.q_res(chips)';

PART_NAME
 R567 'Q_RES_0402LF-4.7K,1%,1/16W,EMPA':;

SECTION_NUMBER 1
 '@S9S_MB_2U_LIB.S9S_MB_2U(SCH_1):PAGE532_I179@PURE_QUANTA.Q_RES(CHIPS)':
 C_PATH='@s9s_mb_2u_lib.s9s_mb_2u(sch_1):page532_i179@pure_quanta.q_res(chips)';

PART_NAME
 R112 'Q_RES_0402LF-10K,1%,1/16W,CHIPA':;

SECTION_NUMBER 1
 '@S9S_MB_2U_LIB.S9S_MB_2U(SCH_1):PAGE532_I413@PURE_QUANTA.Q_RES(CHIPS)':
 C_PATH='@s9s_mb_2u_lib.s9s_mb_2u(sch_1):page532_i413@pure_quanta.q_res(chips)';

PART_NAME
 R106 'Q_RES_0402LF-2K,1%,1/16W,CHIP,A':;

SECTION_NUMBER 1
 '@S9S_MB_2U_LIB.S9S_MB_2U(SCH_1):PAGE532_I304@PURE_QUANTA.Q_RES(CHIPS)':
 C_PATH='@s9s_mb_2u_lib.s9s_mb_2u(sch_1):page532_i304@pure_quanta.q_res(chips)';

PART_NAME
 L4 'Q_INDUCTOR_SMLF-BLM18SG331TN1DA':;

SECTION_NUMBER 1
 '@S9S_MB_2U_LIB.S9S_MB_2U(SCH_1):PAGE532_I177@PURE_QUANTA.Q_INDUCTOR(CHIPS)':
 C_PATH='@s9s_mb_2u_lib.s9s_mb_2u(sch_1):page532_i177@pure_quanta.q_inductor(chips~
)';

PART_NAME
 L3 'Q_INDUCTOR_SMLF-BLM18SG331TN1DA':;

SECTION_NUMBER 1
 '@S9S_MB_2U_LIB.S9S_MB_2U(SCH_1):PAGE532_I170@PURE_QUANTA.Q_INDUCTOR(CHIPS)':
 C_PATH='@s9s_mb_2u_lib.s9s_mb_2u(sch_1):page532_i170@pure_quanta.q_inductor(chips~
)';

PART_NAME
 C1409 'Q_CAP_C0603-10UF,6.3V,20%,X6S,A':;

SECTION_NUMBER 1
 '@S9S_MB_2U_LIB.S9S_MB_2U(SCH_1):PAGE532_I419@PURE_QUANTA.Q_CAP(CHIPS)':
 C_PATH='@s9s_mb_2u_lib.s9s_mb_2u(sch_1):page532_i419@pure_quanta.q_cap(chips)';

PART_NAME
 C211 'Q_CAP_0402-0.1UF,25V,10%,X7R,CA':;

SECTION_NUMBER 1
 '@S9S_MB_2U_LIB.S9S_MB_2U(SCH_1):PAGE532_I165@PURE_QUANTA.Q_CAP(CHIPS)':
 C_PATH='@s9s_mb_2u_lib.s9s_mb_2u(sch_1):page532_i165@pure_quanta.q_cap(chips)';

PART_NAME
 C210 'Q_CAP_0402-0.1UF,25V,10%,X7R,CA':;

SECTION_NUMBER 1
 '@S9S_MB_2U_LIB.S9S_MB_2U(SCH_1):PAGE532_I168@PURE_QUANTA.Q_CAP(CHIPS)':
 C_PATH='@s9s_mb_2u_lib.s9s_mb_2u(sch_1):page532_i168@pure_quanta.q_cap(chips)';

PART_NAME
 C209 'Q_CAP_C0603-10UF,6.3V,20%,X6S,A':;

SECTION_NUMBER 1
 '@S9S_MB_2U_LIB.S9S_MB_2U(SCH_1):PAGE532_I164@PURE_QUANTA.Q_CAP(CHIPS)':
 C_PATH='@s9s_mb_2u_lib.s9s_mb_2u(sch_1):page532_i164@pure_quanta.q_cap(chips)';

PART_NAME
 C208 'Q_CAP_C0603-10UF,6.3V,20%,X6S,A':;

SECTION_NUMBER 1
 '@S9S_MB_2U_LIB.S9S_MB_2U(SCH_1):PAGE532_I167@PURE_QUANTA.Q_CAP(CHIPS)':
 C_PATH='@s9s_mb_2u_lib.s9s_mb_2u(sch_1):page532_i167@pure_quanta.q_cap(chips)';

PART_NAME
 C207 'Q_CAP_0402-0.1UF,25V,10%,X7R,CA':;

SECTION_NUMBER 1
 '@S9S_MB_2U_LIB.S9S_MB_2U(SCH_1):PAGE532_I174@PURE_QUANTA.Q_CAP(CHIPS)':
 C_PATH='@s9s_mb_2u_lib.s9s_mb_2u(sch_1):page532_i174@pure_quanta.q_cap(chips)';

PART_NAME
 C206 'Q_CAP_0402-0.1UF,25V,10%,X7R,CA':;

SECTION_NUMBER 1
 '@S9S_MB_2U_LIB.S9S_MB_2U(SCH_1):PAGE532_I173@PURE_QUANTA.Q_CAP(CHIPS)':
 C_PATH='@s9s_mb_2u_lib.s9s_mb_2u(sch_1):page532_i173@pure_quanta.q_cap(chips)';

PART_NAME
 C205 'Q_CAP_0402-0.1UF,25V,10%,X7R,CA':;

SECTION_NUMBER 1
 '@S9S_MB_2U_LIB.S9S_MB_2U(SCH_1):PAGE532_I172@PURE_QUANTA.Q_CAP(CHIPS)':
 C_PATH='@s9s_mb_2u_lib.s9s_mb_2u(sch_1):page532_i172@pure_quanta.q_cap(chips)';

PART_NAME
 C204 'Q_CAP_0402-0.1UF,25V,10%,X7R,CA':;

SECTION_NUMBER 1
 '@S9S_MB_2U_LIB.S9S_MB_2U(SCH_1):PAGE532_I171@PURE_QUANTA.Q_CAP(CHIPS)':
 C_PATH='@s9s_mb_2u_lib.s9s_mb_2u(sch_1):page532_i171@pure_quanta.q_cap(chips)';

PART_NAME
 U93 'SN74LVC1G08DBVR_SMLF-SN74LVC1GA':;

SECTION_NUMBER 1
 '@S9S_MB_2U_LIB.S9S_MB_2U(SCH_1):PAGE622_I18@PURE_QUANTA.SN74LVC1G08DBVR(CHIPS)':
 C_PATH='@s9s_mb_2u_lib.s9s_mb_2u(sch_1):page622_i18@pure_quanta.sn74lvc1g08dbvr(c~
hips)';

PART_NAME
 U81 'SLG55021200010VTR-SLG55021-200A':;

SECTION_NUMBER 1
 '@S9S_MB_2U_LIB.S9S_MB_2U(SCH_1):PAGE622_I49@PURE_QUANTA.SLG55021200010VTR(CHIPS)':
 C_PATH='@s9s_mb_2u_lib.s9s_mb_2u(sch_1):page622_i49@pure_quanta.slg55021200010vtr~
(chips)';

PART_NAME
 U69 'SN74LVC1G17DCKR-SN74LVC1G17DCKA':;

SECTION_NUMBER 1
 '@S9S_MB_2U_LIB.S9S_MB_2U(SCH_1):PAGE622_I3@PURE_QUANTA.SN74LVC1G17DCKR(CHIPS)':
 C_PATH='@s9s_mb_2u_lib.s9s_mb_2u(sch_1):page622_i3@pure_quanta.sn74lvc1g17dckr(ch~
ips)';

PART_NAME
 R1566 'Q_RES_0402LF-0,5%,1/16W,CHIP,CA':;

SECTION_NUMBER 1
 '@S9S_MB_2U_LIB.S9S_MB_2U(SCH_1):PAGE622_I51@PURE_QUANTA.Q_RES(CHIPS)':
 C_PATH='@s9s_mb_2u_lib.s9s_mb_2u(sch_1):page622_i51@pure_quanta.q_res(chips)';

PART_NAME
 R1564 'Q_RES_0402LF-0,5%,1/16W,CHIP,CA':;

SECTION_NUMBER 1
 '@S9S_MB_2U_LIB.S9S_MB_2U(SCH_1):PAGE622_I6@PURE_QUANTA.Q_RES(CHIPS)':
 C_PATH='@s9s_mb_2u_lib.s9s_mb_2u(sch_1):page622_i6@pure_quanta.q_res(chips)';

PART_NAME
 R1562 'Q_RES_0402LF-100K,1%,1/16W,CHIA':;

SECTION_NUMBER 1
 '@S9S_MB_2U_LIB.S9S_MB_2U(SCH_1):PAGE622_I5@PURE_QUANTA.Q_RES(CHIPS)':
 C_PATH='@s9s_mb_2u_lib.s9s_mb_2u(sch_1):page622_i5@pure_quanta.q_res(chips)';

PART_NAME
 R1555 'Q_RES_0402LF-10K,1%,1/16W,CHIPA':;

SECTION_NUMBER 1
 '@S9S_MB_2U_LIB.S9S_MB_2U(SCH_1):PAGE622_I12@PURE_QUANTA.Q_RES(CHIPS)':
 C_PATH='@s9s_mb_2u_lib.s9s_mb_2u(sch_1):page622_i12@pure_quanta.q_res(chips)';

PART_NAME
 Q42 'BSC010NE2LSI-BSC010NE2LSI,SMLFA':;

SECTION_NUMBER 1
 '@S9S_MB_2U_LIB.S9S_MB_2U(SCH_1):PAGE622_I71@PURE_QUANTA.BSC010NE2LSI(CHIPS)':
 C_PATH='@s9s_mb_2u_lib.s9s_mb_2u(sch_1):page622_i71@pure_quanta.bsc010ne2lsi(chip~
s)';

PART_NAME
 Q30 'BSC010NE2LSI-BSC010NE2LSI,SMLFA':;

SECTION_NUMBER 1
 '@S9S_MB_2U_LIB.S9S_MB_2U(SCH_1):PAGE622_I54@PURE_QUANTA.BSC010NE2LSI(CHIPS)':
 C_PATH='@s9s_mb_2u_lib.s9s_mb_2u(sch_1):page622_i54@pure_quanta.bsc010ne2lsi(chip~
s)';

PART_NAME
 C1306 'Q_CAP_0402-0.1UF,25V,10%,X7R,CA':;

SECTION_NUMBER 1
 '@S9S_MB_2U_LIB.S9S_MB_2U(SCH_1):PAGE622_I26@PURE_QUANTA.Q_CAP(CHIPS)':
 C_PATH='@s9s_mb_2u_lib.s9s_mb_2u(sch_1):page622_i26@pure_quanta.q_cap(chips)';

PART_NAME
 C645 'Q_CAP_C0805-10UF,25V,10%,X6S,CA':;

SECTION_NUMBER 1
 '@S9S_MB_2U_LIB.S9S_MB_2U(SCH_1):PAGE622_I70@PURE_QUANTA.Q_CAP(CHIPS)':
 C_PATH='@s9s_mb_2u_lib.s9s_mb_2u(sch_1):page622_i70@pure_quanta.q_cap(chips)';

PART_NAME
 C612 'Q_CAP_0402-0.1UF,25V,10%,X7R,CA':;

SECTION_NUMBER 1
 '@S9S_MB_2U_LIB.S9S_MB_2U(SCH_1):PAGE622_I69@PURE_QUANTA.Q_CAP(CHIPS)':
 C_PATH='@s9s_mb_2u_lib.s9s_mb_2u(sch_1):page622_i69@pure_quanta.q_cap(chips)';

PART_NAME
 C202 'Q_CAP_C0805-10UF,25V,10%,X6S,CA':;

SECTION_NUMBER 1
 '@S9S_MB_2U_LIB.S9S_MB_2U(SCH_1):PAGE622_I66@PURE_QUANTA.Q_CAP(CHIPS)':
 C_PATH='@s9s_mb_2u_lib.s9s_mb_2u(sch_1):page622_i66@pure_quanta.q_cap(chips)';

PART_NAME
 C200 'Q_CAP_0402-0.1UF,25V,10%,X7R,CA':;

SECTION_NUMBER 1
 '@S9S_MB_2U_LIB.S9S_MB_2U(SCH_1):PAGE622_I65@PURE_QUANTA.Q_CAP(CHIPS)':
 C_PATH='@s9s_mb_2u_lib.s9s_mb_2u(sch_1):page622_i65@pure_quanta.q_cap(chips)';

PART_NAME
 C198 'Q_CAP_0402-150PF,50V,5%,EMPTY,A':;

SECTION_NUMBER 1
 '@S9S_MB_2U_LIB.S9S_MB_2U(SCH_1):PAGE622_I53@PURE_QUANTA.Q_CAP(CHIPS)':
 C_PATH='@s9s_mb_2u_lib.s9s_mb_2u(sch_1):page622_i53@pure_quanta.q_cap(chips)';

PART_NAME
 C196 'Q_CAP_0402-0.1UF,25V,10%,X7R,CA':;

SECTION_NUMBER 1
 '@S9S_MB_2U_LIB.S9S_MB_2U(SCH_1):PAGE622_I30@PURE_QUANTA.Q_CAP(CHIPS)':
 C_PATH='@s9s_mb_2u_lib.s9s_mb_2u(sch_1):page622_i30@pure_quanta.q_cap(chips)';

PART_NAME
 C194 'Q_CAP_0402-0.1UF,25V,10%,X7R,CA':;

SECTION_NUMBER 1
 '@S9S_MB_2U_LIB.S9S_MB_2U(SCH_1):PAGE622_I8@PURE_QUANTA.Q_CAP(CHIPS)':
 C_PATH='@s9s_mb_2u_lib.s9s_mb_2u(sch_1):page622_i8@pure_quanta.q_cap(chips)';

PART_NAME
 C192 'Q_CAP_0402-0.1UF,25V,10%,X7R,CA':;

SECTION_NUMBER 1
 '@S9S_MB_2U_LIB.S9S_MB_2U(SCH_1):PAGE622_I14@PURE_QUANTA.Q_CAP(CHIPS)':
 C_PATH='@s9s_mb_2u_lib.s9s_mb_2u(sch_1):page622_i14@pure_quanta.q_cap(chips)';

PART_NAME
 U107 'SLG55021200010VTR-SLG55021-200A':;

SECTION_NUMBER 1
 '@S9S_MB_2U_LIB.S9S_MB_2U(SCH_1):PAGE570_I89@PURE_QUANTA.SLG55021200010VTR(CHIPS)':
 C_PATH='@s9s_mb_2u_lib.s9s_mb_2u(sch_1):page570_i89@pure_quanta.slg55021200010vtr~
(chips)';

PART_NAME
 U106 'SN74LVC1G17DCKR-SN74LVC1G17DCKA':;

SECTION_NUMBER 1
 '@S9S_MB_2U_LIB.S9S_MB_2U(SCH_1):PAGE570_I94@PURE_QUANTA.SN74LVC1G17DCKR(CHIPS)':
 C_PATH='@s9s_mb_2u_lib.s9s_mb_2u(sch_1):page570_i94@pure_quanta.sn74lvc1g17dckr(c~
hips)';

PART_NAME
 U80 'SLG55021200010VTR-SLG55021-200A':;

SECTION_NUMBER 1
 '@S9S_MB_2U_LIB.S9S_MB_2U(SCH_1):PAGE570_I19@PURE_QUANTA.SLG55021200010VTR(CHIPS)':
 C_PATH='@s9s_mb_2u_lib.s9s_mb_2u(sch_1):page570_i19@pure_quanta.slg55021200010vtr~
(chips)';

PART_NAME
 U20 'SN74LVC1G17DCKR-SN74LVC1G17DCKA':;

SECTION_NUMBER 1
 '@S9S_MB_2U_LIB.S9S_MB_2U(SCH_1):PAGE570_I50@PURE_QUANTA.SN74LVC1G17DCKR(CHIPS)':
 C_PATH='@s9s_mb_2u_lib.s9s_mb_2u(sch_1):page570_i50@pure_quanta.sn74lvc1g17dckr(c~
hips)';

PART_NAME
 R1805 'Q_RES_0402LF-0,5%,1/16W,CHIP,CA':;

SECTION_NUMBER 1
 '@S9S_MB_2U_LIB.S9S_MB_2U(SCH_1):PAGE570_I88@PURE_QUANTA.Q_RES(CHIPS)':
 C_PATH='@s9s_mb_2u_lib.s9s_mb_2u(sch_1):page570_i88@pure_quanta.q_res(chips)';

PART_NAME
 R1804 'Q_RES_0402LF-0,5%,1/16W,CHIP,CA':;

SECTION_NUMBER 1
 '@S9S_MB_2U_LIB.S9S_MB_2U(SCH_1):PAGE570_I93@PURE_QUANTA.Q_RES(CHIPS)':
 C_PATH='@s9s_mb_2u_lib.s9s_mb_2u(sch_1):page570_i93@pure_quanta.q_res(chips)';

PART_NAME
 R1803 'Q_RES_0402LF-100K,1%,1/16W,CHIA':;

SECTION_NUMBER 1
 '@S9S_MB_2U_LIB.S9S_MB_2U(SCH_1):PAGE570_I90@PURE_QUANTA.Q_RES(CHIPS)':
 C_PATH='@s9s_mb_2u_lib.s9s_mb_2u(sch_1):page570_i90@pure_quanta.q_res(chips)';

PART_NAME
 R1802 'Q_RES_0402LF-0,5%,1/16W,CHIP,CA':;

SECTION_NUMBER 1
 '@S9S_MB_2U_LIB.S9S_MB_2U(SCH_1):PAGE570_I98@PURE_QUANTA.Q_RES(CHIPS)':
 C_PATH='@s9s_mb_2u_lib.s9s_mb_2u(sch_1):page570_i98@pure_quanta.q_res(chips)';

PART_NAME
 R1569 'Q_RES_0402LF-4.7K,5%,1/16W,CHIA':;

SECTION_NUMBER 1
 '@S9S_MB_2U_LIB.S9S_MB_2U(SCH_1):PAGE570_I39@PURE_QUANTA.Q_RES(CHIPS)':
 C_PATH='@s9s_mb_2u_lib.s9s_mb_2u(sch_1):page570_i39@pure_quanta.q_res(chips)';

PART_NAME
 R1568 'Q_RES_0402LF-0,5%,1/16W,CHIP,CA':;

SECTION_NUMBER 1
 '@S9S_MB_2U_LIB.S9S_MB_2U(SCH_1):PAGE570_I41@PURE_QUANTA.Q_RES(CHIPS)':
 C_PATH='@s9s_mb_2u_lib.s9s_mb_2u(sch_1):page570_i41@pure_quanta.q_res(chips)';

PART_NAME
 R1567 'Q_RES_0402LF-0,5%,1/16W,CHIP,CA':;

SECTION_NUMBER 1
 '@S9S_MB_2U_LIB.S9S_MB_2U(SCH_1):PAGE570_I40@PURE_QUANTA.Q_RES(CHIPS)':
 C_PATH='@s9s_mb_2u_lib.s9s_mb_2u(sch_1):page570_i40@pure_quanta.q_res(chips)';

PART_NAME
 R1565 'Q_RES_0402LF-0,5%,1/16W,CHIP,CA':;

SECTION_NUMBER 1
 '@S9S_MB_2U_LIB.S9S_MB_2U(SCH_1):PAGE570_I17@PURE_QUANTA.Q_RES(CHIPS)':
 C_PATH='@s9s_mb_2u_lib.s9s_mb_2u(sch_1):page570_i17@pure_quanta.q_res(chips)';

PART_NAME
 R1563 'Q_RES_0402LF-0,5%,1/16W,CHIP,CA':;

SECTION_NUMBER 1
 '@S9S_MB_2U_LIB.S9S_MB_2U(SCH_1):PAGE570_I47@PURE_QUANTA.Q_RES(CHIPS)':
 C_PATH='@s9s_mb_2u_lib.s9s_mb_2u(sch_1):page570_i47@pure_quanta.q_res(chips)';

PART_NAME
 R1561 'Q_RES_0402LF-100K,1%,1/16W,CHIA':;

SECTION_NUMBER 1
 '@S9S_MB_2U_LIB.S9S_MB_2U(SCH_1):PAGE570_I48@PURE_QUANTA.Q_RES(CHIPS)':
 C_PATH='@s9s_mb_2u_lib.s9s_mb_2u(sch_1):page570_i48@pure_quanta.q_res(chips)';

PART_NAME
 Q40 'BSC010NE2LSI-BSC010NE2LSI,SMLFA':;

SECTION_NUMBER 1
 '@S9S_MB_2U_LIB.S9S_MB_2U(SCH_1):PAGE570_I99@PURE_QUANTA.BSC010NE2LSI(CHIPS)':
 C_PATH='@s9s_mb_2u_lib.s9s_mb_2u(sch_1):page570_i99@pure_quanta.bsc010ne2lsi(chip~
s)';

PART_NAME
 Q38 'BSC010NE2LSI-BSC010NE2LSI,SMLFA':;

SECTION_NUMBER 1
 '@S9S_MB_2U_LIB.S9S_MB_2U(SCH_1):PAGE570_I86@PURE_QUANTA.BSC010NE2LSI(CHIPS)':
 C_PATH='@s9s_mb_2u_lib.s9s_mb_2u(sch_1):page570_i86@pure_quanta.bsc010ne2lsi(chip~
s)';

PART_NAME
 Q29 'BSC010NE2LSI-BSC010NE2LSI,SMLFA':;

SECTION_NUMBER 1
 '@S9S_MB_2U_LIB.S9S_MB_2U(SCH_1):PAGE570_I13@PURE_QUANTA.BSC010NE2LSI(CHIPS)':
 C_PATH='@s9s_mb_2u_lib.s9s_mb_2u(sch_1):page570_i13@pure_quanta.bsc010ne2lsi(chip~
s)';

PART_NAME
 C1361 'Q_CAP_C0805-10UF,25V,10%,X6S,CA':;

SECTION_NUMBER 1
 '@S9S_MB_2U_LIB.S9S_MB_2U(SCH_1):PAGE570_I85@PURE_QUANTA.Q_CAP(CHIPS)':
 C_PATH='@s9s_mb_2u_lib.s9s_mb_2u(sch_1):page570_i85@pure_quanta.q_cap(chips)';

PART_NAME
 C1360 'Q_CAP_0402-0.1UF,25V,10%,X7R,CA':;

SECTION_NUMBER 1
 '@S9S_MB_2U_LIB.S9S_MB_2U(SCH_1):PAGE570_I84@PURE_QUANTA.Q_CAP(CHIPS)':
 C_PATH='@s9s_mb_2u_lib.s9s_mb_2u(sch_1):page570_i84@pure_quanta.q_cap(chips)';

PART_NAME
 C1359 'Q_CAP_C0805-10UF,25V,10%,X6S,CA':;

SECTION_NUMBER 1
 '@S9S_MB_2U_LIB.S9S_MB_2U(SCH_1):PAGE570_I83@PURE_QUANTA.Q_CAP(CHIPS)':
 C_PATH='@s9s_mb_2u_lib.s9s_mb_2u(sch_1):page570_i83@pure_quanta.q_cap(chips)';

PART_NAME
 C1358 'Q_CAP_0402-0.1UF,25V,10%,X7R,CA':;

SECTION_NUMBER 1
 '@S9S_MB_2U_LIB.S9S_MB_2U(SCH_1):PAGE570_I82@PURE_QUANTA.Q_CAP(CHIPS)':
 C_PATH='@s9s_mb_2u_lib.s9s_mb_2u(sch_1):page570_i82@pure_quanta.q_cap(chips)';

PART_NAME
 C1357 'Q_CAP_0402-150PF,50V,5%,EMPTY,A':;

SECTION_NUMBER 1
 '@S9S_MB_2U_LIB.S9S_MB_2U(SCH_1):PAGE570_I87@PURE_QUANTA.Q_CAP(CHIPS)':
 C_PATH='@s9s_mb_2u_lib.s9s_mb_2u(sch_1):page570_i87@pure_quanta.q_cap(chips)';

PART_NAME
 C1356 'Q_CAP_0402-0.1UF,25V,10%,X7R,CA':;

SECTION_NUMBER 1
 '@S9S_MB_2U_LIB.S9S_MB_2U(SCH_1):PAGE570_I92@PURE_QUANTA.Q_CAP(CHIPS)':
 C_PATH='@s9s_mb_2u_lib.s9s_mb_2u(sch_1):page570_i92@pure_quanta.q_cap(chips)';

PART_NAME
 C1355 'Q_CAP_0402-0.1UF,25V,10%,X7R,CA':;

SECTION_NUMBER 1
 '@S9S_MB_2U_LIB.S9S_MB_2U(SCH_1):PAGE570_I91@PURE_QUANTA.Q_CAP(CHIPS)':
 C_PATH='@s9s_mb_2u_lib.s9s_mb_2u(sch_1):page570_i91@pure_quanta.q_cap(chips)';

PART_NAME
 C1354 'Q_CAP_0402-0.1UF,25V,10%,X7R,CA':;

SECTION_NUMBER 1
 '@S9S_MB_2U_LIB.S9S_MB_2U(SCH_1):PAGE570_I95@PURE_QUANTA.Q_CAP(CHIPS)':
 C_PATH='@s9s_mb_2u_lib.s9s_mb_2u(sch_1):page570_i95@pure_quanta.q_cap(chips)';

PART_NAME
 C642 'Q_CAP_C0805-10UF,25V,10%,X6S,CA':;

SECTION_NUMBER 1
 '@S9S_MB_2U_LIB.S9S_MB_2U(SCH_1):PAGE570_I1@PURE_QUANTA.Q_CAP(CHIPS)':
 C_PATH='@s9s_mb_2u_lib.s9s_mb_2u(sch_1):page570_i1@pure_quanta.q_cap(chips)';

PART_NAME
 C203 'Q_CAP_0402-0.1UF,25V,10%,X7R,CA':;

SECTION_NUMBER 1
 '@S9S_MB_2U_LIB.S9S_MB_2U(SCH_1):PAGE570_I6@PURE_QUANTA.Q_CAP(CHIPS)':
 C_PATH='@s9s_mb_2u_lib.s9s_mb_2u(sch_1):page570_i6@pure_quanta.q_cap(chips)';

PART_NAME
 C201 'Q_CAP_C0805-10UF,25V,10%,X6S,CA':;

SECTION_NUMBER 1
 '@S9S_MB_2U_LIB.S9S_MB_2U(SCH_1):PAGE570_I7@PURE_QUANTA.Q_CAP(CHIPS)':
 C_PATH='@s9s_mb_2u_lib.s9s_mb_2u(sch_1):page570_i7@pure_quanta.q_cap(chips)';

PART_NAME
 C199 'Q_CAP_0402-0.1UF,25V,10%,X7R,CA':;

SECTION_NUMBER 1
 '@S9S_MB_2U_LIB.S9S_MB_2U(SCH_1):PAGE570_I9@PURE_QUANTA.Q_CAP(CHIPS)':
 C_PATH='@s9s_mb_2u_lib.s9s_mb_2u(sch_1):page570_i9@pure_quanta.q_cap(chips)';

PART_NAME
 C197 'Q_CAP_0402-150PF,50V,5%,EMPTY,A':;

SECTION_NUMBER 1
 '@S9S_MB_2U_LIB.S9S_MB_2U(SCH_1):PAGE570_I14@PURE_QUANTA.Q_CAP(CHIPS)':
 C_PATH='@s9s_mb_2u_lib.s9s_mb_2u(sch_1):page570_i14@pure_quanta.q_cap(chips)';

PART_NAME
 C195 'Q_CAP_0402-0.1UF,25V,10%,X7R,CA':;

SECTION_NUMBER 1
 '@S9S_MB_2U_LIB.S9S_MB_2U(SCH_1):PAGE570_I43@PURE_QUANTA.Q_CAP(CHIPS)':
 C_PATH='@s9s_mb_2u_lib.s9s_mb_2u(sch_1):page570_i43@pure_quanta.q_cap(chips)';

PART_NAME
 C193 'Q_CAP_0402-0.1UF,25V,10%,X7R,CA':;

SECTION_NUMBER 1
 '@S9S_MB_2U_LIB.S9S_MB_2U(SCH_1):PAGE570_I45@PURE_QUANTA.Q_CAP(CHIPS)':
 C_PATH='@s9s_mb_2u_lib.s9s_mb_2u(sch_1):page570_i45@pure_quanta.q_cap(chips)';

PART_NAME
 C191 'Q_CAP_0402-0.1UF,25V,10%,X7R,CA':;

SECTION_NUMBER 1
 '@S9S_MB_2U_LIB.S9S_MB_2U(SCH_1):PAGE570_I54@PURE_QUANTA.Q_CAP(CHIPS)':
 C_PATH='@s9s_mb_2u_lib.s9s_mb_2u(sch_1):page570_i54@pure_quanta.q_cap(chips)';

PART_NAME
 U12 'ADM12781ACPZRL_REVA-ADM1278-1AA':;

SECTION_NUMBER 1
 '@S9S_MB_2U_LIB.S9S_MB_2U(SCH_1):PAGE628_I21@PURE_QUANTA.ADM12781ACPZRL_REVA(CHIPS)':
 C_PATH='@s9s_mb_2u_lib.s9s_mb_2u(sch_1):page628_i21@pure_quanta.adm12781acpzrl_re~
va(chips)';

PART_NAME
 R1922 'Q_RES_0402LF-10,1%,1/16W,CHIP,B':;

SECTION_NUMBER 1
 '@S9S_MB_2U_LIB.S9S_MB_2U(SCH_1):PAGE628_I159@PURE_QUANTA.Q_RES(CHIPS)':
 C_PATH='@s9s_mb_2u_lib.s9s_mb_2u(sch_1):page628_i159@pure_quanta.q_res(chips)';

PART_NAME
 R1808 'Q_RES_0402LF-0,5%,1/16W,EMPTY,A':;

SECTION_NUMBER 1
 '@S9S_MB_2U_LIB.S9S_MB_2U(SCH_1):PAGE628_I149@PURE_QUANTA.Q_RES(CHIPS)':
 C_PATH='@s9s_mb_2u_lib.s9s_mb_2u(sch_1):page628_i149@pure_quanta.q_res(chips)';

PART_NAME
 R1807 'Q_RES_0402LF-0,5%,1/16W,CHIP,CA':;

SECTION_NUMBER 1
 '@S9S_MB_2U_LIB.S9S_MB_2U(SCH_1):PAGE628_I147@PURE_QUANTA.Q_RES(CHIPS)':
 C_PATH='@s9s_mb_2u_lib.s9s_mb_2u(sch_1):page628_i147@pure_quanta.q_res(chips)';

PART_NAME
 R1603 'Q_RES_0402LF-100,1%,1/16W,CHIPA':;

SECTION_NUMBER 1
 '@S9S_MB_2U_LIB.S9S_MB_2U(SCH_1):PAGE628_I153@PURE_QUANTA.Q_RES(CHIPS)':
 C_PATH='@s9s_mb_2u_lib.s9s_mb_2u(sch_1):page628_i153@pure_quanta.q_res(chips)';

PART_NAME
 R1602 'Q_RES_0402LF-100,1%,1/16W,CHIPA':;

SECTION_NUMBER 1
 '@S9S_MB_2U_LIB.S9S_MB_2U(SCH_1):PAGE628_I152@PURE_QUANTA.Q_RES(CHIPS)':
 C_PATH='@s9s_mb_2u_lib.s9s_mb_2u(sch_1):page628_i152@pure_quanta.q_res(chips)';

PART_NAME
 R1553 'Q_RES_0402LF-100K,1%,1/16W,CHIA':;

SECTION_NUMBER 1
 '@S9S_MB_2U_LIB.S9S_MB_2U(SCH_1):PAGE628_I144@PURE_QUANTA.Q_RES(CHIPS)':
 C_PATH='@s9s_mb_2u_lib.s9s_mb_2u(sch_1):page628_i144@pure_quanta.q_res(chips)';

PART_NAME
 R1548 'Q_RES_0402LF-7.32K,1%,1/16W,CHB':;

SECTION_NUMBER 1
 '@S9S_MB_2U_LIB.S9S_MB_2U(SCH_1):PAGE628_I142@PURE_QUANTA.Q_RES(CHIPS)':
 C_PATH='@s9s_mb_2u_lib.s9s_mb_2u(sch_1):page628_i142@pure_quanta.q_res(chips)';

PART_NAME
 R1193 'Q_RES_0402LF-1K,5%,1/16W,CHIP,A':;

SECTION_NUMBER 1
 '@S9S_MB_2U_LIB.S9S_MB_2U(SCH_1):PAGE628_I31@PURE_QUANTA.Q_RES(CHIPS)':
 C_PATH='@s9s_mb_2u_lib.s9s_mb_2u(sch_1):page628_i31@pure_quanta.q_res(chips)';

PART_NAME
 R1192 'Q_RES_0402LF-150K,1%,1/16W,CHIA':;

SECTION_NUMBER 1
 '@S9S_MB_2U_LIB.S9S_MB_2U(SCH_1):PAGE628_I24@PURE_QUANTA.Q_RES(CHIPS)':
 C_PATH='@s9s_mb_2u_lib.s9s_mb_2u(sch_1):page628_i24@pure_quanta.q_res(chips)';

PART_NAME
 R1191 'Q_RES_0402LF-0,5%,1/16W,CHIP,CA':;

SECTION_NUMBER 1
 '@S9S_MB_2U_LIB.S9S_MB_2U(SCH_1):PAGE628_I14@PURE_QUANTA.Q_RES(CHIPS)':
 C_PATH='@s9s_mb_2u_lib.s9s_mb_2u(sch_1):page628_i14@pure_quanta.q_res(chips)';

PART_NAME
 R1190 'Q_RES_0402LF-0,5%,1/16W,CHIP,CA':;

SECTION_NUMBER 1
 '@S9S_MB_2U_LIB.S9S_MB_2U(SCH_1):PAGE628_I13@PURE_QUANTA.Q_RES(CHIPS)':
 C_PATH='@s9s_mb_2u_lib.s9s_mb_2u(sch_1):page628_i13@pure_quanta.q_res(chips)';

PART_NAME
 R1189 'Q_RES_0402LF-0,5%,1/16W,CHIP,CA':;

SECTION_NUMBER 1
 '@S9S_MB_2U_LIB.S9S_MB_2U(SCH_1):PAGE628_I26@PURE_QUANTA.Q_RES(CHIPS)':
 C_PATH='@s9s_mb_2u_lib.s9s_mb_2u(sch_1):page628_i26@pure_quanta.q_res(chips)';

PART_NAME
 R1188 'Q_RES_0402LF-10,1%,1/16W,CHIP,B':;

SECTION_NUMBER 1
 '@S9S_MB_2U_LIB.S9S_MB_2U(SCH_1):PAGE628_I30@PURE_QUANTA.Q_RES(CHIPS)':
 C_PATH='@s9s_mb_2u_lib.s9s_mb_2u(sch_1):page628_i30@pure_quanta.q_res(chips)';

PART_NAME
 R1187 'Q_RES_0402LF-33,5%,1/16W,CHIP,A':;

SECTION_NUMBER 1
 '@S9S_MB_2U_LIB.S9S_MB_2U(SCH_1):PAGE628_I33@PURE_QUANTA.Q_RES(CHIPS)':
 C_PATH='@s9s_mb_2u_lib.s9s_mb_2u(sch_1):page628_i33@pure_quanta.q_res(chips)';

PART_NAME
 R1186 'Q_RES_0402LF-33,5%,1/16W,CHIP,A':;

SECTION_NUMBER 1
 '@S9S_MB_2U_LIB.S9S_MB_2U(SCH_1):PAGE628_I34@PURE_QUANTA.Q_RES(CHIPS)':
 C_PATH='@s9s_mb_2u_lib.s9s_mb_2u(sch_1):page628_i34@pure_quanta.q_res(chips)';

PART_NAME
 R1185 'Q_RES_0402LF-10,1%,1/16W,CHIP,B':;

SECTION_NUMBER 1
 '@S9S_MB_2U_LIB.S9S_MB_2U(SCH_1):PAGE628_I42@PURE_QUANTA.Q_RES(CHIPS)':
 C_PATH='@s9s_mb_2u_lib.s9s_mb_2u(sch_1):page628_i42@pure_quanta.q_res(chips)';

PART_NAME
 R1183 'Q_RES_0402LF-10,1%,1/16W,CHIP,B':;

SECTION_NUMBER 1
 '@S9S_MB_2U_LIB.S9S_MB_2U(SCH_1):PAGE628_I44@PURE_QUANTA.Q_RES(CHIPS)':
 C_PATH='@s9s_mb_2u_lib.s9s_mb_2u(sch_1):page628_i44@pure_quanta.q_res(chips)';

PART_NAME
 R1182 'Q_RES_0402LF-4.7K,1%,1/16W,CHIA':;

SECTION_NUMBER 1
 '@S9S_MB_2U_LIB.S9S_MB_2U(SCH_1):PAGE628_I37@PURE_QUANTA.Q_RES(CHIPS)':
 C_PATH='@s9s_mb_2u_lib.s9s_mb_2u(sch_1):page628_i37@pure_quanta.q_res(chips)';

PART_NAME
 R1181 'Q_RES_0402LF-10,1%,1/16W,CHIP,B':;

SECTION_NUMBER 1
 '@S9S_MB_2U_LIB.S9S_MB_2U(SCH_1):PAGE628_I46@PURE_QUANTA.Q_RES(CHIPS)':
 C_PATH='@s9s_mb_2u_lib.s9s_mb_2u(sch_1):page628_i46@pure_quanta.q_res(chips)';

PART_NAME
 R1180 'Q_RES_0402LF-33,5%,1/16W,CHIP,A':;

SECTION_NUMBER 1
 '@S9S_MB_2U_LIB.S9S_MB_2U(SCH_1):PAGE628_I79@PURE_QUANTA.Q_RES(CHIPS)':
 C_PATH='@s9s_mb_2u_lib.s9s_mb_2u(sch_1):page628_i79@pure_quanta.q_res(chips)';

PART_NAME
 R1179 'Q_RES_0402LF-0,5%,1/16W,CHIP,CA':;

SECTION_NUMBER 1
 '@S9S_MB_2U_LIB.S9S_MB_2U(SCH_1):PAGE628_I54@PURE_QUANTA.Q_RES(CHIPS)':
 C_PATH='@s9s_mb_2u_lib.s9s_mb_2u(sch_1):page628_i54@pure_quanta.q_res(chips)';

PART_NAME
 R1178 'Q_RES_0402LF-10,1%,1/16W,CHIP,B':;

SECTION_NUMBER 1
 '@S9S_MB_2U_LIB.S9S_MB_2U(SCH_1):PAGE628_I49@PURE_QUANTA.Q_RES(CHIPS)':
 C_PATH='@s9s_mb_2u_lib.s9s_mb_2u(sch_1):page628_i49@pure_quanta.q_res(chips)';

PART_NAME
 R1177 'Q_RES_0402LF-0,5%,1/16W,CHIP,CA':;

SECTION_NUMBER 1
 '@S9S_MB_2U_LIB.S9S_MB_2U(SCH_1):PAGE628_I57@PURE_QUANTA.Q_RES(CHIPS)':
 C_PATH='@s9s_mb_2u_lib.s9s_mb_2u(sch_1):page628_i57@pure_quanta.q_res(chips)';

PART_NAME
 R1176 'Q_RES_0402LF-10,1%,1/16W,CHIP,B':;

SECTION_NUMBER 1
 '@S9S_MB_2U_LIB.S9S_MB_2U(SCH_1):PAGE628_I95@PURE_QUANTA.Q_RES(CHIPS)':
 C_PATH='@s9s_mb_2u_lib.s9s_mb_2u(sch_1):page628_i95@pure_quanta.q_res(chips)';

PART_NAME
 R1175 'Q_RES_0402LF-10K,1%,1/16W,EMPTA':;

SECTION_NUMBER 1
 '@S9S_MB_2U_LIB.S9S_MB_2U(SCH_1):PAGE628_I81@PURE_QUANTA.Q_RES(CHIPS)':
 C_PATH='@s9s_mb_2u_lib.s9s_mb_2u(sch_1):page628_i81@pure_quanta.q_res(chips)';

PART_NAME
 R1174 'Q_RES_0402LF-10,1%,1/16W,CHIP,B':;

SECTION_NUMBER 1
 '@S9S_MB_2U_LIB.S9S_MB_2U(SCH_1):PAGE628_I98@PURE_QUANTA.Q_RES(CHIPS)':
 C_PATH='@s9s_mb_2u_lib.s9s_mb_2u(sch_1):page628_i98@pure_quanta.q_res(chips)';

PART_NAME
 R1173 'Q_RES_0402LF-100K,1%,1/16W,CHIA':;

SECTION_NUMBER 1
 '@S9S_MB_2U_LIB.S9S_MB_2U(SCH_1):PAGE628_I58@PURE_QUANTA.Q_RES(CHIPS)':
 C_PATH='@s9s_mb_2u_lib.s9s_mb_2u(sch_1):page628_i58@pure_quanta.q_res(chips)';

PART_NAME
 R1172 'Q_SP_RES4P-0.0002,1%,4W,SMLF,CA':;

SECTION_NUMBER 1
 '@S9S_MB_2U_LIB.S9S_MB_2U(SCH_1):PAGE628_I93@PURE_QUANTA.Q_SP_RES4P(CHIPS)':
 C_PATH='@s9s_mb_a_lib.s9s_mb_a(sch_1):page628_i93@pure_quanta.q_sp_res4p(chips)~
';

PART_NAME
 R1171 'Q_SP_RES4P-0.0002,1%,4W,SMLF,CA':;

SECTION_NUMBER 1
 '@S9S_MB_2U_LIB.S9S_MB_2U(SCH_1):PAGE628_I92@PURE_QUANTA.Q_SP_RES4P(CHIPS)':
 C_PATH='@s9s_mb_a_lib.s9s_mb_a(sch_1):page628_i92@pure_quanta.q_sp_res4p(chips)~
';

PART_NAME
 R1170 'Q_RES_0402LF-12.1K,1%,1/16W,CHA':;

SECTION_NUMBER 1
 '@S9S_MB_2U_LIB.S9S_MB_2U(SCH_1):PAGE628_I100@PURE_QUANTA.Q_RES(CHIPS)':
 C_PATH='@s9s_mb_2u_lib.s9s_mb_2u(sch_1):page628_i100@pure_quanta.q_res(chips)';

PART_NAME
 R1169 'Q_RES_0402LF-100K,1%,1/16W,CHIA':;

SECTION_NUMBER 1
 '@S9S_MB_2U_LIB.S9S_MB_2U(SCH_1):PAGE628_I74@PURE_QUANTA.Q_RES(CHIPS)':
 C_PATH='@s9s_mb_2u_lib.s9s_mb_2u(sch_1):page628_i74@pure_quanta.q_res(chips)';

PART_NAME
 R1168 'Q_RES_0402LF-10,1%,1/16W,CHIP,B':;

SECTION_NUMBER 1
 '@S9S_MB_2U_LIB.S9S_MB_2U(SCH_1):PAGE628_I103@PURE_QUANTA.Q_RES(CHIPS)':
 C_PATH='@s9s_mb_2u_lib.s9s_mb_2u(sch_1):page628_i103@pure_quanta.q_res(chips)';

PART_NAME
 R1167 'Q_RES_0402LF-10,1%,1/16W,CHIP,B':;

SECTION_NUMBER 1
 '@S9S_MB_2U_LIB.S9S_MB_2U(SCH_1):PAGE628_I104@PURE_QUANTA.Q_RES(CHIPS)':
 C_PATH='@s9s_mb_2u_lib.s9s_mb_2u(sch_1):page628_i104@pure_quanta.q_res(chips)';

PART_NAME
 R1166 'Q_RES_0402LF-10,1%,1/16W,CHIP,B':;

SECTION_NUMBER 1
 '@S9S_MB_2U_LIB.S9S_MB_2U(SCH_1):PAGE628_I101@PURE_QUANTA.Q_RES(CHIPS)':
 C_PATH='@s9s_mb_2u_lib.s9s_mb_2u(sch_1):page628_i101@pure_quanta.q_res(chips)';

PART_NAME
 R1165 'Q_RES_0402LF-10,1%,1/16W,CHIP,B':;

SECTION_NUMBER 1
 '@S9S_MB_2U_LIB.S9S_MB_2U(SCH_1):PAGE628_I102@PURE_QUANTA.Q_RES(CHIPS)':
 C_PATH='@s9s_mb_2u_lib.s9s_mb_2u(sch_1):page628_i102@pure_quanta.q_res(chips)';

PART_NAME
 R1164 'Q_RES_0402LF-0,5%,1/16W,CHIP,CA':;

SECTION_NUMBER 1
 '@S9S_MB_2U_LIB.S9S_MB_2U(SCH_1):PAGE628_I70@PURE_QUANTA.Q_RES(CHIPS)':
 C_PATH='@s9s_mb_2u_lib.s9s_mb_2u(sch_1):page628_i70@pure_quanta.q_res(chips)';

PART_NAME
 R1163 'Q_RES_0402LF-0,5%,1/16W,CHIP,CA':;

SECTION_NUMBER 1
 '@S9S_MB_2U_LIB.S9S_MB_2U(SCH_1):PAGE628_I69@PURE_QUANTA.Q_RES(CHIPS)':
 C_PATH='@s9s_mb_2u_lib.s9s_mb_2u(sch_1):page628_i69@pure_quanta.q_res(chips)';

PART_NAME
 R1162 'Q_RES_0402LF-68.1K,1%,1/16W,CHA':;

SECTION_NUMBER 1
 '@S9S_MB_2U_LIB.S9S_MB_2U(SCH_1):PAGE628_I68@PURE_QUANTA.Q_RES(CHIPS)':
 C_PATH='@s9s_mb_2u_lib.s9s_mb_2u(sch_1):page628_i68@pure_quanta.q_res(chips)';

PART_NAME
 R1161 'Q_RES_0402LF-68.1K,1%,1/16W,CHA':;

SECTION_NUMBER 1
 '@S9S_MB_2U_LIB.S9S_MB_2U(SCH_1):PAGE628_I67@PURE_QUANTA.Q_RES(CHIPS)':
 C_PATH='@s9s_mb_2u_lib.s9s_mb_2u(sch_1):page628_i67@pure_quanta.q_res(chips)';

PART_NAME
 R1160 'Q_RES_0402LF-8.25K,1%,1/16W,CHA':;

SECTION_NUMBER 1
 '@S9S_MB_2U_LIB.S9S_MB_2U(SCH_1):PAGE628_I77@PURE_QUANTA.Q_RES(CHIPS)':
 C_PATH='@s9s_mb_2u_lib.s9s_mb_2u(sch_1):page628_i77@pure_quanta.q_res(chips)';

PART_NAME
 R1159 'Q_RES_0402LF-100K,1%,1/16W,CHIA':;

SECTION_NUMBER 1
 '@S9S_MB_2U_LIB.S9S_MB_2U(SCH_1):PAGE628_I76@PURE_QUANTA.Q_RES(CHIPS)':
 C_PATH='@s9s_mb_2u_lib.s9s_mb_2u(sch_1):page628_i76@pure_quanta.q_res(chips)';

PART_NAME
 R1158 'Q_RES_0402LF-11K,1%,1/16W,CHIPA':;

SECTION_NUMBER 1
 '@S9S_MB_2U_LIB.S9S_MB_2U(SCH_1):PAGE628_I113@PURE_QUANTA.Q_RES(CHIPS)':
 C_PATH='@s9s_mb_2u_lib.s9s_mb_2u(sch_1):page628_i113@pure_quanta.q_res(chips)';

PART_NAME
 R1157 'Q_RES_0402LF-100K,1%,1/16W,CHIA':;

SECTION_NUMBER 1
 '@S9S_MB_2U_LIB.S9S_MB_2U(SCH_1):PAGE628_I110@PURE_QUANTA.Q_RES(CHIPS)':
 C_PATH='@s9s_mb_2u_lib.s9s_mb_2u(sch_1):page628_i110@pure_quanta.q_res(chips)';

PART_NAME
 R1156 'Q_RES_0402LF-82K,1%,1/16W,CHIPA':;

SECTION_NUMBER 1
 '@S9S_MB_2U_LIB.S9S_MB_2U(SCH_1):PAGE628_I163@PURE_QUANTA.Q_RES(CHIPS)':
 C_PATH='@s9s_mb_2u_lib.s9s_mb_2u(sch_1):page628_i163@pure_quanta.q_res(chips)';

PART_NAME
 R1155 'Q_RES_0402LF-100K,1%,1/16W,CHIA':;

SECTION_NUMBER 1
 '@S9S_MB_2U_LIB.S9S_MB_2U(SCH_1):PAGE628_I123@PURE_QUANTA.Q_RES(CHIPS)':
 C_PATH='@s9s_mb_2u_lib.s9s_mb_2u(sch_1):page628_i123@pure_quanta.q_res(chips)';

PART_NAME
 R1154 'Q_RES_0402LF-100K,1%,1/16W,CHIA':;

SECTION_NUMBER 1
 '@S9S_MB_2U_LIB.S9S_MB_2U(SCH_1):PAGE628_I120@PURE_QUANTA.Q_RES(CHIPS)':
 C_PATH='@s9s_mb_2u_lib.s9s_mb_2u(sch_1):page628_i120@pure_quanta.q_res(chips)';

PART_NAME
 R1153 'Q_RES_0402LF-31.6K,1%,1/16W,CHA':;

SECTION_NUMBER 1
 '@S9S_MB_2U_LIB.S9S_MB_2U(SCH_1):PAGE628_I161@PURE_QUANTA.Q_RES(CHIPS)':
 C_PATH='@s9s_mb_2u_lib.s9s_mb_2u(sch_1):page628_i161@pure_quanta.q_res(chips)';

PART_NAME
 R1152 'Q_RES_0402LF-7.5K,1%,1/16W,CHIA':;

SECTION_NUMBER 1
 '@S9S_MB_2U_LIB.S9S_MB_2U(SCH_1):PAGE628_I136@PURE_QUANTA.Q_RES(CHIPS)':
 C_PATH='@s9s_mb_2u_lib.s9s_mb_2u(sch_1):page628_i136@pure_quanta.q_res(chips)';

PART_NAME
 R1151 'Q_RES_0402LF-100K,1%,1/16W,CHIA':;

SECTION_NUMBER 1
 '@S9S_MB_2U_LIB.S9S_MB_2U(SCH_1):PAGE628_I133@PURE_QUANTA.Q_RES(CHIPS)':
 C_PATH='@s9s_mb_2u_lib.s9s_mb_2u(sch_1):page628_i133@pure_quanta.q_res(chips)';

PART_NAME
 Q36 'MMBT39047F-MMBT3904-7-F,SMLF,IA':;

SECTION_NUMBER 1
 '@S9S_MB_2U_LIB.S9S_MB_2U(SCH_1):PAGE628_I151@PURE_QUANTA.MMBT39047F(CHIPS)':
 C_PATH='@s9s_mb_2u_lib.s9s_mb_2u(sch_1):page628_i151@pure_quanta.mmbt39047f(chips~
)';

PART_NAME
 Q26 '2N7002A7-2N7002A-7,SMLF,IC,BAMA':;

SECTION_NUMBER 1
 '@S9S_MB_2U_LIB.S9S_MB_2U(SCH_1):PAGE628_I11@PURE_QUANTA.2N7002A7(CHIPS)':
 C_PATH='@s9s_mb_a_lib.s9s_mb_a(sch_1):page628_i11@pure_quanta.\2n7002a7\(chips)~
';

PART_NAME
 Q25 'MOSFET_DUAL_6P-2N7002KDW,SMLF,A':;

SECTION_NUMBER 1
 '@S9S_MB_2U_LIB.S9S_MB_2U(SCH_1):PAGE628_I71@PURE_QUANTA.MOSFET_DUAL_6P(CHIPS)':
 C_PATH='@s9s_mb_2u_lib.s9s_mb_2u(sch_1):page628_i71@pure_quanta.mosfet_dual_6p(ch~
ips)';

PART_NAME
 PQ16 'MOSFET_NCH_1D3S-PSMNR58-30YLH,A':;

SECTION_NUMBER 1
 '@S9S_MB_2U_LIB.S9S_MB_2U(SCH_1):PAGE628_I160@PURE_QUANTA.MOSFET_NCH_1D3S(CHIPS)':
 C_PATH='@s9s_mb_2u_lib.s9s_mb_2u(sch_1):page628_i160@pure_quanta.mosfet_nch_1d3s(~
chips)';

PART_NAME
 PQ15 'MOSFET_NCH_1D3S-PSMNR58-30YLH,A':;

SECTION_NUMBER 1
 '@S9S_MB_2U_LIB.S9S_MB_2U(SCH_1):PAGE628_I29@PURE_QUANTA.MOSFET_NCH_1D3S(CHIPS)':
 C_PATH='@s9s_mb_2u_lib.s9s_mb_2u(sch_1):page628_i29@pure_quanta.mosfet_nch_1d3s(c~
hips)';

PART_NAME
 PQ14 'MOSFET_NCH_1D3S-PSMNR58-30YLH,A':;

SECTION_NUMBER 1
 '@S9S_MB_2U_LIB.S9S_MB_2U(SCH_1):PAGE628_I41@PURE_QUANTA.MOSFET_NCH_1D3S(CHIPS)':
 C_PATH='@s9s_mb_2u_lib.s9s_mb_2u(sch_1):page628_i41@pure_quanta.mosfet_nch_1d3s(c~
hips)';

PART_NAME
 PQ13 'MOSFET_NCH_1D3S-PSMNR58-30YLH,A':;

SECTION_NUMBER 1
 '@S9S_MB_2U_LIB.S9S_MB_2U(SCH_1):PAGE628_I43@PURE_QUANTA.MOSFET_NCH_1D3S(CHIPS)':
 C_PATH='@s9s_mb_2u_lib.s9s_mb_2u(sch_1):page628_i43@pure_quanta.mosfet_nch_1d3s(c~
hips)';

PART_NAME
 PQ12 'MOSFET_NCH_1D3S-PSMNR58-30YLH,A':;

SECTION_NUMBER 1
 '@S9S_MB_2U_LIB.S9S_MB_2U(SCH_1):PAGE628_I45@PURE_QUANTA.MOSFET_NCH_1D3S(CHIPS)':
 C_PATH='@s9s_mb_2u_lib.s9s_mb_2u(sch_1):page628_i45@pure_quanta.mosfet_nch_1d3s(c~
hips)';

PART_NAME
 PQ11 'MOSFET_NCH_1D3S-PSMNR58-30YLH,A':;

SECTION_NUMBER 1
 '@S9S_MB_2U_LIB.S9S_MB_2U(SCH_1):PAGE628_I94@PURE_QUANTA.MOSFET_NCH_1D3S(CHIPS)':
 C_PATH='@s9s_mb_2u_lib.s9s_mb_2u(sch_1):page628_i94@pure_quanta.mosfet_nch_1d3s(c~
hips)';

PART_NAME
 JP3 'CONN3_210HP1030BR1-CONN3_210-HA':;

SECTION_NUMBER 1
 '@S9S_MB_2U_LIB.S9S_MB_2U(SCH_1):PAGE628_I124@PURE_QUANTA.CONN3_210HP1030BR1(CHIPS)':
 C_PATH='@s9s_mb_2u_lib.s9s_mb_2u(sch_1):page628_i124@pure_quanta.conn3_210hp1030b~
r1(chips)';

PART_NAME
 D5 'ZENER_AC-5.0SMDJ14A,SMLF,IC,BCA':;

SECTION_NUMBER 1
 '@S9S_MB_2U_LIB.S9S_MB_2U(SCH_1):PAGE628_I134@PURE_QUANTA.ZENER_AC(CHIPS)':
 C_PATH='@s9s_mb_2u_lib.s9s_mb_2u(sch_1):page628_i134@pure_quanta.zener_ac(chips)';

PART_NAME
 C604 'Q_CAP_C0402-100NF,50V,10%,EMPTA':;

SECTION_NUMBER 1
 '@S9S_MB_2U_LIB.S9S_MB_2U(SCH_1):PAGE628_I10@PURE_QUANTA.Q_CAP(CHIPS)':
 C_PATH='@s9s_mb_2u_lib.s9s_mb_2u(sch_1):page628_i10@pure_quanta.q_cap(chips)';

PART_NAME
 C603 'Q_CAP_C0402-0.015UF,50V,10%,EMA':;

SECTION_NUMBER 1
 '@S9S_MB_2U_LIB.S9S_MB_2U(SCH_1):PAGE628_I12@PURE_QUANTA.Q_CAP(CHIPS)':
 C_PATH='@s9s_mb_2u_lib.s9s_mb_2u(sch_1):page628_i12@pure_quanta.q_cap(chips)';

PART_NAME
 C602 'Q_CAP_C0603-0.068UF,50V,10%,X7A':;

SECTION_NUMBER 1
 '@S9S_MB_2U_LIB.S9S_MB_2U(SCH_1):PAGE628_I96@PURE_QUANTA.Q_CAP(CHIPS)':
 C_PATH='@s9s_mb_2u_lib.s9s_mb_2u(sch_1):page628_i96@pure_quanta.q_cap(chips)';

PART_NAME
 C601 'Q_CAP_C0402-1UF,25V,10%,X6S,CHA':;

SECTION_NUMBER 1
 '@S9S_MB_2U_LIB.S9S_MB_2U(SCH_1):PAGE628_I50@PURE_QUANTA.Q_CAP(CHIPS)':
 C_PATH='@s9s_mb_2u_lib.s9s_mb_2u(sch_1):page628_i50@pure_quanta.q_cap(chips)';

PART_NAME
 C600 'Q_CAP_C0402-1UF,25V,10%,X6S,CHA':;

SECTION_NUMBER 1
 '@S9S_MB_2U_LIB.S9S_MB_2U(SCH_1):PAGE628_I52@PURE_QUANTA.Q_CAP(CHIPS)':
 C_PATH='@s9s_mb_2u_lib.s9s_mb_2u(sch_1):page628_i52@pure_quanta.q_cap(chips)';

PART_NAME
 C599 'Q_CAP_C0603-0.033UF,50V,10%,X7A':;

SECTION_NUMBER 1
 '@S9S_MB_2U_LIB.S9S_MB_2U(SCH_1):PAGE628_I148@PURE_QUANTA.Q_CAP(CHIPS)':
 C_PATH='@s9s_mb_2u_lib.s9s_mb_2u(sch_1):page628_i148@pure_quanta.q_cap(chips)';

PART_NAME
 C598 'Q_CAP_C0402-100NF,50V,10%,X7R,A':;

SECTION_NUMBER 1
 '@S9S_MB_2U_LIB.S9S_MB_2U(SCH_1):PAGE628_I59@PURE_QUANTA.Q_CAP(CHIPS)':
 C_PATH='@s9s_mb_2u_lib.s9s_mb_2u(sch_1):page628_i59@pure_quanta.q_cap(chips)';

PART_NAME
 C597 'Q_CAP_C0402-100NF,50V,10%,EMPTA':;

SECTION_NUMBER 1
 '@S9S_MB_2U_LIB.S9S_MB_2U(SCH_1):PAGE628_I75@PURE_QUANTA.Q_CAP(CHIPS)':
 C_PATH='@s9s_mb_2u_lib.s9s_mb_2u(sch_1):page628_i75@pure_quanta.q_cap(chips)';

PART_NAME
 C596 'Q_CAP_C0402-100NF,50V,10%,X7R,A':;

SECTION_NUMBER 1
 '@S9S_MB_2U_LIB.S9S_MB_2U(SCH_1):PAGE628_I115@PURE_QUANTA.Q_CAP(CHIPS)':
 C_PATH='@s9s_mb_2u_lib.s9s_mb_2u(sch_1):page628_i115@pure_quanta.q_cap(chips)';

PART_NAME
 C595 'Q_CAP_C0402-100NF,50V,10%,X7R,A':;

SECTION_NUMBER 1
 '@S9S_MB_2U_LIB.S9S_MB_2U(SCH_1):PAGE628_I109@PURE_QUANTA.Q_CAP(CHIPS)':
 C_PATH='@s9s_mb_2u_lib.s9s_mb_2u(sch_1):page628_i109@pure_quanta.q_cap(chips)';

PART_NAME
 C594 'Q_CAP_C0402-100NF,50V,10%,X7R,A':;

SECTION_NUMBER 1
 '@S9S_MB_2U_LIB.S9S_MB_2U(SCH_1):PAGE628_I137@PURE_QUANTA.Q_CAP(CHIPS)':
 C_PATH='@s9s_mb_2u_lib.s9s_mb_2u(sch_1):page628_i137@pure_quanta.q_cap(chips)';

PART_NAME
 C585 'Q_CAP_0402-1NF,50V,10%,X7R,CH2A':;

SECTION_NUMBER 1
 '@S9S_MB_2U_LIB.S9S_MB_2U(SCH_1):PAGE628_I154@PURE_QUANTA.Q_CAP(CHIPS)':
 C_PATH='@s9s_mb_2u_lib.s9s_mb_2u(sch_1):page628_i154@pure_quanta.q_cap(chips)';

PART_NAME
 C190 'Q_CAP_C0402-100NF,50V,10%,EMPTA':;

SECTION_NUMBER 1
 '@S9S_MB_2U_LIB.S9S_MB_2U(SCH_1):PAGE628_I140@PURE_QUANTA.Q_CAP(CHIPS)':
 C_PATH='@s9s_mb_2u_lib.s9s_mb_2u(sch_1):page628_i140@pure_quanta.q_cap(chips)';

PART_NAME
 U104 '74LVC1G07GV-74LVC1G07GV,SMLF,IA':;

SECTION_NUMBER 1
 '@S9S_MB_2U_LIB.S9S_MB_2U(SCH_1):PAGE502_I63@PURE_QUANTA.74LVC1G07GV(CHIPS)':
 C_PATH='@s9s_mb_2u_lib.s9s_mb_2u(sch_1):page502_i63@pure_quanta.\74lvc1g07gv\(chi~
ps)';

PART_NAME
 U90 'PI6CV304LE-PI6CV304LE,SMLF,IC,A':;

SECTION_NUMBER 1
 '@S9S_MB_2U_LIB.S9S_MB_2U(SCH_1):PAGE502_I46@PURE_QUANTA.PI6CV304LE(CHIPS)':
 C_PATH='@s9s_mb_a_lib.s9s_mb_a(sch_1):page502_i46@pure_quanta.pi6cv304le(chips)~
';

PART_NAME
 U82 '74LVC1G126GW_SMLF-74LVC1G126GWA':;

SECTION_NUMBER 1
 '@S9S_MB_2U_LIB.S9S_MB_2U(SCH_1):PAGE502_I35@PURE_QUANTA.74LVC1G126GW(CHIPS)':
 C_PATH='@s9s_mb_2u_lib.s9s_mb_2u(sch_1):page502_i35@pure_quanta.\74lvc1g126gw\(ch~
ips)';

PART_NAME
 U75 'SN74LVC1G17DCKR-SN74LVC1G17DCKA':;

SECTION_NUMBER 1
 '@S9S_MB_2U_LIB.S9S_MB_2U(SCH_1):PAGE502_I1@PURE_QUANTA.SN74LVC1G17DCKR(CHIPS)':
 C_PATH='@s9s_mb_2u_lib.s9s_mb_2u(sch_1):page502_i1@pure_quanta.sn74lvc1g17dckr(ch~
ips)';

PART_NAME
 R1824 'Q_RES_0402LF-10K,1%,1/16W,EMPTA':;

SECTION_NUMBER 1
 '@S9S_MB_2U_LIB.S9S_MB_2U(SCH_1):PAGE502_I62@PURE_QUANTA.Q_RES(CHIPS)':
 C_PATH='@s9s_mb_2u_lib.s9s_mb_2u(sch_1):page502_i62@pure_quanta.q_res(chips)';

PART_NAME
 R1595 'Q_RES_0402LF-33.2,1%,1/16W,CHIA':;

SECTION_NUMBER 1
 '@S9S_MB_2U_LIB.S9S_MB_2U(SCH_1):PAGE502_I40@PURE_QUANTA.Q_RES(CHIPS)':
 C_PATH='@s9s_mb_2u_lib.s9s_mb_2u(sch_1):page502_i40@pure_quanta.q_res(chips)';

PART_NAME
 R1594 'Q_RES_0402LF-33.2,1%,1/16W,CHIA':;

SECTION_NUMBER 1
 '@S9S_MB_2U_LIB.S9S_MB_2U(SCH_1):PAGE502_I26@PURE_QUANTA.Q_RES(CHIPS)':
 C_PATH='@s9s_mb_2u_lib.s9s_mb_2u(sch_1):page502_i26@pure_quanta.q_res(chips)';

PART_NAME
 R1593 'Q_RES_0402LF-4.7K,1%,1/16W,EMPA':;

SECTION_NUMBER 1
 '@S9S_MB_2U_LIB.S9S_MB_2U(SCH_1):PAGE502_I42@PURE_QUANTA.Q_RES(CHIPS)':
 C_PATH='@s9s_mb_2u_lib.s9s_mb_2u(sch_1):page502_i42@pure_quanta.q_res(chips)';

PART_NAME
 R1592 'Q_RES_0402LF-10K,1%,1/16W,CHIPA':;

SECTION_NUMBER 1
 '@S9S_MB_2U_LIB.S9S_MB_2U(SCH_1):PAGE502_I37@PURE_QUANTA.Q_RES(CHIPS)':
 C_PATH='@s9s_mb_2u_lib.s9s_mb_2u(sch_1):page502_i37@pure_quanta.q_res(chips)';

PART_NAME
 R1505 'Q_RES_0402LF-33.2,1%,1/16W,CHIA':;

SECTION_NUMBER 1
 '@S9S_MB_2U_LIB.S9S_MB_2U(SCH_1):PAGE502_I13@PURE_QUANTA.Q_RES(CHIPS)':
 C_PATH='@s9s_mb_2u_lib.s9s_mb_2u(sch_1):page502_i13@pure_quanta.q_res(chips)';

PART_NAME
 R1504 'Q_RES_0402LF-33.2,1%,1/16W,CHIA':;

SECTION_NUMBER 1
 '@S9S_MB_2U_LIB.S9S_MB_2U(SCH_1):PAGE502_I10@PURE_QUANTA.Q_RES(CHIPS)':
 C_PATH='@s9s_mb_2u_lib.s9s_mb_2u(sch_1):page502_i10@pure_quanta.q_res(chips)';

PART_NAME
 R1141 'Q_RES_0402LF-27.4,1%,1/16W,CHIA':;

SECTION_NUMBER 1
 '@S9S_MB_2U_LIB.S9S_MB_2U(SCH_1):PAGE502_I53@PURE_QUANTA.Q_RES(CHIPS)':
 C_PATH='@s9s_mb_2u_lib.s9s_mb_2u(sch_1):page502_i53@pure_quanta.q_res(chips)';

PART_NAME
 R1140 'Q_RES_0402LF-27.4,1%,1/16W,CHIA':;

SECTION_NUMBER 1
 '@S9S_MB_2U_LIB.S9S_MB_2U(SCH_1):PAGE502_I52@PURE_QUANTA.Q_RES(CHIPS)':
 C_PATH='@s9s_mb_2u_lib.s9s_mb_2u(sch_1):page502_i52@pure_quanta.q_res(chips)';

PART_NAME
 R1139 'Q_RES_0402LF-0,5%,1/16W,CHIP,CA':;

SECTION_NUMBER 1
 '@S9S_MB_2U_LIB.S9S_MB_2U(SCH_1):PAGE502_I56@PURE_QUANTA.Q_RES(CHIPS)':
 C_PATH='@s9s_mb_2u_lib.s9s_mb_2u(sch_1):page502_i56@pure_quanta.q_res(chips)';

PART_NAME
 R1138 'Q_RES_0402LF-10K,1%,1/16W,CHIPA':;

SECTION_NUMBER 1
 '@S9S_MB_2U_LIB.S9S_MB_2U(SCH_1):PAGE502_I61@PURE_QUANTA.Q_RES(CHIPS)':
 C_PATH='@s9s_mb_2u_lib.s9s_mb_2u(sch_1):page502_i61@pure_quanta.q_res(chips)';

PART_NAME
 R435 'Q_RES_0402LF-33.2,1%,1/16W,CHIA':;

SECTION_NUMBER 1
 '@S9S_MB_2U_LIB.S9S_MB_2U(SCH_1):PAGE502_I8@PURE_QUANTA.Q_RES(CHIPS)':
 C_PATH='@s9s_mb_2u_lib.s9s_mb_2u(sch_1):page502_i8@pure_quanta.q_res(chips)';

PART_NAME
 R419 'Q_RES_0402LF-33.2,1%,1/16W,CHIA':;

SECTION_NUMBER 1
 '@S9S_MB_2U_LIB.S9S_MB_2U(SCH_1):PAGE502_I6@PURE_QUANTA.Q_RES(CHIPS)':
 C_PATH='@s9s_mb_2u_lib.s9s_mb_2u(sch_1):page502_i6@pure_quanta.q_res(chips)';

PART_NAME
 OSC1 'OSC4_SIT1602AI2233E50000000D-5A':;

SECTION_NUMBER 1
 '@S9S_MB_2U_LIB.S9S_MB_2U(SCH_1):PAGE502_I58@PURE_QUANTA.OSC4_SIT1602AI2233E50000000D(CHIPS)':
 C_PATH='@s9s_mb_2u_lib.s9s_mb_2u(sch_1):page502_i58@pure_quanta.osc4_sit1602ai223~
3e50000000d(chips)';

PART_NAME
 C1275 'Q_CAP_0402-0.1UF,25V,10%,X7R,CA':;

SECTION_NUMBER 1
 '@S9S_MB_2U_LIB.S9S_MB_2U(SCH_1):PAGE502_I49@PURE_QUANTA.Q_CAP(CHIPS)':
 C_PATH='@s9s_mb_2u_lib.s9s_mb_2u(sch_1):page502_i49@pure_quanta.q_cap(chips)';

PART_NAME
 C1274 'Q_CAP_0402-0.1UF,25V,10%,X7R,CA':;

SECTION_NUMBER 1
 '@S9S_MB_2U_LIB.S9S_MB_2U(SCH_1):PAGE502_I59@PURE_QUANTA.Q_CAP(CHIPS)':
 C_PATH='@s9s_mb_2u_lib.s9s_mb_2u(sch_1):page502_i59@pure_quanta.q_cap(chips)';

PART_NAME
 C1175 'Q_CAP_0402-0.1UF,25V,10%,X7R,CA':;

SECTION_NUMBER 1
 '@S9S_MB_2U_LIB.S9S_MB_2U(SCH_1):PAGE502_I24@PURE_QUANTA.Q_CAP(CHIPS)':
 C_PATH='@s9s_mb_2u_lib.s9s_mb_2u(sch_1):page502_i24@pure_quanta.q_cap(chips)';

PART_NAME
 C1173 'Q_CAP_0402-0.1UF,25V,10%,X7R,CA':;

SECTION_NUMBER 1
 '@S9S_MB_2U_LIB.S9S_MB_2U(SCH_1):PAGE502_I4@PURE_QUANTA.Q_CAP(CHIPS)':
 C_PATH='@s9s_mb_2u_lib.s9s_mb_2u(sch_1):page502_i4@pure_quanta.q_cap(chips)';

PART_NAME
 C188 'Q_CAP_0402-0.1UF,25V,10%,X7R,CA':;

SECTION_NUMBER 1
 '@S9S_MB_2U_LIB.S9S_MB_2U(SCH_1):PAGE502_I44@PURE_QUANTA.Q_CAP(CHIPS)':
 C_PATH='@s9s_mb_2u_lib.s9s_mb_2u(sch_1):page502_i44@pure_quanta.q_cap(chips)';

PART_NAME
 U59 'SN74LVC2G07DCKR_SMLF-SN74LVC2GA':;

SECTION_NUMBER 1
 '@S9S_MB_2U_LIB.S9S_MB_2U(SCH_1):PAGE507_I46@PURE_QUANTA.SN74LVC2G07DCKR(CHIPS)':
 C_PATH='@s9s_mb_2u_lib.s9s_mb_2u(sch_1):page507_i46@pure_quanta.sn74lvc2g07dckr(c~
hips)';

PART_NAME
 U58 'SN74LVC2G07DCKR_SMLF-SN74LVC2GA':;

SECTION_NUMBER 1
 '@S9S_MB_2U_LIB.S9S_MB_2U(SCH_1):PAGE507_I44@PURE_QUANTA.SN74LVC2G07DCKR(CHIPS)':
 C_PATH='@s9s_mb_2u_lib.s9s_mb_2u(sch_1):page507_i44@pure_quanta.sn74lvc2g07dckr(c~
hips)';

PART_NAME
 U57 'TPS259824ONRGER-TPS259824ONRGEA':;

SECTION_NUMBER 1
 '@S9S_MB_2U_LIB.S9S_MB_2U(SCH_1):PAGE507_I27@PURE_QUANTA.TPS259824ONRGER(CHIPS)':
 C_PATH='@s9s_mb_2u_lib.s9s_mb_2u(sch_1):page507_i27@pure_quanta.tps259824onrger(c~
hips)';

PART_NAME
 U56 'TPS259520DSGR-TPS259520DSGR,SMA':;

SECTION_NUMBER 1
 '@S9S_MB_2U_LIB.S9S_MB_2U(SCH_1):PAGE507_I56@PURE_QUANTA.TPS259520DSGR(CHIPS)':
 C_PATH='@s9s_mb_2u_lib.s9s_mb_2u(sch_1):page507_i56@pure_quanta.tps259520dsgr(chi~
ps)';

PART_NAME
 R1908 'Q_RES_0402LF-10K,1%,1/16W,CHIPA':;

SECTION_NUMBER 1
 '@S9S_MB_2U_LIB.S9S_MB_2U(SCH_1):PAGE507_I81@PURE_QUANTA.Q_RES(CHIPS)':
 C_PATH='@s9s_mb_2u_lib.s9s_mb_2u(sch_1):page507_i81@pure_quanta.q_res(chips)';

PART_NAME
 R1907 'Q_RES_0402LF-10K,1%,1/16W,CHIPA':;

SECTION_NUMBER 1
 '@S9S_MB_2U_LIB.S9S_MB_2U(SCH_1):PAGE507_I80@PURE_QUANTA.Q_RES(CHIPS)':
 C_PATH='@s9s_mb_2u_lib.s9s_mb_2u(sch_1):page507_i80@pure_quanta.q_res(chips)';

PART_NAME
 R1906 'Q_RES_0402LF-10K,1%,1/16W,CHIPA':;

SECTION_NUMBER 1
 '@S9S_MB_2U_LIB.S9S_MB_2U(SCH_1):PAGE507_I83@PURE_QUANTA.Q_RES(CHIPS)':
 C_PATH='@s9s_mb_2u_lib.s9s_mb_2u(sch_1):page507_i83@pure_quanta.q_res(chips)';

PART_NAME
 R1905 'Q_RES_0402LF-10K,1%,1/16W,CHIPA':;

SECTION_NUMBER 1
 '@S9S_MB_2U_LIB.S9S_MB_2U(SCH_1):PAGE507_I79@PURE_QUANTA.Q_RES(CHIPS)':
 C_PATH='@s9s_mb_2u_lib.s9s_mb_2u(sch_1):page507_i79@pure_quanta.q_res(chips)';

PART_NAME
 R1150 'Q_RES_0402LF-10K,1%,1/16W,CHIPA':;

SECTION_NUMBER 1
 '@S9S_MB_2U_LIB.S9S_MB_2U(SCH_1):PAGE507_I32@PURE_QUANTA.Q_RES(CHIPS)':
 C_PATH='@s9s_mb_2u_lib.s9s_mb_2u(sch_1):page507_i32@pure_quanta.q_res(chips)';

PART_NAME
 R1149 'Q_RES_0402LF-10K,1%,1/16W,CHIPA':;

SECTION_NUMBER 1
 '@S9S_MB_2U_LIB.S9S_MB_2U(SCH_1):PAGE507_I35@PURE_QUANTA.Q_RES(CHIPS)':
 C_PATH='@s9s_mb_2u_lib.s9s_mb_2u(sch_1):page507_i35@pure_quanta.q_res(chips)';

PART_NAME
 R1148 'Q_RES_0402LF-0,5%,1/16W,CHIP,CA':;

SECTION_NUMBER 1
 '@S9S_MB_2U_LIB.S9S_MB_2U(SCH_1):PAGE507_I37@PURE_QUANTA.Q_RES(CHIPS)':
 C_PATH='@s9s_mb_2u_lib.s9s_mb_2u(sch_1):page507_i37@pure_quanta.q_res(chips)';

PART_NAME
 R1147 'Q_RES_0402LF-0,5%,1/16W,CHIP,CA':;

SECTION_NUMBER 1
 '@S9S_MB_2U_LIB.S9S_MB_2U(SCH_1):PAGE507_I36@PURE_QUANTA.Q_RES(CHIPS)':
 C_PATH='@s9s_mb_2u_lib.s9s_mb_2u(sch_1):page507_i36@pure_quanta.q_res(chips)';

PART_NAME
 R1146 'Q_RES_0402LF-1K,1%,1/16W,CHIP,A':;

SECTION_NUMBER 1
 '@S9S_MB_2U_LIB.S9S_MB_2U(SCH_1):PAGE507_I8@PURE_QUANTA.Q_RES(CHIPS)':
 C_PATH='@s9s_mb_2u_lib.s9s_mb_2u(sch_1):page507_i8@pure_quanta.q_res(chips)';

PART_NAME
 R1144 'Q_RES_0402LF-562,1%,1/16W,CHIPA':;

SECTION_NUMBER 1
 '@S9S_MB_2U_LIB.S9S_MB_2U(SCH_1):PAGE507_I15@PURE_QUANTA.Q_RES(CHIPS)':
 C_PATH='@s9s_mb_2u_lib.s9s_mb_2u(sch_1):page507_i15@pure_quanta.q_res(chips)';

PART_NAME
 R1143 'Q_RES_0402LF-10K,1%,1/16W,CHIPA':;

SECTION_NUMBER 1
 '@S9S_MB_2U_LIB.S9S_MB_2U(SCH_1):PAGE507_I4@PURE_QUANTA.Q_RES(CHIPS)':
 C_PATH='@s9s_mb_2u_lib.s9s_mb_2u(sch_1):page507_i4@pure_quanta.q_res(chips)';

PART_NAME
 R1142 'Q_RES_0402LF-1K,5%,1/16W,CHIP,A':;

SECTION_NUMBER 1
 '@S9S_MB_2U_LIB.S9S_MB_2U(SCH_1):PAGE507_I21@PURE_QUANTA.Q_RES(CHIPS)':
 C_PATH='@s9s_mb_2u_lib.s9s_mb_2u(sch_1):page507_i21@pure_quanta.q_res(chips)';

PART_NAME
 R1137 'Q_RES_0402LF-150,1%,1/16W,CHIPA':;

SECTION_NUMBER 1
 '@S9S_MB_2U_LIB.S9S_MB_2U(SCH_1):PAGE507_I66@PURE_QUANTA.Q_RES(CHIPS)':
 C_PATH='@s9s_mb_2u_lib.s9s_mb_2u(sch_1):page507_i66@pure_quanta.q_res(chips)';

PART_NAME
 R1136 'Q_RES_0402LF-0,5%,1/16W,CHIP,CA':;

SECTION_NUMBER 1
 '@S9S_MB_2U_LIB.S9S_MB_2U(SCH_1):PAGE507_I67@PURE_QUANTA.Q_RES(CHIPS)':
 C_PATH='@s9s_mb_2u_lib.s9s_mb_2u(sch_1):page507_i67@pure_quanta.q_res(chips)';

PART_NAME
 R1135 'Q_RES_0402LF-0,5%,1/16W,EMPTY,A':;

SECTION_NUMBER 1
 '@S9S_MB_2U_LIB.S9S_MB_2U(SCH_1):PAGE507_I70@PURE_QUANTA.Q_RES(CHIPS)':
 C_PATH='@s9s_mb_2u_lib.s9s_mb_2u(sch_1):page507_i70@pure_quanta.q_res(chips)';

PART_NAME
 R1134 'Q_RES_0402LF-0,5%,1/16W,CHIP,CA':;

SECTION_NUMBER 1
 '@S9S_MB_2U_LIB.S9S_MB_2U(SCH_1):PAGE507_I71@PURE_QUANTA.Q_RES(CHIPS)':
 C_PATH='@s9s_mb_2u_lib.s9s_mb_2u(sch_1):page507_i71@pure_quanta.q_res(chips)';

PART_NAME
 D4 'SCHOTTKY_AC-SX34F,SMLF,IC,BC00A':;

SECTION_NUMBER 1
 '@S9S_MB_2U_LIB.S9S_MB_2U(SCH_1):PAGE507_I23@PURE_QUANTA.SCHOTTKY_AC(CHIPS)':
 C_PATH='@s9s_mb_2u_lib.s9s_mb_2u(sch_1):page507_i23@pure_quanta.schottky_ac(chips~
)';

PART_NAME
 C593 'Q_CAP_0402-0.1UF,25V,10%,X7R,CA':;

SECTION_NUMBER 1
 '@S9S_MB_2U_LIB.S9S_MB_2U(SCH_1):PAGE507_I43@PURE_QUANTA.Q_CAP(CHIPS)':
 C_PATH='@s9s_mb_2u_lib.s9s_mb_2u(sch_1):page507_i43@pure_quanta.q_cap(chips)';

PART_NAME
 C592 'Q_CAP_0402-0.1UF,25V,10%,X7R,CA':;

SECTION_NUMBER 1
 '@S9S_MB_2U_LIB.S9S_MB_2U(SCH_1):PAGE507_I38@PURE_QUANTA.Q_CAP(CHIPS)':
 C_PATH='@s9s_mb_2u_lib.s9s_mb_2u(sch_1):page507_i38@pure_quanta.q_cap(chips)';

PART_NAME
 C591 'Q_CAP_0402-3300PF,50V,10%,X7R,A':;

SECTION_NUMBER 1
 '@S9S_MB_2U_LIB.S9S_MB_2U(SCH_1):PAGE507_I16@PURE_QUANTA.Q_CAP(CHIPS)':
 C_PATH='@s9s_mb_2u_lib.s9s_mb_2u(sch_1):page507_i16@pure_quanta.q_cap(chips)';

PART_NAME
 C589 'Q_CAP_C0402-1UF,16V,10%,X6S,CHA':;

SECTION_NUMBER 1
 '@S9S_MB_2U_LIB.S9S_MB_2U(SCH_1):PAGE507_I12@PURE_QUANTA.Q_CAP(CHIPS)':
 C_PATH='@s9s_mb_2u_lib.s9s_mb_2u(sch_1):page507_i12@pure_quanta.q_cap(chips)';

PART_NAME
 C588 'Q_CAP_C0402-3900PF,50V,10%,X7RA':;

SECTION_NUMBER 1
 '@S9S_MB_2U_LIB.S9S_MB_2U(SCH_1):PAGE507_I18@PURE_QUANTA.Q_CAP(CHIPS)':
 C_PATH='@s9s_mb_2u_lib.s9s_mb_2u(sch_1):page507_i18@pure_quanta.q_cap(chips)';

PART_NAME
 C587 'Q_CAP_C0805-10UF,25V,10%,X6S,CA':;

SECTION_NUMBER 1
 '@S9S_MB_2U_LIB.S9S_MB_2U(SCH_1):PAGE507_I24@PURE_QUANTA.Q_CAP(CHIPS)':
 C_PATH='@s9s_mb_2u_lib.s9s_mb_2u(sch_1):page507_i24@pure_quanta.q_cap(chips)';

PART_NAME
 C586 'Q_CAP_0402-0.1UF,25V,10%,X7R,CA':;

SECTION_NUMBER 1
 '@S9S_MB_2U_LIB.S9S_MB_2U(SCH_1):PAGE507_I61@PURE_QUANTA.Q_CAP(CHIPS)':
 C_PATH='@s9s_mb_2u_lib.s9s_mb_2u(sch_1):page507_i61@pure_quanta.q_cap(chips)';

PART_NAME
 C583 'Q_CAP_C0402-1UF,16V,10%,X6S,CHA':;

SECTION_NUMBER 1
 '@S9S_MB_2U_LIB.S9S_MB_2U(SCH_1):PAGE507_I62@PURE_QUANTA.Q_CAP(CHIPS)':
 C_PATH='@s9s_mb_2u_lib.s9s_mb_2u(sch_1):page507_i62@pure_quanta.q_cap(chips)';

PART_NAME
 C582 'Q_CAP_C0402-100NF,50V,10%,X7R,A':;

SECTION_NUMBER 1
 '@S9S_MB_2U_LIB.S9S_MB_2U(SCH_1):PAGE507_I57@PURE_QUANTA.Q_CAP(CHIPS)':
 C_PATH='@s9s_mb_2u_lib.s9s_mb_2u(sch_1):page507_i57@pure_quanta.q_cap(chips)';

PART_NAME
 C331 'Q_CAP_C0805-22UF,16V,20%,X6S,CA':;

SECTION_NUMBER 1
 '@S9S_MB_2U_LIB.S9S_MB_2U(SCH_1):PAGE507_I75@PURE_QUANTA.Q_CAP(CHIPS)':
 C_PATH='@s9s_mb_2u_lib.s9s_mb_2u(sch_1):page507_i75@pure_quanta.q_cap(chips)';

PART_NAME
 C319 'Q_CAP_C0805-22UF,16V,20%,X6S,CA':;

SECTION_NUMBER 1
 '@S9S_MB_2U_LIB.S9S_MB_2U(SCH_1):PAGE507_I77@PURE_QUANTA.Q_CAP(CHIPS)':
 C_PATH='@s9s_mb_2u_lib.s9s_mb_2u(sch_1):page507_i77@pure_quanta.q_cap(chips)';

PART_NAME
 C189 'Q_CAP_C0805-22UF,16V,20%,X6S,CA':;

SECTION_NUMBER 1
 '@S9S_MB_2U_LIB.S9S_MB_2U(SCH_1):PAGE507_I76@PURE_QUANTA.Q_CAP(CHIPS)':
 C_PATH='@s9s_mb_2u_lib.s9s_mb_2u(sch_1):page507_i76@pure_quanta.q_cap(chips)';

PART_NAME
 C187 'Q_CAP_C0805-22UF,16V,20%,X6S,CA':;

SECTION_NUMBER 1
 '@S9S_MB_2U_LIB.S9S_MB_2U(SCH_1):PAGE507_I74@PURE_QUANTA.Q_CAP(CHIPS)':
 C_PATH='@s9s_mb_2u_lib.s9s_mb_2u(sch_1):page507_i74@pure_quanta.q_cap(chips)';

PART_NAME
 U43 'SN74LVC2G07DCKR_SMLF-SN74LVC2GA':;

SECTION_NUMBER 1
 '@S9S_MB_2U_LIB.S9S_MB_2U(SCH_1):PAGE509_I58@PURE_QUANTA.SN74LVC2G07DCKR(CHIPS)':
 C_PATH='@s9s_mb_2u_lib.s9s_mb_2u(sch_1):page509_i58@pure_quanta.sn74lvc2g07dckr(c~
hips)';

PART_NAME
 U42 'SN74LVC2G07DCKR_SMLF-SN74LVC2GA':;

SECTION_NUMBER 1
 '@S9S_MB_2U_LIB.S9S_MB_2U(SCH_1):PAGE509_I56@PURE_QUANTA.SN74LVC2G07DCKR(CHIPS)':
 C_PATH='@s9s_mb_2u_lib.s9s_mb_2u(sch_1):page509_i56@pure_quanta.sn74lvc2g07dckr(c~
hips)';

PART_NAME
 U41 'TPS259824ONRGER-TPS259824ONRGEA':;

SECTION_NUMBER 1
 '@S9S_MB_2U_LIB.S9S_MB_2U(SCH_1):PAGE509_I30@PURE_QUANTA.TPS259824ONRGER(CHIPS)':
 C_PATH='@s9s_mb_2u_lib.s9s_mb_2u(sch_1):page509_i30@pure_quanta.tps259824onrger(c~
hips)';

PART_NAME
 U40 'TPS259520DSGR-TPS259520DSGR,SMA':;

SECTION_NUMBER 1
 '@S9S_MB_2U_LIB.S9S_MB_2U(SCH_1):PAGE509_I27@PURE_QUANTA.TPS259520DSGR(CHIPS)':
 C_PATH='@s9s_mb_2u_lib.s9s_mb_2u(sch_1):page509_i27@pure_quanta.tps259520dsgr(chi~
ps)';

PART_NAME
 U39 'SN74LVC2G07DCKR_SMLF-SN74LVC2GA':;

SECTION_NUMBER 1
 '@S9S_MB_2U_LIB.S9S_MB_2U(SCH_1):PAGE509_I88@PURE_QUANTA.SN74LVC2G07DCKR(CHIPS)':
 C_PATH='@s9s_mb_2u_lib.s9s_mb_2u(sch_1):page509_i88@pure_quanta.sn74lvc2g07dckr(c~
hips)';

PART_NAME
 U37 'SN74LVC2G07DCKR_SMLF-SN74LVC2GA':;

SECTION_NUMBER 1
 '@S9S_MB_2U_LIB.S9S_MB_2U(SCH_1):PAGE509_I83@PURE_QUANTA.SN74LVC2G07DCKR(CHIPS)':
 C_PATH='@s9s_mb_2u_lib.s9s_mb_2u(sch_1):page509_i83@pure_quanta.sn74lvc2g07dckr(c~
hips)';

PART_NAME
 R1916 'Q_RES_0402LF-100K,1%,1/16W,CHIA':;

SECTION_NUMBER 1
 '@S9S_MB_2U_LIB.S9S_MB_2U(SCH_1):PAGE509_I117@PURE_QUANTA.Q_RES(CHIPS)':
 C_PATH='@s9s_mb_2u_lib.s9s_mb_2u(sch_1):page509_i117@pure_quanta.q_res(chips)';

PART_NAME
 R1915 'Q_RES_0402LF-100K,1%,1/16W,CHIA':;

SECTION_NUMBER 1
 '@S9S_MB_2U_LIB.S9S_MB_2U(SCH_1):PAGE509_I110@PURE_QUANTA.Q_RES(CHIPS)':
 C_PATH='@s9s_mb_2u_lib.s9s_mb_2u(sch_1):page509_i110@pure_quanta.q_res(chips)';

PART_NAME
 R1914 'Q_RES_0402LF-100K,1%,1/16W,CHIA':;

SECTION_NUMBER 1
 '@S9S_MB_2U_LIB.S9S_MB_2U(SCH_1):PAGE509_I111@PURE_QUANTA.Q_RES(CHIPS)':
 C_PATH='@s9s_mb_2u_lib.s9s_mb_2u(sch_1):page509_i111@pure_quanta.q_res(chips)';

PART_NAME
 R1913 'Q_RES_0402LF-100K,1%,1/16W,CHIA':;

SECTION_NUMBER 1
 '@S9S_MB_2U_LIB.S9S_MB_2U(SCH_1):PAGE509_I112@PURE_QUANTA.Q_RES(CHIPS)':
 C_PATH='@s9s_mb_2u_lib.s9s_mb_2u(sch_1):page509_i112@pure_quanta.q_res(chips)';

PART_NAME
 R1912 'Q_RES_0402LF-100K,1%,1/16W,CHIA':;

SECTION_NUMBER 1
 '@S9S_MB_2U_LIB.S9S_MB_2U(SCH_1):PAGE509_I102@PURE_QUANTA.Q_RES(CHIPS)':
 C_PATH='@s9s_mb_2u_lib.s9s_mb_2u(sch_1):page509_i102@pure_quanta.q_res(chips)';

PART_NAME
 R1911 'Q_RES_0402LF-100K,1%,1/16W,CHIA':;

SECTION_NUMBER 1
 '@S9S_MB_2U_LIB.S9S_MB_2U(SCH_1):PAGE509_I101@PURE_QUANTA.Q_RES(CHIPS)':
 C_PATH='@s9s_mb_2u_lib.s9s_mb_2u(sch_1):page509_i101@pure_quanta.q_res(chips)';

PART_NAME
 R1910 'Q_RES_0402LF-100K,1%,1/16W,CHIA':;

SECTION_NUMBER 1
 '@S9S_MB_2U_LIB.S9S_MB_2U(SCH_1):PAGE509_I100@PURE_QUANTA.Q_RES(CHIPS)':
 C_PATH='@s9s_mb_2u_lib.s9s_mb_2u(sch_1):page509_i100@pure_quanta.q_res(chips)';

PART_NAME
 R1909 'Q_RES_0402LF-100K,1%,1/16W,CHIA':;

SECTION_NUMBER 1
 '@S9S_MB_2U_LIB.S9S_MB_2U(SCH_1):PAGE509_I98@PURE_QUANTA.Q_RES(CHIPS)':
 C_PATH='@s9s_mb_2u_lib.s9s_mb_2u(sch_1):page509_i98@pure_quanta.q_res(chips)';

PART_NAME
 R1111 'Q_RES_0402LF-10K,1%,1/16W,CHIPA':;

SECTION_NUMBER 1
 '@S9S_MB_2U_LIB.S9S_MB_2U(SCH_1):PAGE509_I43@PURE_QUANTA.Q_RES(CHIPS)':
 C_PATH='@s9s_mb_2u_lib.s9s_mb_2u(sch_1):page509_i43@pure_quanta.q_res(chips)';

PART_NAME
 R1110 'Q_RES_0402LF-10K,1%,1/16W,CHIPA':;

SECTION_NUMBER 1
 '@S9S_MB_2U_LIB.S9S_MB_2U(SCH_1):PAGE509_I45@PURE_QUANTA.Q_RES(CHIPS)':
 C_PATH='@s9s_mb_2u_lib.s9s_mb_2u(sch_1):page509_i45@pure_quanta.q_res(chips)';

PART_NAME
 R1109 'Q_RES_0402LF-0,5%,1/16W,CHIP,CA':;

SECTION_NUMBER 1
 '@S9S_MB_2U_LIB.S9S_MB_2U(SCH_1):PAGE509_I48@PURE_QUANTA.Q_RES(CHIPS)':
 C_PATH='@s9s_mb_2u_lib.s9s_mb_2u(sch_1):page509_i48@pure_quanta.q_res(chips)';

PART_NAME
 R1108 'Q_RES_0402LF-0,5%,1/16W,CHIP,CA':;

SECTION_NUMBER 1
 '@S9S_MB_2U_LIB.S9S_MB_2U(SCH_1):PAGE509_I49@PURE_QUANTA.Q_RES(CHIPS)':
 C_PATH='@s9s_mb_2u_lib.s9s_mb_2u(sch_1):page509_i49@pure_quanta.q_res(chips)';

PART_NAME
 R1107 'Q_RES_0402LF-1K,1%,1/16W,CHIP,A':;

SECTION_NUMBER 1
 '@S9S_MB_2U_LIB.S9S_MB_2U(SCH_1):PAGE509_I3@PURE_QUANTA.Q_RES(CHIPS)':
 C_PATH='@s9s_mb_2u_lib.s9s_mb_2u(sch_1):page509_i3@pure_quanta.q_res(chips)';

PART_NAME
 R1105 'Q_RES_0402LF-562,1%,1/16W,CHIPA':;

SECTION_NUMBER 1
 '@S9S_MB_2U_LIB.S9S_MB_2U(SCH_1):PAGE509_I18@PURE_QUANTA.Q_RES(CHIPS)':
 C_PATH='@s9s_mb_2u_lib.s9s_mb_2u(sch_1):page509_i18@pure_quanta.q_res(chips)';

PART_NAME
 R1104 'Q_RES_0402LF-10K,1%,1/16W,CHIPA':;

SECTION_NUMBER 1
 '@S9S_MB_2U_LIB.S9S_MB_2U(SCH_1):PAGE509_I12@PURE_QUANTA.Q_RES(CHIPS)':
 C_PATH='@s9s_mb_2u_lib.s9s_mb_2u(sch_1):page509_i12@pure_quanta.q_res(chips)';

PART_NAME
 R1103 'Q_RES_0402LF-1K,5%,1/16W,CHIP,A':;

SECTION_NUMBER 1
 '@S9S_MB_2U_LIB.S9S_MB_2U(SCH_1):PAGE509_I13@PURE_QUANTA.Q_RES(CHIPS)':
 C_PATH='@s9s_mb_2u_lib.s9s_mb_2u(sch_1):page509_i13@pure_quanta.q_res(chips)';

PART_NAME
 R1098 'Q_RES_0402LF-150,1%,1/16W,CHIPA':;

SECTION_NUMBER 1
 '@S9S_MB_2U_LIB.S9S_MB_2U(SCH_1):PAGE509_I34@PURE_QUANTA.Q_RES(CHIPS)':
 C_PATH='@s9s_mb_2u_lib.s9s_mb_2u(sch_1):page509_i34@pure_quanta.q_res(chips)';

PART_NAME
 R1097 'Q_RES_0402LF-0,5%,1/16W,CHIP,CA':;

SECTION_NUMBER 1
 '@S9S_MB_2U_LIB.S9S_MB_2U(SCH_1):PAGE509_I36@PURE_QUANTA.Q_RES(CHIPS)':
 C_PATH='@s9s_mb_2u_lib.s9s_mb_2u(sch_1):page509_i36@pure_quanta.q_res(chips)';

PART_NAME
 R1096 'Q_RES_0402LF-0,5%,1/16W,EMPTY,A':;

SECTION_NUMBER 1
 '@S9S_MB_2U_LIB.S9S_MB_2U(SCH_1):PAGE509_I37@PURE_QUANTA.Q_RES(CHIPS)':
 C_PATH='@s9s_mb_2u_lib.s9s_mb_2u(sch_1):page509_i37@pure_quanta.q_res(chips)';

PART_NAME
 R1095 'Q_RES_0402LF-0,5%,1/16W,CHIP,CA':;

SECTION_NUMBER 1
 '@S9S_MB_2U_LIB.S9S_MB_2U(SCH_1):PAGE509_I80@PURE_QUANTA.Q_RES(CHIPS)':
 C_PATH='@s9s_mb_2u_lib.s9s_mb_2u(sch_1):page509_i80@pure_quanta.q_res(chips)';

PART_NAME
 D2 'SCHOTTKY_AC-SX34F,SMLF,IC,BC00A':;

SECTION_NUMBER 1
 '@S9S_MB_2U_LIB.S9S_MB_2U(SCH_1):PAGE509_I16@PURE_QUANTA.SCHOTTKY_AC(CHIPS)':
 C_PATH='@s9s_mb_2u_lib.s9s_mb_2u(sch_1):page509_i16@pure_quanta.schottky_ac(chips~
)';

PART_NAME
 C573 'Q_CAP_0402-0.1UF,25V,10%,X7R,CA':;

SECTION_NUMBER 1
 '@S9S_MB_2U_LIB.S9S_MB_2U(SCH_1):PAGE509_I55@PURE_QUANTA.Q_CAP(CHIPS)':
 C_PATH='@s9s_mb_2u_lib.s9s_mb_2u(sch_1):page509_i55@pure_quanta.q_cap(chips)';

PART_NAME
 C572 'Q_CAP_0402-0.1UF,25V,10%,X7R,CA':;

SECTION_NUMBER 1
 '@S9S_MB_2U_LIB.S9S_MB_2U(SCH_1):PAGE509_I51@PURE_QUANTA.Q_CAP(CHIPS)':
 C_PATH='@s9s_mb_2u_lib.s9s_mb_2u(sch_1):page509_i51@pure_quanta.q_cap(chips)';

PART_NAME
 C571 'Q_CAP_0402-3300PF,50V,10%,X7R,A':;

SECTION_NUMBER 1
 '@S9S_MB_2U_LIB.S9S_MB_2U(SCH_1):PAGE509_I21@PURE_QUANTA.Q_CAP(CHIPS)':
 C_PATH='@s9s_mb_2u_lib.s9s_mb_2u(sch_1):page509_i21@pure_quanta.q_cap(chips)';

PART_NAME
 C469 'Q_CAP_C0805-22UF,16V,20%,X6S,CA':;

SECTION_NUMBER 1
 '@S9S_MB_2U_LIB.S9S_MB_2U(SCH_1):PAGE509_I96@PURE_QUANTA.Q_CAP(CHIPS)':
 C_PATH='@s9s_mb_2u_lib.s9s_mb_2u(sch_1):page509_i96@pure_quanta.q_cap(chips)';

PART_NAME
 C378 'Q_CAP_C0805-22UF,16V,20%,X6S,CA':;

SECTION_NUMBER 1
 '@S9S_MB_2U_LIB.S9S_MB_2U(SCH_1):PAGE509_I95@PURE_QUANTA.Q_CAP(CHIPS)':
 C_PATH='@s9s_mb_2u_lib.s9s_mb_2u(sch_1):page509_i95@pure_quanta.q_cap(chips)';

PART_NAME
 C375 'Q_CAP_C0805-22UF,16V,20%,X6S,CA':;

SECTION_NUMBER 1
 '@S9S_MB_2U_LIB.S9S_MB_2U(SCH_1):PAGE509_I94@PURE_QUANTA.Q_CAP(CHIPS)':
 C_PATH='@s9s_mb_2u_lib.s9s_mb_2u(sch_1):page509_i94@pure_quanta.q_cap(chips)';

PART_NAME
 C334 'Q_CAP_C0805-22UF,16V,20%,X6S,CA':;

SECTION_NUMBER 1
 '@S9S_MB_2U_LIB.S9S_MB_2U(SCH_1):PAGE509_I97@PURE_QUANTA.Q_CAP(CHIPS)':
 C_PATH='@s9s_mb_2u_lib.s9s_mb_2u(sch_1):page509_i97@pure_quanta.q_cap(chips)';

PART_NAME
 C186 'Q_CAP_C0402-1UF,16V,10%,X6S,CHA':;

SECTION_NUMBER 1
 '@S9S_MB_2U_LIB.S9S_MB_2U(SCH_1):PAGE509_I15@PURE_QUANTA.Q_CAP(CHIPS)':
 C_PATH='@s9s_mb_2u_lib.s9s_mb_2u(sch_1):page509_i15@pure_quanta.q_cap(chips)';

PART_NAME
 C185 'Q_CAP_C0402-3900PF,50V,10%,X7RA':;

SECTION_NUMBER 1
 '@S9S_MB_2U_LIB.S9S_MB_2U(SCH_1):PAGE509_I22@PURE_QUANTA.Q_CAP(CHIPS)':
 C_PATH='@s9s_mb_2u_lib.s9s_mb_2u(sch_1):page509_i22@pure_quanta.q_cap(chips)';

PART_NAME
 C184 'Q_CAP_C0805-10UF,25V,10%,X6S,CA':;

SECTION_NUMBER 1
 '@S9S_MB_2U_LIB.S9S_MB_2U(SCH_1):PAGE509_I24@PURE_QUANTA.Q_CAP(CHIPS)':
 C_PATH='@s9s_mb_2u_lib.s9s_mb_2u(sch_1):page509_i24@pure_quanta.q_cap(chips)';

PART_NAME
 C183 'Q_CAP_0402-0.1UF,25V,10%,X7R,CA':;

SECTION_NUMBER 1
 '@S9S_MB_2U_LIB.S9S_MB_2U(SCH_1):PAGE509_I29@PURE_QUANTA.Q_CAP(CHIPS)':
 C_PATH='@s9s_mb_2u_lib.s9s_mb_2u(sch_1):page509_i29@pure_quanta.q_cap(chips)';

PART_NAME
 C182 'Q_CAP_0402-0.1UF,25V,10%,X7R,CA':;

SECTION_NUMBER 1
 '@S9S_MB_2U_LIB.S9S_MB_2U(SCH_1):PAGE509_I71@PURE_QUANTA.Q_CAP(CHIPS)':
 C_PATH='@s9s_mb_2u_lib.s9s_mb_2u(sch_1):page509_i71@pure_quanta.q_cap(chips)';

PART_NAME
 C181 'Q_CAP_0402-0.1UF,25V,10%,X7R,CA':;

SECTION_NUMBER 1
 '@S9S_MB_2U_LIB.S9S_MB_2U(SCH_1):PAGE509_I70@PURE_QUANTA.Q_CAP(CHIPS)':
 C_PATH='@s9s_mb_2u_lib.s9s_mb_2u(sch_1):page509_i70@pure_quanta.q_cap(chips)';

PART_NAME
 C180 'Q_CAP_C0402-1UF,16V,10%,X6S,CHA':;

SECTION_NUMBER 1
 '@S9S_MB_2U_LIB.S9S_MB_2U(SCH_1):PAGE509_I77@PURE_QUANTA.Q_CAP(CHIPS)':
 C_PATH='@s9s_mb_2u_lib.s9s_mb_2u(sch_1):page509_i77@pure_quanta.q_cap(chips)';

PART_NAME
 C179 'Q_CAP_C0402-100NF,50V,10%,X7R,A':;

SECTION_NUMBER 1
 '@S9S_MB_2U_LIB.S9S_MB_2U(SCH_1):PAGE509_I73@PURE_QUANTA.Q_CAP(CHIPS)':
 C_PATH='@s9s_mb_2u_lib.s9s_mb_2u(sch_1):page509_i73@pure_quanta.q_cap(chips)';

PART_NAME
 U35 'SN74LVC1G126DCKR-SN74LVC1G126DA':;

SECTION_NUMBER 1
 '@S9S_MB_2U_LIB.S9S_MB_2U(SCH_1):PAGE572_I10@PURE_QUANTA.SN74LVC1G126DCKR(CHIPS)':
 C_PATH='@s9s_mb_2u_lib.s9s_mb_2u(sch_1):page572_i10@pure_quanta.sn74lvc1g126dckr(~
chips)';

PART_NAME
 U34 'TPS3700DSER-TPS3700DSER,SMLF,IA':;

SECTION_NUMBER 1
 '@S9S_MB_2U_LIB.S9S_MB_2U(SCH_1):PAGE572_I57@PURE_QUANTA.TPS3700DSER(CHIPS)':
 C_PATH='@s9s_mb_2u_lib.s9s_mb_2u(sch_1):page572_i57@pure_quanta.tps3700dser(chips~
)';

PART_NAME
 U33 'TPS3700DSER-TPS3700DSER,SMLF,IA':;

SECTION_NUMBER 1
 '@S9S_MB_2U_LIB.S9S_MB_2U(SCH_1):PAGE572_I61@PURE_QUANTA.TPS3700DSER(CHIPS)':
 C_PATH='@s9s_mb_2u_lib.s9s_mb_2u(sch_1):page572_i61@pure_quanta.tps3700dser(chips~
)';

PART_NAME
 U32 'TPS3700DSER-TPS3700DSER,SMLF,IA':;

SECTION_NUMBER 1
 '@S9S_MB_2U_LIB.S9S_MB_2U(SCH_1):PAGE572_I31@PURE_QUANTA.TPS3700DSER(CHIPS)':
 C_PATH='@s9s_mb_2u_lib.s9s_mb_2u(sch_1):page572_i31@pure_quanta.tps3700dser(chips~
)';

PART_NAME
 R1849 'Q_RES_0402LF-4.75K,1%,1/16W,EMA':;

SECTION_NUMBER 1
 '@S9S_MB_2U_LIB.S9S_MB_2U(SCH_1):PAGE572_I83@PURE_QUANTA.Q_RES(CHIPS)':
 C_PATH='@s9s_mb_2u_lib.s9s_mb_2u(sch_1):page572_i83@pure_quanta.q_res(chips)';

PART_NAME
 R1848 'Q_RES_0402LF-4.75K,1%,1/16W,CHA':;

SECTION_NUMBER 1
 '@S9S_MB_2U_LIB.S9S_MB_2U(SCH_1):PAGE572_I81@PURE_QUANTA.Q_RES(CHIPS)':
 C_PATH='@s9s_mb_2u_lib.s9s_mb_2u(sch_1):page572_i81@pure_quanta.q_res(chips)';

PART_NAME
 R1847 'Q_RES_0402LF-4.75K,1%,1/16W,EMA':;

SECTION_NUMBER 1
 '@S9S_MB_2U_LIB.S9S_MB_2U(SCH_1):PAGE572_I85@PURE_QUANTA.Q_RES(CHIPS)':
 C_PATH='@s9s_mb_2u_lib.s9s_mb_2u(sch_1):page572_i85@pure_quanta.q_res(chips)';

PART_NAME
 R1846 'Q_RES_0402LF-4.75K,1%,1/16W,EMA':;

SECTION_NUMBER 1
 '@S9S_MB_2U_LIB.S9S_MB_2U(SCH_1):PAGE572_I87@PURE_QUANTA.Q_RES(CHIPS)':
 C_PATH='@s9s_mb_2u_lib.s9s_mb_2u(sch_1):page572_i87@pure_quanta.q_res(chips)';

PART_NAME
 R1424 'Q_RES_0402LF-10K,1%,1/16W,EMPTA':;

SECTION_NUMBER 1
 '@S9S_MB_2U_LIB.S9S_MB_2U(SCH_1):PAGE572_I48@PURE_QUANTA.Q_RES(CHIPS)':
 C_PATH='@s9s_mb_2u_lib.s9s_mb_2u(sch_1):page572_i48@pure_quanta.q_res(chips)';

PART_NAME
 R1050 'Q_RES_0402LF-10K,1%,1/16W,CHIPA':;

SECTION_NUMBER 1
 '@S9S_MB_2U_LIB.S9S_MB_2U(SCH_1):PAGE572_I6@PURE_QUANTA.Q_RES(CHIPS)':
 C_PATH='@s9s_mb_2u_lib.s9s_mb_2u(sch_1):page572_i6@pure_quanta.q_res(chips)';

PART_NAME
 R1049 'Q_RES_0402LF-2.7K,1%,1/16W,CHIA':;

SECTION_NUMBER 1
 '@S9S_MB_2U_LIB.S9S_MB_2U(SCH_1):PAGE572_I13@PURE_QUANTA.Q_RES(CHIPS)':
 C_PATH='@s9s_mb_2u_lib.s9s_mb_2u(sch_1):page572_i13@pure_quanta.q_res(chips)';

PART_NAME
 R1048 'Q_RES_0402LF-0,5%,1/16W,EMPTY,A':;

SECTION_NUMBER 1
 '@S9S_MB_2U_LIB.S9S_MB_2U(SCH_1):PAGE572_I51@PURE_QUANTA.Q_RES(CHIPS)':
 C_PATH='@s9s_mb_2u_lib.s9s_mb_2u(sch_1):page572_i51@pure_quanta.q_res(chips)';

PART_NAME
 R1047 'Q_RES_0402LF-0,5%,1/16W,CHIP,CA':;

SECTION_NUMBER 1
 '@S9S_MB_2U_LIB.S9S_MB_2U(SCH_1):PAGE572_I4@PURE_QUANTA.Q_RES(CHIPS)':
 C_PATH='@s9s_mb_2u_lib.s9s_mb_2u(sch_1):page572_i4@pure_quanta.q_res(chips)';

PART_NAME
 R1046 'Q_RES_0402LF-2.7K,1%,1/16W,CHIA':;

SECTION_NUMBER 1
 '@S9S_MB_2U_LIB.S9S_MB_2U(SCH_1):PAGE572_I53@PURE_QUANTA.Q_RES(CHIPS)':
 C_PATH='@s9s_mb_2u_lib.s9s_mb_2u(sch_1):page572_i53@pure_quanta.q_res(chips)';

PART_NAME
 R1045 'Q_RES_0402LF-4.7K,5%,1/16W,CHIA':;

SECTION_NUMBER 1
 '@S9S_MB_2U_LIB.S9S_MB_2U(SCH_1):PAGE572_I20@PURE_QUANTA.Q_RES(CHIPS)':
 C_PATH='@s9s_mb_2u_lib.s9s_mb_2u(sch_1):page572_i20@pure_quanta.q_res(chips)';

PART_NAME
 R1044 'Q_RES_0402LF-10K,1%,1/16W,CHIPA':;

SECTION_NUMBER 1
 '@S9S_MB_2U_LIB.S9S_MB_2U(SCH_1):PAGE572_I27@PURE_QUANTA.Q_RES(CHIPS)':
 C_PATH='@s9s_mb_2u_lib.s9s_mb_2u(sch_1):page572_i27@pure_quanta.q_res(chips)';

PART_NAME
 R1043 'Q_RES_0402LF-0,5%,1/16W,EMPTY,A':;

SECTION_NUMBER 1
 '@S9S_MB_2U_LIB.S9S_MB_2U(SCH_1):PAGE572_I24@PURE_QUANTA.Q_RES(CHIPS)':
 C_PATH='@s9s_mb_2u_lib.s9s_mb_2u(sch_1):page572_i24@pure_quanta.q_res(chips)';

PART_NAME
 R1042 'Q_RES_0402LF-10K,1%,1/16W,CHIPA':;

SECTION_NUMBER 1
 '@S9S_MB_2U_LIB.S9S_MB_2U(SCH_1):PAGE572_I17@PURE_QUANTA.Q_RES(CHIPS)':
 C_PATH='@s9s_mb_2u_lib.s9s_mb_2u(sch_1):page572_i17@pure_quanta.q_res(chips)';

PART_NAME
 R1041 'Q_RES_0402LF-10K,1%,1/16W,CHIPA':;

SECTION_NUMBER 1
 '@S9S_MB_2U_LIB.S9S_MB_2U(SCH_1):PAGE572_I29@PURE_QUANTA.Q_RES(CHIPS)':
 C_PATH='@s9s_mb_2u_lib.s9s_mb_2u(sch_1):page572_i29@pure_quanta.q_res(chips)';

PART_NAME
 R1040 'Q_RES_0402LF-10K,1%,1/16W,CHIPA':;

SECTION_NUMBER 1
 '@S9S_MB_2U_LIB.S9S_MB_2U(SCH_1):PAGE572_I18@PURE_QUANTA.Q_RES(CHIPS)':
 C_PATH='@s9s_mb_2u_lib.s9s_mb_2u(sch_1):page572_i18@pure_quanta.q_res(chips)';

PART_NAME
 R1039 'Q_RES_0402LF-10K,1%,1/16W,EMPTA':;

SECTION_NUMBER 1
 '@S9S_MB_2U_LIB.S9S_MB_2U(SCH_1):PAGE572_I59@PURE_QUANTA.Q_RES(CHIPS)':
 C_PATH='@s9s_mb_2u_lib.s9s_mb_2u(sch_1):page572_i59@pure_quanta.q_res(chips)';

PART_NAME
 R1038 'Q_RES_0402LF-0,5%,1/16W,CHIP,CA':;

SECTION_NUMBER 1
 '@S9S_MB_2U_LIB.S9S_MB_2U(SCH_1):PAGE572_I73@PURE_QUANTA.Q_RES(CHIPS)':
 C_PATH='@s9s_mb_2u_lib.s9s_mb_2u(sch_1):page572_i73@pure_quanta.q_res(chips)';

PART_NAME
 R1037 'Q_RES_0402LF-4.99K,1%,1/16W,CHA':;

SECTION_NUMBER 1
 '@S9S_MB_2U_LIB.S9S_MB_2U(SCH_1):PAGE572_I72@PURE_QUANTA.Q_RES(CHIPS)':
 C_PATH='@s9s_mb_2u_lib.s9s_mb_2u(sch_1):page572_i72@pure_quanta.q_res(chips)';

PART_NAME
 R1036 'Q_RES_0402LF-100K,1%,1/16W,CHIA':;

SECTION_NUMBER 1
 '@S9S_MB_2U_LIB.S9S_MB_2U(SCH_1):PAGE572_I66@PURE_QUANTA.Q_RES(CHIPS)':
 C_PATH='@s9s_mb_2u_lib.s9s_mb_2u(sch_1):page572_i66@pure_quanta.q_res(chips)';

PART_NAME
 R1035 'Q_RES_0402LF-27K,1%,1/16W,CHIPA':;

SECTION_NUMBER 1
 '@S9S_MB_2U_LIB.S9S_MB_2U(SCH_1):PAGE572_I63@PURE_QUANTA.Q_RES(CHIPS)':
 C_PATH='@s9s_mb_2u_lib.s9s_mb_2u(sch_1):page572_i63@pure_quanta.q_res(chips)';

PART_NAME
 R1034 'Q_RES_0402LF-10K,1%,1/16W,CHIPA':;

SECTION_NUMBER 1
 '@S9S_MB_2U_LIB.S9S_MB_2U(SCH_1):PAGE572_I40@PURE_QUANTA.Q_RES(CHIPS)':
 C_PATH='@s9s_mb_2u_lib.s9s_mb_2u(sch_1):page572_i40@pure_quanta.q_res(chips)';

PART_NAME
 R1033 'Q_RES_0402LF-165K,1%,1/16W,CHIA':;

SECTION_NUMBER 1
 '@S9S_MB_2U_LIB.S9S_MB_2U(SCH_1):PAGE572_I34@PURE_QUANTA.Q_RES(CHIPS)':
 C_PATH='@s9s_mb_2u_lib.s9s_mb_2u(sch_1):page572_i34@pure_quanta.q_res(chips)';

PART_NAME
 R1032 'Q_RES_0402LF-1K,1%,1/16W,CHIP,A':;

SECTION_NUMBER 1
 '@S9S_MB_2U_LIB.S9S_MB_2U(SCH_1):PAGE572_I68@PURE_QUANTA.Q_RES(CHIPS)':
 C_PATH='@s9s_mb_2u_lib.s9s_mb_2u(sch_1):page572_i68@pure_quanta.q_res(chips)';

PART_NAME
 R1031 'Q_RES_0402LF-26.7K,1%,1/16W,CHA':;

SECTION_NUMBER 1
 '@S9S_MB_2U_LIB.S9S_MB_2U(SCH_1):PAGE572_I44@PURE_QUANTA.Q_RES(CHIPS)':
 C_PATH='@s9s_mb_2u_lib.s9s_mb_2u(sch_1):page572_i44@pure_quanta.q_res(chips)';

PART_NAME
 R1030 'Q_RES_0402LF-10K,1%,1/16W,CHIPA':;

SECTION_NUMBER 1
 '@S9S_MB_2U_LIB.S9S_MB_2U(SCH_1):PAGE572_I42@PURE_QUANTA.Q_RES(CHIPS)':
 C_PATH='@s9s_mb_2u_lib.s9s_mb_2u(sch_1):page572_i42@pure_quanta.q_res(chips)';

PART_NAME
 R1029 'Q_RES_0402LF-150K,1%,1/16W,CHIA':;

SECTION_NUMBER 1
 '@S9S_MB_2U_LIB.S9S_MB_2U(SCH_1):PAGE572_I35@PURE_QUANTA.Q_RES(CHIPS)':
 C_PATH='@s9s_mb_2u_lib.s9s_mb_2u(sch_1):page572_i35@pure_quanta.q_res(chips)';

PART_NAME
 R1028 'Q_RES_0402LF-10K,1%,1/16W,CHIPA':;

SECTION_NUMBER 1
 '@S9S_MB_2U_LIB.S9S_MB_2U(SCH_1):PAGE572_I78@PURE_QUANTA.Q_RES(CHIPS)':
 C_PATH='@s9s_mb_2u_lib.s9s_mb_2u(sch_1):page572_i78@pure_quanta.q_res(chips)';

PART_NAME
 R1027 'Q_RES_0402LF-267K,1%,1/16W,CHIA':;

SECTION_NUMBER 1
 '@S9S_MB_2U_LIB.S9S_MB_2U(SCH_1):PAGE572_I77@PURE_QUANTA.Q_RES(CHIPS)':
 C_PATH='@s9s_mb_2u_lib.s9s_mb_2u(sch_1):page572_i77@pure_quanta.q_res(chips)';

PART_NAME
 R385 'Q_RES_0402LF-0,5%,1/16W,CHIP,CA':;

SECTION_NUMBER 1
 '@S9S_MB_2U_LIB.S9S_MB_2U(SCH_1):PAGE572_I97@PURE_QUANTA.Q_RES(CHIPS)':
 C_PATH='@s9s_mb_2u_lib.s9s_mb_2u(sch_1):page572_i97@pure_quanta.q_res(chips)';

PART_NAME
 Q18 'MOSFET_NCH_DUAL-DMN53D0LDW-7,SA':;

SECTION_NUMBER 1
 '@S9S_MB_2U_LIB.S9S_MB_2U(SCH_1):PAGE572_I90@PURE_QUANTA.MOSFET_NCH_DUAL(CHIPS)':
 C_PATH='@s9s_mb_2u_lib.s9s_mb_2u(sch_1):page572_i90@pure_quanta.mosfet_nch_dual(c~
hips)';

SECTION_NUMBER 2
 '@S9S_MB_2U_LIB.S9S_MB_2U(SCH_1):PAGE572_I93@PURE_QUANTA.MOSFET_NCH_DUAL(CHIPS)':
 C_PATH='@s9s_mb_2u_lib.s9s_mb_2u(sch_1):page572_i93@pure_quanta.mosfet_nch_dual(c~
hips)';

PART_NAME
 Q17 'MOSFET_NCH_DUAL-DMN53D0LDW-7,SA':;

SECTION_NUMBER 1
 '@S9S_MB_2U_LIB.S9S_MB_2U(SCH_1):PAGE572_I92@PURE_QUANTA.MOSFET_NCH_DUAL(CHIPS)':
 C_PATH='@s9s_mb_2u_lib.s9s_mb_2u(sch_1):page572_i92@pure_quanta.mosfet_nch_dual(c~
hips)';

SECTION_NUMBER 2
 '@S9S_MB_2U_LIB.S9S_MB_2U(SCH_1):PAGE572_I94@PURE_QUANTA.MOSFET_NCH_DUAL(CHIPS)':
 C_PATH='@s9s_mb_2u_lib.s9s_mb_2u(sch_1):page572_i94@pure_quanta.mosfet_nch_dual(c~
hips)';

PART_NAME
 C178 'Q_CAP_0402-0.1UF,25V,10%,X7R,CA':;

SECTION_NUMBER 1
 '@S9S_MB_2U_LIB.S9S_MB_2U(SCH_1):PAGE572_I9@PURE_QUANTA.Q_CAP(CHIPS)':
 C_PATH='@s9s_mb_2u_lib.s9s_mb_2u(sch_1):page572_i9@pure_quanta.q_cap(chips)';

PART_NAME
 C177 'Q_CAP_0402-0.1UF,25V,10%,X7R,CA':;

SECTION_NUMBER 1
 '@S9S_MB_2U_LIB.S9S_MB_2U(SCH_1):PAGE572_I55@PURE_QUANTA.Q_CAP(CHIPS)':
 C_PATH='@s9s_mb_2u_lib.s9s_mb_2u(sch_1):page572_i55@pure_quanta.q_cap(chips)';

PART_NAME
 C176 'Q_CAP_0402-0.1UF,25V,10%,X7R,CA':;

SECTION_NUMBER 1
 '@S9S_MB_2U_LIB.S9S_MB_2U(SCH_1):PAGE572_I38@PURE_QUANTA.Q_CAP(CHIPS)':
 C_PATH='@s9s_mb_2u_lib.s9s_mb_2u(sch_1):page572_i38@pure_quanta.q_cap(chips)';

PART_NAME
 C175 'Q_CAP_0402-0.1UF,25V,10%,X7R,CA':;

SECTION_NUMBER 1
 '@S9S_MB_2U_LIB.S9S_MB_2U(SCH_1):PAGE572_I32@PURE_QUANTA.Q_CAP(CHIPS)':
 C_PATH='@s9s_mb_2u_lib.s9s_mb_2u(sch_1):page572_i32@pure_quanta.q_cap(chips)';

PART_NAME
 U36 'PCA9548APW-PCA9548APW,SMLF,IC,A':;

SECTION_NUMBER 1
 '@S9S_MB_2U_LIB.S9S_MB_2U(SCH_1):PAGE621_I23@PURE_QUANTA.PCA9548APW(CHIPS)':
 C_PATH='@s9s_mb_a_lib.s9s_mb_a(sch_1):page621_i23@pure_quanta.pca9548apw(chips)~
';

PART_NAME
 R1822 'Q_RES_0402LF-10K,1%,1/16W,CHIPA':;

SECTION_NUMBER 1
 '@S9S_MB_2U_LIB.S9S_MB_2U(SCH_1):PAGE621_I100@PURE_QUANTA.Q_RES(CHIPS)':
 C_PATH='@s9s_mb_2u_lib.s9s_mb_2u(sch_1):page621_i100@pure_quanta.q_res(chips)';

PART_NAME
 R1806 'Q_RES_0402LF-0,5%,1/16W,CHIP,CA':;

SECTION_NUMBER 1
 '@S9S_MB_2U_LIB.S9S_MB_2U(SCH_1):PAGE621_I97@PURE_QUANTA.Q_RES(CHIPS)':
 C_PATH='@s9s_mb_2u_lib.s9s_mb_2u(sch_1):page621_i97@pure_quanta.q_res(chips)';

PART_NAME
 R1460 'Q_RES_0402LF-2.2K ,5%,1/16W,EMA':;

SECTION_NUMBER 1
 '@S9S_MB_2U_LIB.S9S_MB_2U(SCH_1):PAGE621_I104@PURE_QUANTA.Q_RES(CHIPS)':
 C_PATH='@s9s_mb_2u_lib.s9s_mb_2u(sch_1):page621_i104@pure_quanta.q_res(chips)';

PART_NAME
 R1336 'Q_RES_0402LF-2.2K ,5%,1/16W,EMA':;

SECTION_NUMBER 1
 '@S9S_MB_2U_LIB.S9S_MB_2U(SCH_1):PAGE621_I101@PURE_QUANTA.Q_RES(CHIPS)':
 C_PATH='@s9s_mb_2u_lib.s9s_mb_2u(sch_1):page621_i101@pure_quanta.q_res(chips)';

PART_NAME
 R1094 'Q_RES_0402LF-2.2K ,5%,1/16W,CHA':;

SECTION_NUMBER 1
 '@S9S_MB_2U_LIB.S9S_MB_2U(SCH_1):PAGE621_I28@PURE_QUANTA.Q_RES(CHIPS)':
 C_PATH='@s9s_mb_2u_lib.s9s_mb_2u(sch_1):page621_i28@pure_quanta.q_res(chips)';

PART_NAME
 R1093 'Q_RES_0402LF-2.2K ,5%,1/16W,CHA':;

SECTION_NUMBER 1
 '@S9S_MB_2U_LIB.S9S_MB_2U(SCH_1):PAGE621_I27@PURE_QUANTA.Q_RES(CHIPS)':
 C_PATH='@s9s_mb_2u_lib.s9s_mb_2u(sch_1):page621_i27@pure_quanta.q_res(chips)';

PART_NAME
 R1092 'Q_RES_0402LF-2.2K ,5%,1/16W,CHA':;

SECTION_NUMBER 1
 '@S9S_MB_2U_LIB.S9S_MB_2U(SCH_1):PAGE621_I29@PURE_QUANTA.Q_RES(CHIPS)':
 C_PATH='@s9s_mb_2u_lib.s9s_mb_2u(sch_1):page621_i29@pure_quanta.q_res(chips)';

PART_NAME
 R1091 'Q_RES_0402LF-2.2K ,5%,1/16W,CHA':;

SECTION_NUMBER 1
 '@S9S_MB_2U_LIB.S9S_MB_2U(SCH_1):PAGE621_I30@PURE_QUANTA.Q_RES(CHIPS)':
 C_PATH='@s9s_mb_2u_lib.s9s_mb_2u(sch_1):page621_i30@pure_quanta.q_res(chips)';

PART_NAME
 R1090 'Q_RES_0402LF-2.2K ,5%,1/16W,CHA':;

SECTION_NUMBER 1
 '@S9S_MB_2U_LIB.S9S_MB_2U(SCH_1):PAGE621_I32@PURE_QUANTA.Q_RES(CHIPS)':
 C_PATH='@s9s_mb_2u_lib.s9s_mb_2u(sch_1):page621_i32@pure_quanta.q_res(chips)';

PART_NAME
 R1089 'Q_RES_0402LF-2.2K ,5%,1/16W,CHA':;

SECTION_NUMBER 1
 '@S9S_MB_2U_LIB.S9S_MB_2U(SCH_1):PAGE621_I31@PURE_QUANTA.Q_RES(CHIPS)':
 C_PATH='@s9s_mb_2u_lib.s9s_mb_2u(sch_1):page621_i31@pure_quanta.q_res(chips)';

PART_NAME
 R1088 'Q_RES_0402LF-2.2K ,5%,1/16W,CHA':;

SECTION_NUMBER 1
 '@S9S_MB_2U_LIB.S9S_MB_2U(SCH_1):PAGE621_I40@PURE_QUANTA.Q_RES(CHIPS)':
 C_PATH='@s9s_mb_2u_lib.s9s_mb_2u(sch_1):page621_i40@pure_quanta.q_res(chips)';

PART_NAME
 R1087 'Q_RES_0402LF-2.2K ,5%,1/16W,CHA':;

SECTION_NUMBER 1
 '@S9S_MB_2U_LIB.S9S_MB_2U(SCH_1):PAGE621_I39@PURE_QUANTA.Q_RES(CHIPS)':
 C_PATH='@s9s_mb_2u_lib.s9s_mb_2u(sch_1):page621_i39@pure_quanta.q_res(chips)';

PART_NAME
 R1086 'Q_RES_0402LF-0,5%,1/16W,CHIP,CA':;

SECTION_NUMBER 1
 '@S9S_MB_2U_LIB.S9S_MB_2U(SCH_1):PAGE621_I50@PURE_QUANTA.Q_RES(CHIPS)':
 C_PATH='@s9s_mb_2u_lib.s9s_mb_2u(sch_1):page621_i50@pure_quanta.q_res(chips)';

PART_NAME
 R1085 'Q_RES_0402LF-0,5%,1/16W,CHIP,CA':;

SECTION_NUMBER 1
 '@S9S_MB_2U_LIB.S9S_MB_2U(SCH_1):PAGE621_I51@PURE_QUANTA.Q_RES(CHIPS)':
 C_PATH='@s9s_mb_2u_lib.s9s_mb_2u(sch_1):page621_i51@pure_quanta.q_res(chips)';

PART_NAME
 R1084 'Q_RES_0402LF-0,5%,1/16W,CHIP,CA':;

SECTION_NUMBER 1
 '@S9S_MB_2U_LIB.S9S_MB_2U(SCH_1):PAGE621_I52@PURE_QUANTA.Q_RES(CHIPS)':
 C_PATH='@s9s_mb_2u_lib.s9s_mb_2u(sch_1):page621_i52@pure_quanta.q_res(chips)';

PART_NAME
 R1083 'Q_RES_0402LF-0,5%,1/16W,CHIP,CA':;

SECTION_NUMBER 1
 '@S9S_MB_2U_LIB.S9S_MB_2U(SCH_1):PAGE621_I53@PURE_QUANTA.Q_RES(CHIPS)':
 C_PATH='@s9s_mb_2u_lib.s9s_mb_2u(sch_1):page621_i53@pure_quanta.q_res(chips)';

PART_NAME
 R1082 'Q_RES_0402LF-0,5%,1/16W,CHIP,CA':;

SECTION_NUMBER 1
 '@S9S_MB_2U_LIB.S9S_MB_2U(SCH_1):PAGE621_I54@PURE_QUANTA.Q_RES(CHIPS)':
 C_PATH='@s9s_mb_2u_lib.s9s_mb_2u(sch_1):page621_i54@pure_quanta.q_res(chips)';

PART_NAME
 R1081 'Q_RES_0402LF-0,5%,1/16W,CHIP,CA':;

SECTION_NUMBER 1
 '@S9S_MB_2U_LIB.S9S_MB_2U(SCH_1):PAGE621_I55@PURE_QUANTA.Q_RES(CHIPS)':
 C_PATH='@s9s_mb_2u_lib.s9s_mb_2u(sch_1):page621_i55@pure_quanta.q_res(chips)';

PART_NAME
 R1080 'Q_RES_0402LF-0,5%,1/16W,CHIP,CA':;

SECTION_NUMBER 1
 '@S9S_MB_2U_LIB.S9S_MB_2U(SCH_1):PAGE621_I56@PURE_QUANTA.Q_RES(CHIPS)':
 C_PATH='@s9s_mb_2u_lib.s9s_mb_2u(sch_1):page621_i56@pure_quanta.q_res(chips)';

PART_NAME
 R1079 'Q_RES_0402LF-0,5%,1/16W,CHIP,CA':;

SECTION_NUMBER 1
 '@S9S_MB_2U_LIB.S9S_MB_2U(SCH_1):PAGE621_I57@PURE_QUANTA.Q_RES(CHIPS)':
 C_PATH='@s9s_mb_2u_lib.s9s_mb_2u(sch_1):page621_i57@pure_quanta.q_res(chips)';

PART_NAME
 R1078 'Q_RES_0402LF-0,5%,1/16W,CHIP,CA':;

SECTION_NUMBER 1
 '@S9S_MB_2U_LIB.S9S_MB_2U(SCH_1):PAGE621_I58@PURE_QUANTA.Q_RES(CHIPS)':
 C_PATH='@s9s_mb_2u_lib.s9s_mb_2u(sch_1):page621_i58@pure_quanta.q_res(chips)';

PART_NAME
 R1077 'Q_RES_0402LF-0,5%,1/16W,CHIP,CA':;

SECTION_NUMBER 1
 '@S9S_MB_2U_LIB.S9S_MB_2U(SCH_1):PAGE621_I59@PURE_QUANTA.Q_RES(CHIPS)':
 C_PATH='@s9s_mb_2u_lib.s9s_mb_2u(sch_1):page621_i59@pure_quanta.q_res(chips)';

PART_NAME
 R1076 'Q_RES_0402LF-0,5%,1/16W,CHIP,CA':;

SECTION_NUMBER 1
 '@S9S_MB_2U_LIB.S9S_MB_2U(SCH_1):PAGE621_I61@PURE_QUANTA.Q_RES(CHIPS)':
 C_PATH='@s9s_mb_2u_lib.s9s_mb_2u(sch_1):page621_i61@pure_quanta.q_res(chips)';

PART_NAME
 R1075 'Q_RES_0402LF-0,5%,1/16W,CHIP,CA':;

SECTION_NUMBER 1
 '@S9S_MB_2U_LIB.S9S_MB_2U(SCH_1):PAGE621_I92@PURE_QUANTA.Q_RES(CHIPS)':
 C_PATH='@s9s_mb_2u_lib.s9s_mb_2u(sch_1):page621_i92@pure_quanta.q_res(chips)';

PART_NAME
 R1074 'Q_RES_0402LF-0,5%,1/16W,CHIP,CA':;

SECTION_NUMBER 1
 '@S9S_MB_2U_LIB.S9S_MB_2U(SCH_1):PAGE621_I62@PURE_QUANTA.Q_RES(CHIPS)':
 C_PATH='@s9s_mb_2u_lib.s9s_mb_2u(sch_1):page621_i62@pure_quanta.q_res(chips)';

PART_NAME
 R1073 'Q_RES_0402LF-0,5%,1/16W,CHIP,CA':;

SECTION_NUMBER 1
 '@S9S_MB_2U_LIB.S9S_MB_2U(SCH_1):PAGE621_I63@PURE_QUANTA.Q_RES(CHIPS)':
 C_PATH='@s9s_mb_2u_lib.s9s_mb_2u(sch_1):page621_i63@pure_quanta.q_res(chips)';

PART_NAME
 R649 'Q_RES_0402LF-2.2K ,5%,1/16W,CHA':;

SECTION_NUMBER 1
 '@S9S_MB_2U_LIB.S9S_MB_2U(SCH_1):PAGE621_I42@PURE_QUANTA.Q_RES(CHIPS)':
 C_PATH='@s9s_mb_2u_lib.s9s_mb_2u(sch_1):page621_i42@pure_quanta.q_res(chips)';

PART_NAME
 R606 'Q_RES_0402LF-2.2K ,5%,1/16W,CHA':;

SECTION_NUMBER 1
 '@S9S_MB_2U_LIB.S9S_MB_2U(SCH_1):PAGE621_I41@PURE_QUANTA.Q_RES(CHIPS)':
 C_PATH='@s9s_mb_2u_lib.s9s_mb_2u(sch_1):page621_i41@pure_quanta.q_res(chips)';

PART_NAME
 R605 'Q_RES_0402LF-2.2K ,5%,1/16W,CHA':;

SECTION_NUMBER 1
 '@S9S_MB_2U_LIB.S9S_MB_2U(SCH_1):PAGE621_I43@PURE_QUANTA.Q_RES(CHIPS)':
 C_PATH='@s9s_mb_2u_lib.s9s_mb_2u(sch_1):page621_i43@pure_quanta.q_res(chips)';

PART_NAME
 R604 'Q_RES_0402LF-2.2K ,5%,1/16W,CHA':;

SECTION_NUMBER 1
 '@S9S_MB_2U_LIB.S9S_MB_2U(SCH_1):PAGE621_I44@PURE_QUANTA.Q_RES(CHIPS)':
 C_PATH='@s9s_mb_2u_lib.s9s_mb_2u(sch_1):page621_i44@pure_quanta.q_res(chips)';

PART_NAME
 R603 'Q_RES_0402LF-2.2K ,5%,1/16W,CHA':;

SECTION_NUMBER 1
 '@S9S_MB_2U_LIB.S9S_MB_2U(SCH_1):PAGE621_I46@PURE_QUANTA.Q_RES(CHIPS)':
 C_PATH='@s9s_mb_2u_lib.s9s_mb_2u(sch_1):page621_i46@pure_quanta.q_res(chips)';

PART_NAME
 R602 'Q_RES_0402LF-2.2K ,5%,1/16W,CHA':;

SECTION_NUMBER 1
 '@S9S_MB_2U_LIB.S9S_MB_2U(SCH_1):PAGE621_I47@PURE_QUANTA.Q_RES(CHIPS)':
 C_PATH='@s9s_mb_2u_lib.s9s_mb_2u(sch_1):page621_i47@pure_quanta.q_res(chips)';

PART_NAME
 R601 'Q_RES_0402LF-2.2K ,5%,1/16W,CHA':;

SECTION_NUMBER 1
 '@S9S_MB_2U_LIB.S9S_MB_2U(SCH_1):PAGE621_I48@PURE_QUANTA.Q_RES(CHIPS)':
 C_PATH='@s9s_mb_2u_lib.s9s_mb_2u(sch_1):page621_i48@pure_quanta.q_res(chips)';

PART_NAME
 R592 'Q_RES_0402LF-2.2K ,5%,1/16W,CHA':;

SECTION_NUMBER 1
 '@S9S_MB_2U_LIB.S9S_MB_2U(SCH_1):PAGE621_I49@PURE_QUANTA.Q_RES(CHIPS)':
 C_PATH='@s9s_mb_2u_lib.s9s_mb_2u(sch_1):page621_i49@pure_quanta.q_res(chips)';

PART_NAME
 R591 'Q_RES_0402LF-0,5%,1/16W,CHIP,CA':;

SECTION_NUMBER 1
 '@S9S_MB_2U_LIB.S9S_MB_2U(SCH_1):PAGE621_I64@PURE_QUANTA.Q_RES(CHIPS)':
 C_PATH='@s9s_mb_2u_lib.s9s_mb_2u(sch_1):page621_i64@pure_quanta.q_res(chips)';

PART_NAME
 R590 'Q_RES_0402LF-0,5%,1/16W,CHIP,CA':;

SECTION_NUMBER 1
 '@S9S_MB_2U_LIB.S9S_MB_2U(SCH_1):PAGE621_I65@PURE_QUANTA.Q_RES(CHIPS)':
 C_PATH='@s9s_mb_2u_lib.s9s_mb_2u(sch_1):page621_i65@pure_quanta.q_res(chips)';

PART_NAME
 R589 'Q_RES_0402LF-33.2,1%,1/16W,CHIA':;

SECTION_NUMBER 1
 '@S9S_MB_2U_LIB.S9S_MB_2U(SCH_1):PAGE621_I20@PURE_QUANTA.Q_RES(CHIPS)':
 C_PATH='@s9s_mb_2u_lib.s9s_mb_2u(sch_1):page621_i20@pure_quanta.q_res(chips)';

PART_NAME
 R588 'Q_RES_0402LF-33.2,1%,1/16W,CHIA':;

SECTION_NUMBER 1
 '@S9S_MB_2U_LIB.S9S_MB_2U(SCH_1):PAGE621_I19@PURE_QUANTA.Q_RES(CHIPS)':
 C_PATH='@s9s_mb_2u_lib.s9s_mb_2u(sch_1):page621_i19@pure_quanta.q_res(chips)';

PART_NAME
 R587 'Q_RES_0402LF-1K,1%,1/16W,CHIP,A':;

SECTION_NUMBER 1
 '@S9S_MB_2U_LIB.S9S_MB_2U(SCH_1):PAGE621_I6@PURE_QUANTA.Q_RES(CHIPS)':
 C_PATH='@s9s_mb_2u_lib.s9s_mb_2u(sch_1):page621_i6@pure_quanta.q_res(chips)';

PART_NAME
 R540 'Q_RES_0402LF-10K,1%,1/16W,EMPTA':;

SECTION_NUMBER 1
 '@S9S_MB_2U_LIB.S9S_MB_2U(SCH_1):PAGE621_I10@PURE_QUANTA.Q_RES(CHIPS)':
 C_PATH='@s9s_mb_2u_lib.s9s_mb_2u(sch_1):page621_i10@pure_quanta.q_res(chips)';

PART_NAME
 R539 'Q_RES_0402LF-1K,1%,1/16W,CHIP,A':;

SECTION_NUMBER 1
 '@S9S_MB_2U_LIB.S9S_MB_2U(SCH_1):PAGE621_I4@PURE_QUANTA.Q_RES(CHIPS)':
 C_PATH='@s9s_mb_2u_lib.s9s_mb_2u(sch_1):page621_i4@pure_quanta.q_res(chips)';

PART_NAME
 R538 'Q_RES_0402LF-10K,1%,1/16W,EMPTA':;

SECTION_NUMBER 1
 '@S9S_MB_2U_LIB.S9S_MB_2U(SCH_1):PAGE621_I9@PURE_QUANTA.Q_RES(CHIPS)':
 C_PATH='@s9s_mb_2u_lib.s9s_mb_2u(sch_1):page621_i9@pure_quanta.q_res(chips)';

PART_NAME
 R537 'Q_RES_0402LF-1K,1%,1/16W,CHIP,A':;

SECTION_NUMBER 1
 '@S9S_MB_2U_LIB.S9S_MB_2U(SCH_1):PAGE621_I2@PURE_QUANTA.Q_RES(CHIPS)':
 C_PATH='@s9s_mb_2u_lib.s9s_mb_2u(sch_1):page621_i2@pure_quanta.q_res(chips)';

PART_NAME
 R536 'Q_RES_0402LF-10K,1%,1/16W,EMPTA':;

SECTION_NUMBER 1
 '@S9S_MB_2U_LIB.S9S_MB_2U(SCH_1):PAGE621_I7@PURE_QUANTA.Q_RES(CHIPS)':
 C_PATH='@s9s_mb_2u_lib.s9s_mb_2u(sch_1):page621_i7@pure_quanta.q_res(chips)';

PART_NAME
 C174 'Q_CAP_0402-0.1UF,25V,10%,X7R,CA':;

SECTION_NUMBER 1
 '@S9S_MB_2U_LIB.S9S_MB_2U(SCH_1):PAGE621_I25@PURE_QUANTA.Q_CAP(CHIPS)':
 C_PATH='@s9s_mb_2u_lib.s9s_mb_2u(sch_1):page621_i25@pure_quanta.q_cap(chips)';

PART_NAME
 C170 'Q_CAP_DIFFBUS_C0201-DIFF BUS_0A':;

SECTION_NUMBER 1
 '@S9S_MB_2U_LIB.S9S_MB_2U(SCH_1):PAGE513_I128@PURE_QUANTA.Q_CAP_DIFFBUS(CHIPS)':
 C_PATH='@s9s_mb_2u_lib.s9s_mb_2u(sch_1):page513_i128@pure_quanta.q_cap_diffbus(ch~
ips)';

PART_NAME
 C169 'Q_CAP_DIFFBUS_C0201-DIFF BUS_0A':;

SECTION_NUMBER 1
 '@S9S_MB_2U_LIB.S9S_MB_2U(SCH_1):PAGE513_I127@PURE_QUANTA.Q_CAP_DIFFBUS(CHIPS)':
 C_PATH='@s9s_mb_2u_lib.s9s_mb_2u(sch_1):page513_i127@pure_quanta.q_cap_diffbus(ch~
ips)';

PART_NAME
 C168 'Q_CAP_DIFFBUS_C0201-DIFF BUS_0A':;

SECTION_NUMBER 1
 '@S9S_MB_2U_LIB.S9S_MB_2U(SCH_1):PAGE513_I125@PURE_QUANTA.Q_CAP_DIFFBUS(CHIPS)':
 C_PATH='@s9s_mb_2u_lib.s9s_mb_2u(sch_1):page513_i125@pure_quanta.q_cap_diffbus(ch~
ips)';

PART_NAME
 C167 'Q_CAP_DIFFBUS_C0201-DIFF BUS_0A':;

SECTION_NUMBER 1
 '@S9S_MB_2U_LIB.S9S_MB_2U(SCH_1):PAGE513_I126@PURE_QUANTA.Q_CAP_DIFFBUS(CHIPS)':
 C_PATH='@s9s_mb_2u_lib.s9s_mb_2u(sch_1):page513_i126@pure_quanta.q_cap_diffbus(ch~
ips)';

PART_NAME
 C166 'Q_CAP_DIFFBUS_C0201-DIFF BUS_0A':;

SECTION_NUMBER 1
 '@S9S_MB_2U_LIB.S9S_MB_2U(SCH_1):PAGE513_I124@PURE_QUANTA.Q_CAP_DIFFBUS(CHIPS)':
 C_PATH='@s9s_mb_2u_lib.s9s_mb_2u(sch_1):page513_i124@pure_quanta.q_cap_diffbus(ch~
ips)';

PART_NAME
 C165 'Q_CAP_DIFFBUS_C0201-DIFF BUS_0A':;

SECTION_NUMBER 1
 '@S9S_MB_2U_LIB.S9S_MB_2U(SCH_1):PAGE513_I123@PURE_QUANTA.Q_CAP_DIFFBUS(CHIPS)':
 C_PATH='@s9s_mb_2u_lib.s9s_mb_2u(sch_1):page513_i123@pure_quanta.q_cap_diffbus(ch~
ips)';

PART_NAME
 C164 'Q_CAP_DIFFBUS_C0201-DIFF BUS_0A':;

SECTION_NUMBER 1
 '@S9S_MB_2U_LIB.S9S_MB_2U(SCH_1):PAGE513_I122@PURE_QUANTA.Q_CAP_DIFFBUS(CHIPS)':
 C_PATH='@s9s_mb_2u_lib.s9s_mb_2u(sch_1):page513_i122@pure_quanta.q_cap_diffbus(ch~
ips)';

PART_NAME
 C163 'Q_CAP_DIFFBUS_C0201-DIFF BUS_0A':;

SECTION_NUMBER 1
 '@S9S_MB_2U_LIB.S9S_MB_2U(SCH_1):PAGE513_I121@PURE_QUANTA.Q_CAP_DIFFBUS(CHIPS)':
 C_PATH='@s9s_mb_2u_lib.s9s_mb_2u(sch_1):page513_i121@pure_quanta.q_cap_diffbus(ch~
ips)';

PART_NAME
 C162 'Q_CAP_DIFFBUS_C0201-DIFF BUS_0A':;

SECTION_NUMBER 1
 '@S9S_MB_2U_LIB.S9S_MB_2U(SCH_1):PAGE513_I120@PURE_QUANTA.Q_CAP_DIFFBUS(CHIPS)':
 C_PATH='@s9s_mb_2u_lib.s9s_mb_2u(sch_1):page513_i120@pure_quanta.q_cap_diffbus(ch~
ips)';

PART_NAME
 C161 'Q_CAP_DIFFBUS_C0201-DIFF BUS_0A':;

SECTION_NUMBER 1
 '@S9S_MB_2U_LIB.S9S_MB_2U(SCH_1):PAGE513_I119@PURE_QUANTA.Q_CAP_DIFFBUS(CHIPS)':
 C_PATH='@s9s_mb_2u_lib.s9s_mb_2u(sch_1):page513_i119@pure_quanta.q_cap_diffbus(ch~
ips)';

PART_NAME
 C160 'Q_CAP_DIFFBUS_C0201-DIFF BUS_0A':;

SECTION_NUMBER 1
 '@S9S_MB_2U_LIB.S9S_MB_2U(SCH_1):PAGE513_I118@PURE_QUANTA.Q_CAP_DIFFBUS(CHIPS)':
 C_PATH='@s9s_mb_2u_lib.s9s_mb_2u(sch_1):page513_i118@pure_quanta.q_cap_diffbus(ch~
ips)';

PART_NAME
 C159 'Q_CAP_DIFFBUS_C0201-DIFF BUS_0A':;

SECTION_NUMBER 1
 '@S9S_MB_2U_LIB.S9S_MB_2U(SCH_1):PAGE513_I117@PURE_QUANTA.Q_CAP_DIFFBUS(CHIPS)':
 C_PATH='@s9s_mb_2u_lib.s9s_mb_2u(sch_1):page513_i117@pure_quanta.q_cap_diffbus(ch~
ips)';

PART_NAME
 C158 'Q_CAP_DIFFBUS_C0201-DIFF BUS_0A':;

SECTION_NUMBER 1
 '@S9S_MB_2U_LIB.S9S_MB_2U(SCH_1):PAGE513_I116@PURE_QUANTA.Q_CAP_DIFFBUS(CHIPS)':
 C_PATH='@s9s_mb_2u_lib.s9s_mb_2u(sch_1):page513_i116@pure_quanta.q_cap_diffbus(ch~
ips)';

PART_NAME
 C157 'Q_CAP_DIFFBUS_C0201-DIFF BUS_0A':;

SECTION_NUMBER 1
 '@S9S_MB_2U_LIB.S9S_MB_2U(SCH_1):PAGE513_I115@PURE_QUANTA.Q_CAP_DIFFBUS(CHIPS)':
 C_PATH='@s9s_mb_2u_lib.s9s_mb_2u(sch_1):page513_i115@pure_quanta.q_cap_diffbus(ch~
ips)';

PART_NAME
 C156 'Q_CAP_DIFFBUS_C0201-DIFF BUS_0A':;

SECTION_NUMBER 1
 '@S9S_MB_2U_LIB.S9S_MB_2U(SCH_1):PAGE513_I114@PURE_QUANTA.Q_CAP_DIFFBUS(CHIPS)':
 C_PATH='@s9s_mb_2u_lib.s9s_mb_2u(sch_1):page513_i114@pure_quanta.q_cap_diffbus(ch~
ips)';

PART_NAME
 C155 'Q_CAP_DIFFBUS_C0201-DIFF BUS_0A':;

SECTION_NUMBER 1
 '@S9S_MB_2U_LIB.S9S_MB_2U(SCH_1):PAGE513_I113@PURE_QUANTA.Q_CAP_DIFFBUS(CHIPS)':
 C_PATH='@s9s_mb_2u_lib.s9s_mb_2u(sch_1):page513_i113@pure_quanta.q_cap_diffbus(ch~
ips)';

PART_NAME
 C154 'Q_CAP_DIFFBUS_C0201-DIFF BUS_0A':;

SECTION_NUMBER 1
 '@S9S_MB_2U_LIB.S9S_MB_2U(SCH_1):PAGE513_I22@PURE_QUANTA.Q_CAP_DIFFBUS(CHIPS)':
 C_PATH='@s9s_mb_2u_lib.s9s_mb_2u(sch_1):page513_i22@pure_quanta.q_cap_diffbus(chi~
ps)';

PART_NAME
 C153 'Q_CAP_DIFFBUS_C0201-DIFF BUS_0A':;

SECTION_NUMBER 1
 '@S9S_MB_2U_LIB.S9S_MB_2U(SCH_1):PAGE513_I21@PURE_QUANTA.Q_CAP_DIFFBUS(CHIPS)':
 C_PATH='@s9s_mb_2u_lib.s9s_mb_2u(sch_1):page513_i21@pure_quanta.q_cap_diffbus(chi~
ps)';

PART_NAME
 C152 'Q_CAP_DIFFBUS_C0201-DIFF BUS_0A':;

SECTION_NUMBER 1
 '@S9S_MB_2U_LIB.S9S_MB_2U(SCH_1):PAGE513_I23@PURE_QUANTA.Q_CAP_DIFFBUS(CHIPS)':
 C_PATH='@s9s_mb_2u_lib.s9s_mb_2u(sch_1):page513_i23@pure_quanta.q_cap_diffbus(chi~
ps)';

PART_NAME
 C151 'Q_CAP_DIFFBUS_C0201-DIFF BUS_0A':;

SECTION_NUMBER 1
 '@S9S_MB_2U_LIB.S9S_MB_2U(SCH_1):PAGE513_I24@PURE_QUANTA.Q_CAP_DIFFBUS(CHIPS)':
 C_PATH='@s9s_mb_2u_lib.s9s_mb_2u(sch_1):page513_i24@pure_quanta.q_cap_diffbus(chi~
ps)';

PART_NAME
 C150 'Q_CAP_DIFFBUS_C0201-DIFF BUS_0A':;

SECTION_NUMBER 1
 '@S9S_MB_2U_LIB.S9S_MB_2U(SCH_1):PAGE513_I26@PURE_QUANTA.Q_CAP_DIFFBUS(CHIPS)':
 C_PATH='@s9s_mb_2u_lib.s9s_mb_2u(sch_1):page513_i26@pure_quanta.q_cap_diffbus(chi~
ps)';

PART_NAME
 C149 'Q_CAP_DIFFBUS_C0201-DIFF BUS_0A':;

SECTION_NUMBER 1
 '@S9S_MB_2U_LIB.S9S_MB_2U(SCH_1):PAGE513_I25@PURE_QUANTA.Q_CAP_DIFFBUS(CHIPS)':
 C_PATH='@s9s_mb_2u_lib.s9s_mb_2u(sch_1):page513_i25@pure_quanta.q_cap_diffbus(chi~
ps)';

PART_NAME
 C148 'Q_CAP_DIFFBUS_C0201-DIFF BUS_0A':;

SECTION_NUMBER 1
 '@S9S_MB_2U_LIB.S9S_MB_2U(SCH_1):PAGE513_I27@PURE_QUANTA.Q_CAP_DIFFBUS(CHIPS)':
 C_PATH='@s9s_mb_2u_lib.s9s_mb_2u(sch_1):page513_i27@pure_quanta.q_cap_diffbus(chi~
ps)';

PART_NAME
 C147 'Q_CAP_DIFFBUS_C0201-DIFF BUS_0A':;

SECTION_NUMBER 1
 '@S9S_MB_2U_LIB.S9S_MB_2U(SCH_1):PAGE513_I28@PURE_QUANTA.Q_CAP_DIFFBUS(CHIPS)':
 C_PATH='@s9s_mb_2u_lib.s9s_mb_2u(sch_1):page513_i28@pure_quanta.q_cap_diffbus(chi~
ps)';

PART_NAME
 C146 'Q_CAP_DIFFBUS_C0201-DIFF BUS_0A':;

SECTION_NUMBER 1
 '@S9S_MB_2U_LIB.S9S_MB_2U(SCH_1):PAGE513_I29@PURE_QUANTA.Q_CAP_DIFFBUS(CHIPS)':
 C_PATH='@s9s_mb_2u_lib.s9s_mb_2u(sch_1):page513_i29@pure_quanta.q_cap_diffbus(chi~
ps)';

PART_NAME
 C145 'Q_CAP_DIFFBUS_C0201-DIFF BUS_0A':;

SECTION_NUMBER 1
 '@S9S_MB_2U_LIB.S9S_MB_2U(SCH_1):PAGE513_I30@PURE_QUANTA.Q_CAP_DIFFBUS(CHIPS)':
 C_PATH='@s9s_mb_2u_lib.s9s_mb_2u(sch_1):page513_i30@pure_quanta.q_cap_diffbus(chi~
ps)';

PART_NAME
 C144 'Q_CAP_DIFFBUS_C0201-DIFF BUS_0A':;

SECTION_NUMBER 1
 '@S9S_MB_2U_LIB.S9S_MB_2U(SCH_1):PAGE513_I31@PURE_QUANTA.Q_CAP_DIFFBUS(CHIPS)':
 C_PATH='@s9s_mb_2u_lib.s9s_mb_2u(sch_1):page513_i31@pure_quanta.q_cap_diffbus(chi~
ps)';

PART_NAME
 C143 'Q_CAP_DIFFBUS_C0201-DIFF BUS_0A':;

SECTION_NUMBER 1
 '@S9S_MB_2U_LIB.S9S_MB_2U(SCH_1):PAGE513_I32@PURE_QUANTA.Q_CAP_DIFFBUS(CHIPS)':
 C_PATH='@s9s_mb_2u_lib.s9s_mb_2u(sch_1):page513_i32@pure_quanta.q_cap_diffbus(chi~
ps)';

PART_NAME
 C142 'Q_CAP_DIFFBUS_C0201-DIFF BUS_0A':;

SECTION_NUMBER 1
 '@S9S_MB_2U_LIB.S9S_MB_2U(SCH_1):PAGE513_I33@PURE_QUANTA.Q_CAP_DIFFBUS(CHIPS)':
 C_PATH='@s9s_mb_2u_lib.s9s_mb_2u(sch_1):page513_i33@pure_quanta.q_cap_diffbus(chi~
ps)';

PART_NAME
 C141 'Q_CAP_DIFFBUS_C0201-DIFF BUS_0A':;

SECTION_NUMBER 1
 '@S9S_MB_2U_LIB.S9S_MB_2U(SCH_1):PAGE513_I34@PURE_QUANTA.Q_CAP_DIFFBUS(CHIPS)':
 C_PATH='@s9s_mb_2u_lib.s9s_mb_2u(sch_1):page513_i34@pure_quanta.q_cap_diffbus(chi~
ps)';

PART_NAME
 C140 'Q_CAP_DIFFBUS_C0201-DIFF BUS_0A':;

SECTION_NUMBER 1
 '@S9S_MB_2U_LIB.S9S_MB_2U(SCH_1):PAGE513_I36@PURE_QUANTA.Q_CAP_DIFFBUS(CHIPS)':
 C_PATH='@s9s_mb_2u_lib.s9s_mb_2u(sch_1):page513_i36@pure_quanta.q_cap_diffbus(chi~
ps)';

PART_NAME
 C139 'Q_CAP_DIFFBUS_C0201-DIFF BUS_0A':;

SECTION_NUMBER 1
 '@S9S_MB_2U_LIB.S9S_MB_2U(SCH_1):PAGE513_I35@PURE_QUANTA.Q_CAP_DIFFBUS(CHIPS)':
 C_PATH='@s9s_mb_2u_lib.s9s_mb_2u(sch_1):page513_i35@pure_quanta.q_cap_diffbus(chi~
ps)';

PART_NAME
 R1580 'Q_RES_0402LF-10K,5%,1/16W,CHIPA':;

SECTION_NUMBER 1
 '@S9S_MB_2U_LIB.S9S_MB_2U(SCH_1):PAGE495_I228@PURE_QUANTA.Q_RES(CHIPS)':
 C_PATH='@s9s_mb_2u_lib.s9s_mb_2u(sch_1):page495_i228@pure_quanta.q_res(chips)';

PART_NAME
 R1579 'Q_RES_0402LF-10K,5%,1/16W,CHIPA':;

SECTION_NUMBER 1
 '@S9S_MB_2U_LIB.S9S_MB_2U(SCH_1):PAGE495_I226@PURE_QUANTA.Q_RES(CHIPS)':
 C_PATH='@s9s_mb_2u_lib.s9s_mb_2u(sch_1):page495_i226@pure_quanta.q_res(chips)';

PART_NAME
 R1578 'Q_RES_0402LF-100,1%,1/16W,CHIPA':;

SECTION_NUMBER 1
 '@S9S_MB_2U_LIB.S9S_MB_2U(SCH_1):PAGE495_I234@PURE_QUANTA.Q_RES(CHIPS)':
 C_PATH='@s9s_mb_2u_lib.s9s_mb_2u(sch_1):page495_i234@pure_quanta.q_res(chips)';

PART_NAME
 R1577 'Q_RES_0402LF-0,5%,1/16W,CHIP,CA':;

SECTION_NUMBER 1
 '@S9S_MB_2U_LIB.S9S_MB_2U(SCH_1):PAGE495_I239@PURE_QUANTA.Q_RES(CHIPS)':
 C_PATH='@s9s_mb_2u_lib.s9s_mb_2u(sch_1):page495_i239@pure_quanta.q_res(chips)';

PART_NAME
 R1536 'Q_RES_0402LF-4.7K,5%,1/16W,EMPA':;

SECTION_NUMBER 1
 '@S9S_MB_2U_LIB.S9S_MB_2U(SCH_1):PAGE495_I165@PURE_QUANTA.Q_RES(CHIPS)':
 C_PATH='@s9s_mb_2u_lib.s9s_mb_2u(sch_1):page495_i165@pure_quanta.q_res(chips)';

PART_NAME
 R1535 'Q_RES_0402LF-4.7K,5%,1/16W,EMPA':;

SECTION_NUMBER 1
 '@S9S_MB_2U_LIB.S9S_MB_2U(SCH_1):PAGE495_I166@PURE_QUANTA.Q_RES(CHIPS)':
 C_PATH='@s9s_mb_2u_lib.s9s_mb_2u(sch_1):page495_i166@pure_quanta.q_res(chips)';

PART_NAME
 R1534 'Q_RES_0402LF-4.7K,5%,1/16W,EMPA':;

SECTION_NUMBER 1
 '@S9S_MB_2U_LIB.S9S_MB_2U(SCH_1):PAGE495_I167@PURE_QUANTA.Q_RES(CHIPS)':
 C_PATH='@s9s_mb_2u_lib.s9s_mb_2u(sch_1):page495_i167@pure_quanta.q_res(chips)';

PART_NAME
 R1533 'Q_RES_0402LF-4.7K,5%,1/16W,EMPA':;

SECTION_NUMBER 1
 '@S9S_MB_2U_LIB.S9S_MB_2U(SCH_1):PAGE495_I168@PURE_QUANTA.Q_RES(CHIPS)':
 C_PATH='@s9s_mb_2u_lib.s9s_mb_2u(sch_1):page495_i168@pure_quanta.q_res(chips)';

PART_NAME
 R1532 'Q_RES_0402LF-4.7K,5%,1/16W,EMPA':;

SECTION_NUMBER 1
 '@S9S_MB_2U_LIB.S9S_MB_2U(SCH_1):PAGE495_I170@PURE_QUANTA.Q_RES(CHIPS)':
 C_PATH='@s9s_mb_2u_lib.s9s_mb_2u(sch_1):page495_i170@pure_quanta.q_res(chips)';

PART_NAME
 R1482 'Q_RES_0402LF-33.2,1%,1/16W,CHIA':;

SECTION_NUMBER 1
 '@S9S_MB_2U_LIB.S9S_MB_2U(SCH_1):PAGE495_I172@PURE_QUANTA.Q_RES(CHIPS)':
 C_PATH='@s9s_mb_2u_lib.s9s_mb_2u(sch_1):page495_i172@pure_quanta.q_res(chips)';

PART_NAME
 R392 'Q_RES_0402LF-10K,5%,1/16W,CHIPA':;

SECTION_NUMBER 1
 '@S9S_MB_2U_LIB.S9S_MB_2U(SCH_1):PAGE495_I231@PURE_QUANTA.Q_RES(CHIPS)':
 C_PATH='@s9s_mb_2u_lib.s9s_mb_2u(sch_1):page495_i231@pure_quanta.q_res(chips)';

PART_NAME
 R391 'Q_RES_0402LF-10K,1%,1/16W,CHIPA':;

SECTION_NUMBER 1
 '@S9S_MB_2U_LIB.S9S_MB_2U(SCH_1):PAGE495_I108@PURE_QUANTA.Q_RES(CHIPS)':
 C_PATH='@s9s_mb_2u_lib.s9s_mb_2u(sch_1):page495_i108@pure_quanta.q_res(chips)';

PART_NAME
 R86 'Q_RES_0402LF-10K,5%,1/16W,EMPTA':;

SECTION_NUMBER 1
 '@S9S_MB_2U_LIB.S9S_MB_2U(SCH_1):PAGE495_I240@PURE_QUANTA.Q_RES(CHIPS)':
 C_PATH='@s9s_mb_2u_lib.s9s_mb_2u(sch_1):page495_i240@pure_quanta.q_res(chips)';

PART_NAME
 J57 'SCONN140_ME1014010101011-SCONNA':;

SECTION_NUMBER 1
 '@S9S_MB_2U_LIB.S9S_MB_2U(SCH_1):PAGE495_I36@PURE_QUANTA.SCONN140_ME1014010101011(CHIPS)':
 C_PATH='@s9s_mb_2u_lib.s9s_mb_2u(sch_1):page495_i36@pure_quanta.sconn140_me101401~
0101011(chips)';

PART_NAME
 C138 'Q_CAP_0402-0.1UF,25V,10%,X7R,CA':;

SECTION_NUMBER 1
 '@S9S_MB_2U_LIB.S9S_MB_2U(SCH_1):PAGE495_I26@PURE_QUANTA.Q_CAP(CHIPS)':
 C_PATH='@s9s_mb_2u_lib.s9s_mb_2u(sch_1):page495_i26@pure_quanta.q_cap(chips)';

PART_NAME
 C137 'Q_CAP_C0402-1UF,25V,10%,X6S,CHA':;

SECTION_NUMBER 1
 '@S9S_MB_2U_LIB.S9S_MB_2U(SCH_1):PAGE495_I24@PURE_QUANTA.Q_CAP(CHIPS)':
 C_PATH='@s9s_mb_2u_lib.s9s_mb_2u(sch_1):page495_i24@pure_quanta.q_cap(chips)';

PART_NAME
 C136 'Q_CAP_0402-0.1UF,25V,10%,X7R,CA':;

SECTION_NUMBER 1
 '@S9S_MB_2U_LIB.S9S_MB_2U(SCH_1):PAGE495_I23@PURE_QUANTA.Q_CAP(CHIPS)':
 C_PATH='@s9s_mb_2u_lib.s9s_mb_2u(sch_1):page495_i23@pure_quanta.q_cap(chips)';

PART_NAME
 C135 'Q_CAPP_SMLF-100UF,16V,20%,POSCA':;

SECTION_NUMBER 1
 '@S9S_MB_2U_LIB.S9S_MB_2U(SCH_1):PAGE495_I21@PURE_QUANTA.Q_CAPP(CHIPS)':
 C_PATH='@s9s_mb_2u_lib.s9s_mb_2u(sch_1):page495_i21@pure_quanta.q_capp(chips)';

PART_NAME
 C134 'Q_CAP_0402-0.1UF,25V,10%,X7R,CA':;

SECTION_NUMBER 1
 '@S9S_MB_2U_LIB.S9S_MB_2U(SCH_1):PAGE495_I20@PURE_QUANTA.Q_CAP(CHIPS)':
 C_PATH='@s9s_mb_2u_lib.s9s_mb_2u(sch_1):page495_i20@pure_quanta.q_cap(chips)';

PART_NAME
 C133 'Q_CAPP_SMLF-100UF,16V,20%,POSCA':;

SECTION_NUMBER 1
 '@S9S_MB_2U_LIB.S9S_MB_2U(SCH_1):PAGE495_I18@PURE_QUANTA.Q_CAPP(CHIPS)':
 C_PATH='@s9s_mb_2u_lib.s9s_mb_2u(sch_1):page495_i18@pure_quanta.q_capp(chips)';

PART_NAME
 R1576 'Q_RES_0402LF-10K,5%,1/16W,CHIPA':;

SECTION_NUMBER 1
 '@S9S_MB_2U_LIB.S9S_MB_2U(SCH_1):PAGE494_I228@PURE_QUANTA.Q_RES(CHIPS)':
 C_PATH='@s9s_mb_2u_lib.s9s_mb_2u(sch_1):page494_i228@pure_quanta.q_res(chips)';

PART_NAME
 R1575 'Q_RES_0402LF-10K,5%,1/16W,CHIPA':;

SECTION_NUMBER 1
 '@S9S_MB_2U_LIB.S9S_MB_2U(SCH_1):PAGE494_I226@PURE_QUANTA.Q_RES(CHIPS)':
 C_PATH='@s9s_mb_2u_lib.s9s_mb_2u(sch_1):page494_i226@pure_quanta.q_res(chips)';

PART_NAME
 R1574 'Q_RES_0402LF-100,1%,1/16W,CHIPA':;

SECTION_NUMBER 1
 '@S9S_MB_2U_LIB.S9S_MB_2U(SCH_1):PAGE494_I234@PURE_QUANTA.Q_RES(CHIPS)':
 C_PATH='@s9s_mb_2u_lib.s9s_mb_2u(sch_1):page494_i234@pure_quanta.q_res(chips)';

PART_NAME
 R1573 'Q_RES_0402LF-0,5%,1/16W,CHIP,CA':;

SECTION_NUMBER 1
 '@S9S_MB_2U_LIB.S9S_MB_2U(SCH_1):PAGE494_I237@PURE_QUANTA.Q_RES(CHIPS)':
 C_PATH='@s9s_mb_2u_lib.s9s_mb_2u(sch_1):page494_i237@pure_quanta.q_res(chips)';

PART_NAME
 R1531 'Q_RES_0402LF-4.7K,5%,1/16W,EMPA':;

SECTION_NUMBER 1
 '@S9S_MB_2U_LIB.S9S_MB_2U(SCH_1):PAGE494_I160@PURE_QUANTA.Q_RES(CHIPS)':
 C_PATH='@s9s_mb_2u_lib.s9s_mb_2u(sch_1):page494_i160@pure_quanta.q_res(chips)';

PART_NAME
 R1530 'Q_RES_0402LF-4.7K,5%,1/16W,EMPA':;

SECTION_NUMBER 1
 '@S9S_MB_2U_LIB.S9S_MB_2U(SCH_1):PAGE494_I161@PURE_QUANTA.Q_RES(CHIPS)':
 C_PATH='@s9s_mb_2u_lib.s9s_mb_2u(sch_1):page494_i161@pure_quanta.q_res(chips)';

PART_NAME
 R1529 'Q_RES_0402LF-4.7K,5%,1/16W,EMPA':;

SECTION_NUMBER 1
 '@S9S_MB_2U_LIB.S9S_MB_2U(SCH_1):PAGE494_I162@PURE_QUANTA.Q_RES(CHIPS)':
 C_PATH='@s9s_mb_2u_lib.s9s_mb_2u(sch_1):page494_i162@pure_quanta.q_res(chips)';

PART_NAME
 R1528 'Q_RES_0402LF-4.7K,5%,1/16W,EMPA':;

SECTION_NUMBER 1
 '@S9S_MB_2U_LIB.S9S_MB_2U(SCH_1):PAGE494_I163@PURE_QUANTA.Q_RES(CHIPS)':
 C_PATH='@s9s_mb_2u_lib.s9s_mb_2u(sch_1):page494_i163@pure_quanta.q_res(chips)';

PART_NAME
 R1481 'Q_RES_0402LF-33.2,1%,1/16W,CHIA':;

SECTION_NUMBER 1
 '@S9S_MB_2U_LIB.S9S_MB_2U(SCH_1):PAGE494_I172@PURE_QUANTA.Q_RES(CHIPS)':
 C_PATH='@s9s_mb_2u_lib.s9s_mb_2u(sch_1):page494_i172@pure_quanta.q_res(chips)';

PART_NAME
 R640 'Q_RES_0402LF-4.7K,5%,1/16W,EMPA':;

SECTION_NUMBER 1
 '@S9S_MB_2U_LIB.S9S_MB_2U(SCH_1):PAGE494_I164@PURE_QUANTA.Q_RES(CHIPS)':
 C_PATH='@s9s_mb_2u_lib.s9s_mb_2u(sch_1):page494_i164@pure_quanta.q_res(chips)';

PART_NAME
 R389 'Q_RES_0402LF-10K,5%,1/16W,CHIPA':;

SECTION_NUMBER 1
 '@S9S_MB_2U_LIB.S9S_MB_2U(SCH_1):PAGE494_I231@PURE_QUANTA.Q_RES(CHIPS)':
 C_PATH='@s9s_mb_2u_lib.s9s_mb_2u(sch_1):page494_i231@pure_quanta.q_res(chips)';

PART_NAME
 R388 'Q_RES_0402LF-10K,1%,1/16W,CHIPA':;

SECTION_NUMBER 1
 '@S9S_MB_2U_LIB.S9S_MB_2U(SCH_1):PAGE494_I108@PURE_QUANTA.Q_RES(CHIPS)':
 C_PATH='@s9s_mb_2u_lib.s9s_mb_2u(sch_1):page494_i108@pure_quanta.q_res(chips)';

PART_NAME
 R85 'Q_RES_0402LF-10K,5%,1/16W,EMPTA':;

SECTION_NUMBER 1
 '@S9S_MB_2U_LIB.S9S_MB_2U(SCH_1):PAGE494_I173@PURE_QUANTA.Q_RES(CHIPS)':
 C_PATH='@s9s_mb_2u_lib.s9s_mb_2u(sch_1):page494_i173@pure_quanta.q_res(chips)';

PART_NAME
 J56 'SCONN140_ME1014010101011-SCONNA':;

SECTION_NUMBER 1
 '@S9S_MB_2U_LIB.S9S_MB_2U(SCH_1):PAGE494_I27@PURE_QUANTA.SCONN140_ME1014010101011(CHIPS)':
 C_PATH='@s9s_mb_2u_lib.s9s_mb_2u(sch_1):page494_i27@pure_quanta.sconn140_me101401~
0101011(chips)';

PART_NAME
 C132 'Q_CAP_0402-0.1UF,25V,10%,X7R,CA':;

SECTION_NUMBER 1
 '@S9S_MB_2U_LIB.S9S_MB_2U(SCH_1):PAGE494_I106@PURE_QUANTA.Q_CAP(CHIPS)':
 C_PATH='@s9s_mb_2u_lib.s9s_mb_2u(sch_1):page494_i106@pure_quanta.q_cap(chips)';

PART_NAME
 C131 'Q_CAP_C0402-1UF,25V,10%,X6S,CHA':;

SECTION_NUMBER 1
 '@S9S_MB_2U_LIB.S9S_MB_2U(SCH_1):PAGE494_I103@PURE_QUANTA.Q_CAP(CHIPS)':
 C_PATH='@s9s_mb_2u_lib.s9s_mb_2u(sch_1):page494_i103@pure_quanta.q_cap(chips)';

PART_NAME
 C130 'Q_CAP_0402-0.1UF,25V,10%,X7R,CA':;

SECTION_NUMBER 1
 '@S9S_MB_2U_LIB.S9S_MB_2U(SCH_1):PAGE494_I56@PURE_QUANTA.Q_CAP(CHIPS)':
 C_PATH='@s9s_mb_2u_lib.s9s_mb_2u(sch_1):page494_i56@pure_quanta.q_cap(chips)';

PART_NAME
 C129 'Q_CAPP_SMLF-100UF,16V,20%,POSCA':;

SECTION_NUMBER 1
 '@S9S_MB_2U_LIB.S9S_MB_2U(SCH_1):PAGE494_I54@PURE_QUANTA.Q_CAPP(CHIPS)':
 C_PATH='@s9s_mb_2u_lib.s9s_mb_2u(sch_1):page494_i54@pure_quanta.q_capp(chips)';

PART_NAME
 C128 'Q_CAP_0402-0.1UF,25V,10%,X7R,CA':;

SECTION_NUMBER 1
 '@S9S_MB_2U_LIB.S9S_MB_2U(SCH_1):PAGE494_I52@PURE_QUANTA.Q_CAP(CHIPS)':
 C_PATH='@s9s_mb_2u_lib.s9s_mb_2u(sch_1):page494_i52@pure_quanta.q_cap(chips)';

PART_NAME
 C127 'Q_CAPP_SMLF-100UF,16V,20%,POSCA':;

SECTION_NUMBER 1
 '@S9S_MB_2U_LIB.S9S_MB_2U(SCH_1):PAGE494_I50@PURE_QUANTA.Q_CAPP(CHIPS)':
 C_PATH='@s9s_mb_2u_lib.s9s_mb_2u(sch_1):page494_i50@pure_quanta.q_capp(chips)';

PART_NAME
 R1572 'Q_RES_0402LF-10K,5%,1/16W,CHIPA':;

SECTION_NUMBER 1
 '@S9S_MB_2U_LIB.S9S_MB_2U(SCH_1):PAGE493_I310@PURE_QUANTA.Q_RES(CHIPS)':
 C_PATH='@s9s_mb_2u_lib.s9s_mb_2u(sch_1):page493_i310@pure_quanta.q_res(chips)';

PART_NAME
 R1571 'Q_RES_0402LF-10K,5%,1/16W,CHIPA':;

SECTION_NUMBER 1
 '@S9S_MB_2U_LIB.S9S_MB_2U(SCH_1):PAGE493_I312@PURE_QUANTA.Q_RES(CHIPS)':
 C_PATH='@s9s_mb_2u_lib.s9s_mb_2u(sch_1):page493_i312@pure_quanta.q_res(chips)';

PART_NAME
 R1570 'Q_RES_0402LF-100,1%,1/16W,CHIPA':;

SECTION_NUMBER 1
 '@S9S_MB_2U_LIB.S9S_MB_2U(SCH_1):PAGE493_I316@PURE_QUANTA.Q_RES(CHIPS)':
 C_PATH='@s9s_mb_2u_lib.s9s_mb_2u(sch_1):page493_i316@pure_quanta.q_res(chips)';

PART_NAME
 R1480 'Q_RES_0402LF-33.2,1%,1/16W,CHIA':;

SECTION_NUMBER 1
 '@S9S_MB_2U_LIB.S9S_MB_2U(SCH_1):PAGE493_I280@PURE_QUANTA.Q_RES(CHIPS)':
 C_PATH='@s9s_mb_2u_lib.s9s_mb_2u(sch_1):page493_i280@pure_quanta.q_res(chips)';

PART_NAME
 R639 'Q_RES_0402LF-4.7K,5%,1/16W,EMPA':;

SECTION_NUMBER 1
 '@S9S_MB_2U_LIB.S9S_MB_2U(SCH_1):PAGE493_I303@PURE_QUANTA.Q_RES(CHIPS)':
 C_PATH='@s9s_mb_2u_lib.s9s_mb_2u(sch_1):page493_i303@pure_quanta.q_res(chips)';

PART_NAME
 R638 'Q_RES_0402LF-4.7K,5%,1/16W,EMPA':;

SECTION_NUMBER 1
 '@S9S_MB_2U_LIB.S9S_MB_2U(SCH_1):PAGE493_I301@PURE_QUANTA.Q_RES(CHIPS)':
 C_PATH='@s9s_mb_2u_lib.s9s_mb_2u(sch_1):page493_i301@pure_quanta.q_res(chips)';

PART_NAME
 R637 'Q_RES_0402LF-4.7K,5%,1/16W,EMPA':;

SECTION_NUMBER 1
 '@S9S_MB_2U_LIB.S9S_MB_2U(SCH_1):PAGE493_I298@PURE_QUANTA.Q_RES(CHIPS)':
 C_PATH='@s9s_mb_2u_lib.s9s_mb_2u(sch_1):page493_i298@pure_quanta.q_res(chips)';

PART_NAME
 R636 'Q_RES_0402LF-4.7K,5%,1/16W,EMPA':;

SECTION_NUMBER 1
 '@S9S_MB_2U_LIB.S9S_MB_2U(SCH_1):PAGE493_I296@PURE_QUANTA.Q_RES(CHIPS)':
 C_PATH='@s9s_mb_2u_lib.s9s_mb_2u(sch_1):page493_i296@pure_quanta.q_res(chips)';

PART_NAME
 R390 'Q_RES_0402LF-0,5%,1/16W,CHIP,CA':;

SECTION_NUMBER 1
 '@S9S_MB_2U_LIB.S9S_MB_2U(SCH_1):PAGE493_I321@PURE_QUANTA.Q_RES(CHIPS)':
 C_PATH='@s9s_mb_2u_lib.s9s_mb_2u(sch_1):page493_i321@pure_quanta.q_res(chips)';

PART_NAME
 R387 'Q_RES_0402LF-10K,5%,1/16W,EMPTA':;

SECTION_NUMBER 1
 '@S9S_MB_2U_LIB.S9S_MB_2U(SCH_1):PAGE493_I322@PURE_QUANTA.Q_RES(CHIPS)':
 C_PATH='@s9s_mb_2u_lib.s9s_mb_2u(sch_1):page493_i322@pure_quanta.q_res(chips)';

PART_NAME
 R386 'Q_RES_0402LF-10K,5%,1/16W,CHIPA':;

SECTION_NUMBER 1
 '@S9S_MB_2U_LIB.S9S_MB_2U(SCH_1):PAGE493_I314@PURE_QUANTA.Q_RES(CHIPS)':
 C_PATH='@s9s_mb_2u_lib.s9s_mb_2u(sch_1):page493_i314@pure_quanta.q_res(chips)';

PART_NAME
 R384 'Q_RES_0402LF-10K,1%,1/16W,CHIPA':;

SECTION_NUMBER 1
 '@S9S_MB_2U_LIB.S9S_MB_2U(SCH_1):PAGE493_I190@PURE_QUANTA.Q_RES(CHIPS)':
 C_PATH='@s9s_mb_2u_lib.s9s_mb_2u(sch_1):page493_i190@pure_quanta.q_res(chips)';

PART_NAME
 R84 'Q_RES_0402LF-4.7K,5%,1/16W,EMPA':;

SECTION_NUMBER 1
 '@S9S_MB_2U_LIB.S9S_MB_2U(SCH_1):PAGE493_I294@PURE_QUANTA.Q_RES(CHIPS)':
 C_PATH='@s9s_mb_2u_lib.s9s_mb_2u(sch_1):page493_i294@pure_quanta.q_res(chips)';

PART_NAME
 J55 'SCONN140_ME1014010101011-SCONNA':;

SECTION_NUMBER 1
 '@S9S_MB_2U_LIB.S9S_MB_2U(SCH_1):PAGE493_I101@PURE_QUANTA.SCONN140_ME1014010101011(CHIPS)':
 C_PATH='@s9s_mb_2u_lib.s9s_mb_2u(sch_1):page493_i101@pure_quanta.sconn140_me10140~
10101011(chips)';

PART_NAME
 C126 'Q_CAP_0402-0.1UF,25V,10%,X7R,CA':;

SECTION_NUMBER 1
 '@S9S_MB_2U_LIB.S9S_MB_2U(SCH_1):PAGE493_I97@PURE_QUANTA.Q_CAP(CHIPS)':
 C_PATH='@s9s_mb_2u_lib.s9s_mb_2u(sch_1):page493_i97@pure_quanta.q_cap(chips)';

PART_NAME
 C125 'Q_CAP_C0402-1UF,25V,10%,X6S,CHA':;

SECTION_NUMBER 1
 '@S9S_MB_2U_LIB.S9S_MB_2U(SCH_1):PAGE493_I94@PURE_QUANTA.Q_CAP(CHIPS)':
 C_PATH='@s9s_mb_2u_lib.s9s_mb_2u(sch_1):page493_i94@pure_quanta.q_cap(chips)';

PART_NAME
 C124 'Q_CAP_0402-0.1UF,25V,10%,X7R,CA':;

SECTION_NUMBER 1
 '@S9S_MB_2U_LIB.S9S_MB_2U(SCH_1):PAGE493_I93@PURE_QUANTA.Q_CAP(CHIPS)':
 C_PATH='@s9s_mb_2u_lib.s9s_mb_2u(sch_1):page493_i93@pure_quanta.q_cap(chips)';

PART_NAME
 C123 'Q_CAPP_SMLF-220UF,6.3V,20%,OSCA':;

SECTION_NUMBER 1
 '@S9S_MB_2U_LIB.S9S_MB_2U(SCH_1):PAGE493_I98@PURE_QUANTA.Q_CAPP(CHIPS)':
 C_PATH='@s9s_mb_2u_lib.s9s_mb_2u(sch_1):page493_i98@pure_quanta.q_capp(chips)';

PART_NAME
 C122 'Q_CAP_0402-0.1UF,25V,10%,X7R,CA':;

SECTION_NUMBER 1
 '@S9S_MB_2U_LIB.S9S_MB_2U(SCH_1):PAGE493_I99@PURE_QUANTA.Q_CAP(CHIPS)':
 C_PATH='@s9s_mb_2u_lib.s9s_mb_2u(sch_1):page493_i99@pure_quanta.q_cap(chips)';

PART_NAME
 C121 'Q_CAPP_RDLLF-100UF,16V,20%,OSCA':;

SECTION_NUMBER 1
 '@S9S_MB_2U_LIB.S9S_MB_2U(SCH_1):PAGE493_I32@PURE_QUANTA.Q_CAPP(CHIPS)':
 C_PATH='@s9s_mb_2u_lib.s9s_mb_2u(sch_1):page493_i32@pure_quanta.q_capp(chips)';

PART_NAME
 Y2 'Q_XTAL_4P_13_SMLF-25MHZ,IC,BG6A':;

SECTION_NUMBER 1
 '@S9S_MB_2U_LIB.S9S_MB_2U(SCH_1):PAGE534_I185@PURE_QUANTA.Q_XTAL_4P_13(CHIPS)':
 C_PATH='@s9s_mb_2u_lib.s9s_mb_2u(sch_1):page534_i185@pure_quanta.q_xtal_4p_13(chi~
ps)';

PART_NAME
 U13 '9SQ440NQQI8-9SQ440NQQI8,SMLF,IA':;

SECTION_NUMBER 1
 '@S9S_MB_2U_LIB.S9S_MB_2U(SCH_1):PAGE534_I180@PURE_QUANTA.9SQ440NQQI8(CHIPS)':
 C_PATH='@s9s_mb_2u_lib.s9s_mb_2u(sch_1):page534_i180@pure_quanta.\9sq440nqqi8\(ch~
ips)';

SECTION_NUMBER 2
 '@S9S_MB_2U_LIB.S9S_MB_2U(SCH_1):PAGE534_I288@PURE_QUANTA.9SQ440NQQI8(CHIPS)':
 C_PATH='@s9s_mb_2u_lib.s9s_mb_2u(sch_1):page534_i288@pure_quanta.\9sq440nqqi8\(ch~
ips)';

PART_NAME
 R1724 'Q_RES_0402LF-0,5%,1/16W,CHIP,CA':;

SECTION_NUMBER 1
 '@S9S_MB_2U_LIB.S9S_MB_2U(SCH_1):PAGE534_I287@PURE_QUANTA.Q_RES(CHIPS)':
 C_PATH='@s9s_mb_2u_lib.s9s_mb_2u(sch_1):page534_i287@pure_quanta.q_res(chips)';

PART_NAME
 R1680 'Q_RES_0402LF-0,5%,1/16W,CHIP,CA':;

SECTION_NUMBER 1
 '@S9S_MB_2U_LIB.S9S_MB_2U(SCH_1):PAGE534_I252@PURE_QUANTA.Q_RES(CHIPS)':
 C_PATH='@s9s_mb_2u_lib.s9s_mb_2u(sch_1):page534_i252@pure_quanta.q_res(chips)';

PART_NAME
 R1527 'Q_RES_0402LF-1K,1%,1/16W,CHIP,A':;

SECTION_NUMBER 1
 '@S9S_MB_2U_LIB.S9S_MB_2U(SCH_1):PAGE534_I269@PURE_QUANTA.Q_RES(CHIPS)':
 C_PATH='@s9s_mb_2u_lib.s9s_mb_2u(sch_1):page534_i269@pure_quanta.q_res(chips)';

PART_NAME
 R1502 'Q_RES_0402LF-4.75K,1%,1/16W,CHA':;

SECTION_NUMBER 1
 '@S9S_MB_2U_LIB.S9S_MB_2U(SCH_1):PAGE534_I270@PURE_QUANTA.Q_RES(CHIPS)':
 C_PATH='@s9s_mb_2u_lib.s9s_mb_2u(sch_1):page534_i270@pure_quanta.q_res(chips)';

PART_NAME
 R1500 'Q_RES_0402LF-4.75K,1%,1/16W,CHA':;

SECTION_NUMBER 1
 '@S9S_MB_2U_LIB.S9S_MB_2U(SCH_1):PAGE534_I271@PURE_QUANTA.Q_RES(CHIPS)':
 C_PATH='@s9s_mb_2u_lib.s9s_mb_2u(sch_1):page534_i271@pure_quanta.q_res(chips)';

PART_NAME
 R1484 'Q_RES_0402LF-1K,1%,1/16W,EMPTYA':;

SECTION_NUMBER 1
 '@S9S_MB_2U_LIB.S9S_MB_2U(SCH_1):PAGE534_I268@PURE_QUANTA.Q_RES(CHIPS)':
 C_PATH='@s9s_mb_2u_lib.s9s_mb_2u(sch_1):page534_i268@pure_quanta.q_res(chips)';

PART_NAME
 R1483 'Q_RES_0402LF-10K,1%,1/16W,EMPTA':;

SECTION_NUMBER 1
 '@S9S_MB_2U_LIB.S9S_MB_2U(SCH_1):PAGE534_I265@PURE_QUANTA.Q_RES(CHIPS)':
 C_PATH='@s9s_mb_2u_lib.s9s_mb_2u(sch_1):page534_i265@pure_quanta.q_res(chips)';

PART_NAME
 R1471 'Q_RES_0402LF-4.75K,1%,1/16W,CHA':;

SECTION_NUMBER 1
 '@S9S_MB_2U_LIB.S9S_MB_2U(SCH_1):PAGE534_I267@PURE_QUANTA.Q_RES(CHIPS)':
 C_PATH='@s9s_mb_2u_lib.s9s_mb_2u(sch_1):page534_i267@pure_quanta.q_res(chips)';

PART_NAME
 R1462 'Q_RES_0402LF-1K,1%,1/16W,CHIP,A':;

SECTION_NUMBER 1
 '@S9S_MB_2U_LIB.S9S_MB_2U(SCH_1):PAGE534_I274@PURE_QUANTA.Q_RES(CHIPS)':
 C_PATH='@s9s_mb_2u_lib.s9s_mb_2u(sch_1):page534_i274@pure_quanta.q_res(chips)';

PART_NAME
 R1390 'Q_RES_0402LF-1K,1%,1/16W,EMPTYA':;

SECTION_NUMBER 1
 '@S9S_MB_2U_LIB.S9S_MB_2U(SCH_1):PAGE534_I275@PURE_QUANTA.Q_RES(CHIPS)':
 C_PATH='@s9s_mb_2u_lib.s9s_mb_2u(sch_1):page534_i275@pure_quanta.q_res(chips)';

PART_NAME
 R1305 'Q_RES_0402LF-10K,1%,1/16W,EMPTA':;

SECTION_NUMBER 1
 '@S9S_MB_2U_LIB.S9S_MB_2U(SCH_1):PAGE534_I272@PURE_QUANTA.Q_RES(CHIPS)':
 C_PATH='@s9s_mb_2u_lib.s9s_mb_2u(sch_1):page534_i272@pure_quanta.q_res(chips)';

PART_NAME
 R1267 'Q_RES_0402LF-1K,1%,1/16W,CHIP,A':;

SECTION_NUMBER 1
 '@S9S_MB_2U_LIB.S9S_MB_2U(SCH_1):PAGE534_I276@PURE_QUANTA.Q_RES(CHIPS)':
 C_PATH='@s9s_mb_2u_lib.s9s_mb_2u(sch_1):page534_i276@pure_quanta.q_res(chips)';

PART_NAME
 R1204 'Q_RES_0402LF-10K,1%,1/16W,EMPTA':;

SECTION_NUMBER 1
 '@S9S_MB_2U_LIB.S9S_MB_2U(SCH_1):PAGE534_I273@PURE_QUANTA.Q_RES(CHIPS)':
 C_PATH='@s9s_mb_2u_lib.s9s_mb_2u(sch_1):page534_i273@pure_quanta.q_res(chips)';

PART_NAME
 R1196 'Q_RES_0402LF-4.75K,1%,1/16W,CHA':;

SECTION_NUMBER 1
 '@S9S_MB_2U_LIB.S9S_MB_2U(SCH_1):PAGE534_I281@PURE_QUANTA.Q_RES(CHIPS)':
 C_PATH='@s9s_mb_2u_lib.s9s_mb_2u(sch_1):page534_i281@pure_quanta.q_res(chips)';

PART_NAME
 R1194 'Q_RES_0402LF-4.75K,1%,1/16W,EMA':;

SECTION_NUMBER 1
 '@S9S_MB_2U_LIB.S9S_MB_2U(SCH_1):PAGE534_I277@PURE_QUANTA.Q_RES(CHIPS)':
 C_PATH='@s9s_mb_2u_lib.s9s_mb_2u(sch_1):page534_i277@pure_quanta.q_res(chips)';

PART_NAME
 R953 'Q_RES_0402LF-4.75K,1%,1/16W,CHA':;

SECTION_NUMBER 1
 '@S9S_MB_2U_LIB.S9S_MB_2U(SCH_1):PAGE534_I282@PURE_QUANTA.Q_RES(CHIPS)':
 C_PATH='@s9s_mb_2u_lib.s9s_mb_2u(sch_1):page534_i282@pure_quanta.q_res(chips)';

PART_NAME
 R912 'Q_RES_0402LF-4.75K,1%,1/16W,EMA':;

SECTION_NUMBER 1
 '@S9S_MB_2U_LIB.S9S_MB_2U(SCH_1):PAGE534_I278@PURE_QUANTA.Q_RES(CHIPS)':
 C_PATH='@s9s_mb_2u_lib.s9s_mb_2u(sch_1):page534_i278@pure_quanta.q_res(chips)';

PART_NAME
 R734 'Q_RES_0402LF-4.75K,1%,1/16W,CHA':;

SECTION_NUMBER 1
 '@S9S_MB_2U_LIB.S9S_MB_2U(SCH_1):PAGE534_I283@PURE_QUANTA.Q_RES(CHIPS)':
 C_PATH='@s9s_mb_2u_lib.s9s_mb_2u(sch_1):page534_i283@pure_quanta.q_res(chips)';

PART_NAME
 R562 'Q_RES_0402LF-4.75K,1%,1/16W,EMA':;

SECTION_NUMBER 1
 '@S9S_MB_2U_LIB.S9S_MB_2U(SCH_1):PAGE534_I280@PURE_QUANTA.Q_RES(CHIPS)':
 C_PATH='@s9s_mb_2u_lib.s9s_mb_2u(sch_1):page534_i280@pure_quanta.q_res(chips)';

PART_NAME
 C1324 'Q_CAP_0402-0.1UF,25V,10%,EMPTYA':;

SECTION_NUMBER 1
 '@S9S_MB_2U_LIB.S9S_MB_2U(SCH_1):PAGE534_I286@PURE_QUANTA.Q_CAP(CHIPS)':
 C_PATH='@s9s_mb_2u_lib.s9s_mb_2u(sch_1):page534_i286@pure_quanta.q_cap(chips)';

PART_NAME
 C118 'Q_CAP_0402-15PF,50V,5%,C0G,CH0A':;

SECTION_NUMBER 1
 '@S9S_MB_2U_LIB.S9S_MB_2U(SCH_1):PAGE534_I183@PURE_QUANTA.Q_CAP(CHIPS)':
 C_PATH='@s9s_mb_2u_lib.s9s_mb_2u(sch_1):page534_i183@pure_quanta.q_cap(chips)';

PART_NAME
 C113 'Q_CAP_0402-15PF,50V,5%,C0G,CH0A':;

SECTION_NUMBER 1
 '@S9S_MB_2U_LIB.S9S_MB_2U(SCH_1):PAGE534_I186@PURE_QUANTA.Q_CAP(CHIPS)':
 C_PATH='@s9s_mb_2u_lib.s9s_mb_2u(sch_1):page534_i186@pure_quanta.q_cap(chips)';

PART_NAME
 R519 'Q_RES_0603LF-1,1%,1/10W,CHIP,CA':;

SECTION_NUMBER 1
 '@S9S_MB_2U_LIB.S9S_MB_2U(SCH_1):PAGE536_I7@PURE_QUANTA.Q_RES(CHIPS)':
 C_PATH='@s9s_mb_2u_lib.s9s_mb_2u(sch_1):page536_i7@pure_quanta.q_res(chips)';

PART_NAME
 R447 'Q_RES_0603LF-1,1%,1/10W,CHIP,CA':;

SECTION_NUMBER 1
 '@S9S_MB_2U_LIB.S9S_MB_2U(SCH_1):PAGE536_I55@PURE_QUANTA.Q_RES(CHIPS)':
 C_PATH='@s9s_mb_2u_lib.s9s_mb_2u(sch_1):page536_i55@pure_quanta.q_res(chips)';

PART_NAME
 R442 'Q_RES_0603LF-1,1%,1/10W,CHIP,CA':;

SECTION_NUMBER 1
 '@S9S_MB_2U_LIB.S9S_MB_2U(SCH_1):PAGE536_I36@PURE_QUANTA.Q_RES(CHIPS)':
 C_PATH='@s9s_mb_2u_lib.s9s_mb_2u(sch_1):page536_i36@pure_quanta.q_res(chips)';

PART_NAME
 L14 'Q_INDUCTOR_SMLF-BLM21AG601SN1DA':;

SECTION_NUMBER 1
 '@S9S_MB_2U_LIB.S9S_MB_2U(SCH_1):PAGE536_I60@PURE_QUANTA.Q_INDUCTOR(CHIPS)':
 C_PATH='@s9s_mb_a_lib.s9s_mb_a(sch_1):page536_i60@pure_quanta.q_inductor(chips)~
';

PART_NAME
 L13 'Q_INDUCTOR_SMLF-BLM21AG601SN1DA':;

SECTION_NUMBER 1
 '@S9S_MB_2U_LIB.S9S_MB_2U(SCH_1):PAGE536_I41@PURE_QUANTA.Q_INDUCTOR(CHIPS)':
 C_PATH='@s9s_mb_a_lib.s9s_mb_a(sch_1):page536_i41@pure_quanta.q_inductor(chips)~
';

PART_NAME
 L1 'Q_INDUCTOR_SMLF-BLM21AG601SN1DA':;

SECTION_NUMBER 1
 '@S9S_MB_2U_LIB.S9S_MB_2U(SCH_1):PAGE536_I20@PURE_QUANTA.Q_INDUCTOR(CHIPS)':
 C_PATH='@s9s_mb_a_lib.s9s_mb_a(sch_1):page536_i20@pure_quanta.q_inductor(chips)~
';

PART_NAME
 C1314 'Q_CAP_C0603-10UF,6.3V,20%,X6S,A':;

SECTION_NUMBER 1
 '@S9S_MB_2U_LIB.S9S_MB_2U(SCH_1):PAGE536_I53@PURE_QUANTA.Q_CAP(CHIPS)':
 C_PATH='@s9s_mb_2u_lib.s9s_mb_2u(sch_1):page536_i53@pure_quanta.q_cap(chips)';

PART_NAME
 C1313 'Q_CAP_C0603-10UF,6.3V,20%,X6S,A':;

SECTION_NUMBER 1
 '@S9S_MB_2U_LIB.S9S_MB_2U(SCH_1):PAGE536_I48@PURE_QUANTA.Q_CAP(CHIPS)':
 C_PATH='@s9s_mb_2u_lib.s9s_mb_2u(sch_1):page536_i48@pure_quanta.q_cap(chips)';

PART_NAME
 C1312 'Q_CAP_C0402-1UF,25V,10%,X6S,CHA':;

SECTION_NUMBER 1
 '@S9S_MB_2U_LIB.S9S_MB_2U(SCH_1):PAGE536_I58@PURE_QUANTA.Q_CAP(CHIPS)':
 C_PATH='@s9s_mb_2u_lib.s9s_mb_2u(sch_1):page536_i58@pure_quanta.q_cap(chips)';

PART_NAME
 C1311 'Q_CAP_C0402-1UF,25V,10%,X6S,CHA':;

SECTION_NUMBER 1
 '@S9S_MB_2U_LIB.S9S_MB_2U(SCH_1):PAGE536_I43@PURE_QUANTA.Q_CAP(CHIPS)':
 C_PATH='@s9s_mb_2u_lib.s9s_mb_2u(sch_1):page536_i43@pure_quanta.q_cap(chips)';

PART_NAME
 C1310 'Q_CAP_C0603-10UF,6.3V,20%,X6S,A':;

SECTION_NUMBER 1
 '@S9S_MB_2U_LIB.S9S_MB_2U(SCH_1):PAGE536_I59@PURE_QUANTA.Q_CAP(CHIPS)':
 C_PATH='@s9s_mb_2u_lib.s9s_mb_2u(sch_1):page536_i59@pure_quanta.q_cap(chips)';

PART_NAME
 C1309 'Q_CAP_C0603-10UF,6.3V,20%,X6S,A':;

SECTION_NUMBER 1
 '@S9S_MB_2U_LIB.S9S_MB_2U(SCH_1):PAGE536_I44@PURE_QUANTA.Q_CAP(CHIPS)':
 C_PATH='@s9s_mb_2u_lib.s9s_mb_2u(sch_1):page536_i44@pure_quanta.q_cap(chips)';

PART_NAME
 C173 'Q_CAP_0402-0.1UF,25V,10%,X7R,CA':;

SECTION_NUMBER 1
 '@S9S_MB_2U_LIB.S9S_MB_2U(SCH_1):PAGE536_I4@PURE_QUANTA.Q_CAP(CHIPS)':
 C_PATH='@s9s_mb_2u_lib.s9s_mb_2u(sch_1):page536_i4@pure_quanta.q_cap(chips)';

PART_NAME
 C172 'Q_CAP_C0603-10UF,6.3V,20%,X6S,A':;

SECTION_NUMBER 1
 '@S9S_MB_2U_LIB.S9S_MB_2U(SCH_1):PAGE536_I6@PURE_QUANTA.Q_CAP(CHIPS)':
 C_PATH='@s9s_mb_2u_lib.s9s_mb_2u(sch_1):page536_i6@pure_quanta.q_cap(chips)';

PART_NAME
 C171 'Q_CAP_0402-0.1UF,25V,10%,X7R,CA':;

SECTION_NUMBER 1
 '@S9S_MB_2U_LIB.S9S_MB_2U(SCH_1):PAGE536_I2@PURE_QUANTA.Q_CAP(CHIPS)':
 C_PATH='@s9s_mb_2u_lib.s9s_mb_2u(sch_1):page536_i2@pure_quanta.q_cap(chips)';

PART_NAME
 C120 'Q_CAP_0402-0.1UF,25V,10%,X7R,CA':;

SECTION_NUMBER 1
 '@S9S_MB_2U_LIB.S9S_MB_2U(SCH_1):PAGE536_I68@PURE_QUANTA.Q_CAP(CHIPS)':
 C_PATH='@s9s_mb_2u_lib.s9s_mb_2u(sch_1):page536_i68@pure_quanta.q_cap(chips)';

PART_NAME
 C119 'Q_CAP_0402-0.1UF,25V,10%,X7R,CA':;

SECTION_NUMBER 1
 '@S9S_MB_2U_LIB.S9S_MB_2U(SCH_1):PAGE536_I67@PURE_QUANTA.Q_CAP(CHIPS)':
 C_PATH='@s9s_mb_2u_lib.s9s_mb_2u(sch_1):page536_i67@pure_quanta.q_cap(chips)';

PART_NAME
 C117 'Q_CAP_0402-0.1UF,25V,10%,X7R,CA':;

SECTION_NUMBER 1
 '@S9S_MB_2U_LIB.S9S_MB_2U(SCH_1):PAGE536_I64@PURE_QUANTA.Q_CAP(CHIPS)':
 C_PATH='@s9s_mb_2u_lib.s9s_mb_2u(sch_1):page536_i64@pure_quanta.q_cap(chips)';

PART_NAME
 C116 'Q_CAP_0402-0.1UF,25V,10%,X7R,CA':;

SECTION_NUMBER 1
 '@S9S_MB_2U_LIB.S9S_MB_2U(SCH_1):PAGE536_I65@PURE_QUANTA.Q_CAP(CHIPS)':
 C_PATH='@s9s_mb_2u_lib.s9s_mb_2u(sch_1):page536_i65@pure_quanta.q_cap(chips)';

PART_NAME
 C115 'Q_CAP_0402-0.1UF,25V,10%,X7R,CA':;

SECTION_NUMBER 1
 '@S9S_MB_2U_LIB.S9S_MB_2U(SCH_1):PAGE536_I66@PURE_QUANTA.Q_CAP(CHIPS)':
 C_PATH='@s9s_mb_2u_lib.s9s_mb_2u(sch_1):page536_i66@pure_quanta.q_cap(chips)';

PART_NAME
 C114 'Q_CAP_0402-0.1UF,25V,10%,X7R,CA':;

SECTION_NUMBER 1
 '@S9S_MB_2U_LIB.S9S_MB_2U(SCH_1):PAGE536_I47@PURE_QUANTA.Q_CAP(CHIPS)':
 C_PATH='@s9s_mb_2u_lib.s9s_mb_2u(sch_1):page536_i47@pure_quanta.q_cap(chips)';

PART_NAME
 C112 'Q_CAP_0402-0.1UF,25V,10%,X7R,CA':;

SECTION_NUMBER 1
 '@S9S_MB_2U_LIB.S9S_MB_2U(SCH_1):PAGE536_I45@PURE_QUANTA.Q_CAP(CHIPS)':
 C_PATH='@s9s_mb_2u_lib.s9s_mb_2u(sch_1):page536_i45@pure_quanta.q_cap(chips)';

PART_NAME
 C111 'Q_CAP_0402-0.1UF,25V,10%,X7R,CA':;

SECTION_NUMBER 1
 '@S9S_MB_2U_LIB.S9S_MB_2U(SCH_1):PAGE536_I46@PURE_QUANTA.Q_CAP(CHIPS)':
 C_PATH='@s9s_mb_2u_lib.s9s_mb_2u(sch_1):page536_i46@pure_quanta.q_cap(chips)';

PART_NAME
 C110 'Q_CAP_0402-0.1UF,25V,10%,X7R,CA':;

SECTION_NUMBER 1
 '@S9S_MB_2U_LIB.S9S_MB_2U(SCH_1):PAGE536_I17@PURE_QUANTA.Q_CAP(CHIPS)':
 C_PATH='@s9s_mb_2u_lib.s9s_mb_2u(sch_1):page536_i17@pure_quanta.q_cap(chips)';

PART_NAME
 C109 'Q_CAP_C0402-1UF,25V,10%,X6S,CHA':;

SECTION_NUMBER 1
 '@S9S_MB_2U_LIB.S9S_MB_2U(SCH_1):PAGE536_I18@PURE_QUANTA.Q_CAP(CHIPS)':
 C_PATH='@s9s_mb_2u_lib.s9s_mb_2u(sch_1):page536_i18@pure_quanta.q_cap(chips)';

PART_NAME
 C108 'Q_CAP_C0603-10UF,6.3V,20%,X6S,A':;

SECTION_NUMBER 1
 '@S9S_MB_2U_LIB.S9S_MB_2U(SCH_1):PAGE536_I19@PURE_QUANTA.Q_CAP(CHIPS)':
 C_PATH='@s9s_mb_2u_lib.s9s_mb_2u(sch_1):page536_i19@pure_quanta.q_cap(chips)';

PART_NAME
 U7 '74LVC1G07GV-74LVC1G07GV,SMLF,IA':;

SECTION_NUMBER 1
 '@S9S_MB_2U_LIB.S9S_MB_2U(SCH_1):PAGE485_I43@PURE_QUANTA.74LVC1G07GV(CHIPS)':
 C_PATH='@s9s_mb_2u_lib.s9s_mb_2u(sch_1):page485_i43@pure_quanta.\74lvc1g07gv\(chi~
ps)';

PART_NAME
 R198 'Q_RES_0402LF-10K,1%,1/16W,EMPTA':;

SECTION_NUMBER 1
 '@S9S_MB_2U_LIB.S9S_MB_2U(SCH_1):PAGE485_I54@PURE_QUANTA.Q_RES(CHIPS)':
 C_PATH='@s9s_mb_2u_lib.s9s_mb_2u(sch_1):page485_i54@pure_quanta.q_res(chips)';

PART_NAME
 R197 'Q_RES_0402LF-10K,1%,1/16W,EMPTA':;

SECTION_NUMBER 1
 '@S9S_MB_2U_LIB.S9S_MB_2U(SCH_1):PAGE485_I53@PURE_QUANTA.Q_RES(CHIPS)':
 C_PATH='@s9s_mb_2u_lib.s9s_mb_2u(sch_1):page485_i53@pure_quanta.q_res(chips)';

PART_NAME
 R196 'Q_RES_0402LF-49.9     ,1%  ,1/A':;

SECTION_NUMBER 1
 '@S9S_MB_2U_LIB.S9S_MB_2U(SCH_1):PAGE485_I57@PURE_QUANTA.Q_RES(CHIPS)':
 C_PATH='@s9s_mb_2u_lib.s9s_mb_2u(sch_1):page485_i57@pure_quanta.q_res(chips)';

PART_NAME
 R195 'Q_RES_0402LF-49.9     ,1%  ,1/A':;

SECTION_NUMBER 1
 '@S9S_MB_2U_LIB.S9S_MB_2U(SCH_1):PAGE485_I49@PURE_QUANTA.Q_RES(CHIPS)':
 C_PATH='@s9s_mb_2u_lib.s9s_mb_2u(sch_1):page485_i49@pure_quanta.q_res(chips)';

PART_NAME
 R194 'Q_RES_0402LF-301,1%,1/16W,CHIPA':;

SECTION_NUMBER 1
 '@S9S_MB_2U_LIB.S9S_MB_2U(SCH_1):PAGE485_I66@PURE_QUANTA.Q_RES(CHIPS)':
 C_PATH='@s9s_mb_2u_lib.s9s_mb_2u(sch_1):page485_i66@pure_quanta.q_res(chips)';

PART_NAME
 R193 'Q_RES_0402LF-0,5%,1/16W,EMPTY,A':;

SECTION_NUMBER 1
 '@S9S_MB_2U_LIB.S9S_MB_2U(SCH_1):PAGE485_I44@PURE_QUANTA.Q_RES(CHIPS)':
 C_PATH='@s9s_mb_2u_lib.s9s_mb_2u(sch_1):page485_i44@pure_quanta.q_res(chips)';

PART_NAME
 R192 'Q_RES_0402LF-301,1%,1/16W,CHIPA':;

SECTION_NUMBER 1
 '@S9S_MB_2U_LIB.S9S_MB_2U(SCH_1):PAGE485_I64@PURE_QUANTA.Q_RES(CHIPS)':
 C_PATH='@s9s_mb_2u_lib.s9s_mb_2u(sch_1):page485_i64@pure_quanta.q_res(chips)';

PART_NAME
 R191 'Q_RES_0402LF-0,5%,1/16W,CHIP,CA':;

SECTION_NUMBER 1
 '@S9S_MB_2U_LIB.S9S_MB_2U(SCH_1):PAGE485_I61@PURE_QUANTA.Q_RES(CHIPS)':
 C_PATH='@s9s_mb_2u_lib.s9s_mb_2u(sch_1):page485_i61@pure_quanta.q_res(chips)';

PART_NAME
 R190 'Q_RES_0402LF-0,5%,1/16W,CHIP,CA':;

SECTION_NUMBER 1
 '@S9S_MB_2U_LIB.S9S_MB_2U(SCH_1):PAGE485_I60@PURE_QUANTA.Q_RES(CHIPS)':
 C_PATH='@s9s_mb_2u_lib.s9s_mb_2u(sch_1):page485_i60@pure_quanta.q_res(chips)';

PART_NAME
 R189 'Q_RES_1206LF-10K,1%,1/4W,CHIP,A':;

SECTION_NUMBER 1
 '@S9S_MB_2U_LIB.S9S_MB_2U(SCH_1):PAGE485_I50@PURE_QUANTA.Q_RES(CHIPS)':
 C_PATH='@s9s_mb_2u_lib.s9s_mb_2u(sch_1):page485_i50@pure_quanta.q_res(chips)';

PART_NAME
 R188 'Q_RES_0402LF-0,5%,1/16W,CHIP,CA':;

SECTION_NUMBER 1
 '@S9S_MB_2U_LIB.S9S_MB_2U(SCH_1):PAGE485_I8@PURE_QUANTA.Q_RES(CHIPS)':
 C_PATH='@s9s_mb_2u_lib.s9s_mb_2u(sch_1):page485_i8@pure_quanta.q_res(chips)';

PART_NAME
 R187 'Q_RES_0402LF-0,5%,1/16W,EMPTY,A':;

SECTION_NUMBER 1
 '@S9S_MB_2U_LIB.S9S_MB_2U(SCH_1):PAGE485_I9@PURE_QUANTA.Q_RES(CHIPS)':
 C_PATH='@s9s_mb_2u_lib.s9s_mb_2u(sch_1):page485_i9@pure_quanta.q_res(chips)';

PART_NAME
 C105 'Q_CAP_0402-0.1UF,25V,10%,X7R,CA':;

SECTION_NUMBER 1
 '@S9S_MB_2U_LIB.S9S_MB_2U(SCH_1):PAGE485_I58@PURE_QUANTA.Q_CAP(CHIPS)':
 C_PATH='@s9s_mb_2u_lib.s9s_mb_2u(sch_1):page485_i58@pure_quanta.q_cap(chips)';

PART_NAME
 Y3 'Q_XTAL_4P_13BI_24GND-25MHZ,SMLA':;

SECTION_NUMBER 1
 '@S9S_MB_2U_LIB.S9S_MB_2U(SCH_1):PAGE515_I75@PURE_QUANTA.Q_XTAL_4P_13BI_24GND(CHIPS)':
 C_PATH='@s9s_mb_2u_lib.s9s_mb_2u(sch_1):page515_i75@pure_quanta.q_xtal_4p_13bi_24~
gnd(chips)';

PART_NAME
 Y1 'Q_CRYSTAL_SMLF-32.768KHZ,IC,BGA':;

SECTION_NUMBER 1
 '@S9S_MB_2U_LIB.S9S_MB_2U(SCH_1):PAGE515_I11@PURE_QUANTA.Q_CRYSTAL(CHIPS)':
 C_PATH='@s9s_mb_2u_lib.s9s_mb_2u(sch_1):page515_i11@pure_quanta.q_crystal(chips)';

PART_NAME
 R1721 'Q_RES_0402LF-0,5%,1/16W,CHIP,CA':;

SECTION_NUMBER 1
 '@S9S_MB_2U_LIB.S9S_MB_2U(SCH_1):PAGE515_I104@PURE_QUANTA.Q_RES(CHIPS)':
 C_PATH='@s9s_mb_2u_lib.s9s_mb_2u(sch_1):page515_i104@pure_quanta.q_res(chips)';

PART_NAME
 R1720 'Q_RES_0402LF-0,5%,1/16W,CHIP,CA':;

SECTION_NUMBER 1
 '@S9S_MB_2U_LIB.S9S_MB_2U(SCH_1):PAGE515_I103@PURE_QUANTA.Q_RES(CHIPS)':
 C_PATH='@s9s_mb_2u_lib.s9s_mb_2u(sch_1):page515_i103@pure_quanta.q_res(chips)';

PART_NAME
 R1316 'Q_RES_0603LF-200K,0.1%,1/10W,CA':;

SECTION_NUMBER 1
 '@S9S_MB_2U_LIB.S9S_MB_2U(SCH_1):PAGE515_I92@PURE_QUANTA.Q_RES(CHIPS)':
 C_PATH='@s9s_mb_2u_lib.s9s_mb_2u(sch_1):page515_i92@pure_quanta.q_res(chips)';

PART_NAME
 R477 'Q_RES_0402LF-60.4,1%,1/16W,CHIA':;

SECTION_NUMBER 1
 '@S9S_MB_2U_LIB.S9S_MB_2U(SCH_1):PAGE515_I69@PURE_QUANTA.Q_RES(CHIPS)':
 C_PATH='@s9s_mb_2u_lib.s9s_mb_2u(sch_1):page515_i69@pure_quanta.q_res(chips)';

PART_NAME
 R120 'Q_RES_0603LF-10M,1%,1/10W,CHIPA':;

SECTION_NUMBER 1
 '@S9S_MB_2U_LIB.S9S_MB_2U(SCH_1):PAGE515_I74@PURE_QUANTA.Q_RES(CHIPS)':
 C_PATH='@s9s_mb_2u_lib.s9s_mb_2u(sch_1):page515_i74@pure_quanta.q_res(chips)';

PART_NAME
 C1508 'Q_CAP_0402-27PF  ,50V ,5% ,NPOA':;

SECTION_NUMBER 1
 '@S9S_MB_2U_LIB.S9S_MB_2U(SCH_1):PAGE515_I17@PURE_QUANTA.Q_CAP(CHIPS)':
 C_PATH='@s9s_mb_2u_lib.s9s_mb_2u(sch_1):page515_i17@pure_quanta.q_cap(chips)';

PART_NAME
 C1507 'Q_CAP_0402-27PF  ,50V ,5% ,NPOA':;

SECTION_NUMBER 1
 '@S9S_MB_2U_LIB.S9S_MB_2U(SCH_1):PAGE515_I10@PURE_QUANTA.Q_CAP(CHIPS)':
 C_PATH='@s9s_mb_2u_lib.s9s_mb_2u(sch_1):page515_i10@pure_quanta.q_cap(chips)';

PART_NAME
 C609 'Q_CAP_0402-0.1UF,25V,10%,X7R,CA':;

SECTION_NUMBER 1
 '@S9S_MB_2U_LIB.S9S_MB_2U(SCH_1):PAGE515_I89@PURE_QUANTA.Q_CAP(CHIPS)':
 C_PATH='@s9s_mb_2u_lib.s9s_mb_2u(sch_1):page515_i89@pure_quanta.q_cap(chips)';

PART_NAME
 C104 'Q_CAP_0402-27PF  ,50V ,5% ,NPOA':;

SECTION_NUMBER 1
 '@S9S_MB_2U_LIB.S9S_MB_2U(SCH_1):PAGE515_I76@PURE_QUANTA.Q_CAP(CHIPS)':
 C_PATH='@s9s_mb_2u_lib.s9s_mb_2u(sch_1):page515_i76@pure_quanta.q_cap(chips)';

PART_NAME
 C103 'Q_CAP_0402-27PF  ,50V ,5% ,NPOA':;

SECTION_NUMBER 1
 '@S9S_MB_2U_LIB.S9S_MB_2U(SCH_1):PAGE515_I77@PURE_QUANTA.Q_CAP(CHIPS)':
 C_PATH='@s9s_mb_2u_lib.s9s_mb_2u(sch_1):page515_i77@pure_quanta.q_cap(chips)';

PART_NAME
 U11 'GTL2014PW-GTL2014PW,SMLF,IC,ALA':;

SECTION_NUMBER 1
 '@S9S_MB_2U_LIB.S9S_MB_2U(SCH_1):PAGE478_I30@PURE_QUANTA.GTL2014PW(CHIPS)':
 C_PATH='@s9s_mb_2u_lib.s9s_mb_2u(sch_1):page478_i30@pure_quanta.gtl2014pw(chips)';

PART_NAME
 R364 'Q_RES_0402LF-33,5%,1/16W,EMPTYA':;

SECTION_NUMBER 1
 '@S9S_MB_2U_LIB.S9S_MB_2U(SCH_1):PAGE478_I88@PURE_QUANTA.Q_RES(CHIPS)':
 C_PATH='@s9s_mb_2u_lib.s9s_mb_2u(sch_1):page478_i88@pure_quanta.q_res(chips)';

PART_NAME
 R363 'Q_RES_0402LF-33,5%,1/16W,EMPTYA':;

SECTION_NUMBER 1
 '@S9S_MB_2U_LIB.S9S_MB_2U(SCH_1):PAGE478_I85@PURE_QUANTA.Q_RES(CHIPS)':
 C_PATH='@s9s_mb_2u_lib.s9s_mb_2u(sch_1):page478_i85@pure_quanta.q_res(chips)';

PART_NAME
 R362 'Q_RES_0402LF-33,5%,1/16W,EMPTYA':;

SECTION_NUMBER 1
 '@S9S_MB_2U_LIB.S9S_MB_2U(SCH_1):PAGE478_I81@PURE_QUANTA.Q_RES(CHIPS)':
 C_PATH='@s9s_mb_2u_lib.s9s_mb_2u(sch_1):page478_i81@pure_quanta.q_res(chips)';

PART_NAME
 R361 'Q_RES_0402LF-33,5%,1/16W,EMPTYA':;

SECTION_NUMBER 1
 '@S9S_MB_2U_LIB.S9S_MB_2U(SCH_1):PAGE478_I84@PURE_QUANTA.Q_RES(CHIPS)':
 C_PATH='@s9s_mb_2u_lib.s9s_mb_2u(sch_1):page478_i84@pure_quanta.q_res(chips)';

PART_NAME
 R360 'Q_RES_0402LF-33,5%,1/16W,EMPTYA':;

SECTION_NUMBER 1
 '@S9S_MB_2U_LIB.S9S_MB_2U(SCH_1):PAGE478_I75@PURE_QUANTA.Q_RES(CHIPS)':
 C_PATH='@s9s_mb_2u_lib.s9s_mb_2u(sch_1):page478_i75@pure_quanta.q_res(chips)';

PART_NAME
 R359 'Q_RES_0402LF-33,5%,1/16W,EMPTYA':;

SECTION_NUMBER 1
 '@S9S_MB_2U_LIB.S9S_MB_2U(SCH_1):PAGE478_I67@PURE_QUANTA.Q_RES(CHIPS)':
 C_PATH='@s9s_mb_2u_lib.s9s_mb_2u(sch_1):page478_i67@pure_quanta.q_res(chips)';

PART_NAME
 R358 'Q_RES_0402LF-33,5%,1/16W,CHIP,A':;

SECTION_NUMBER 1
 '@S9S_MB_2U_LIB.S9S_MB_2U(SCH_1):PAGE478_I80@PURE_QUANTA.Q_RES(CHIPS)':
 C_PATH='@s9s_mb_2u_lib.s9s_mb_2u(sch_1):page478_i80@pure_quanta.q_res(chips)';

PART_NAME
 R357 'Q_RES_0402LF-33,5%,1/16W,CHIP,A':;

SECTION_NUMBER 1
 '@S9S_MB_2U_LIB.S9S_MB_2U(SCH_1):PAGE478_I68@PURE_QUANTA.Q_RES(CHIPS)':
 C_PATH='@s9s_mb_2u_lib.s9s_mb_2u(sch_1):page478_i68@pure_quanta.q_res(chips)';

PART_NAME
 R356 'Q_RES_0402LF-33,5%,1/16W,CHIP,A':;

SECTION_NUMBER 1
 '@S9S_MB_2U_LIB.S9S_MB_2U(SCH_1):PAGE478_I79@PURE_QUANTA.Q_RES(CHIPS)':
 C_PATH='@s9s_mb_2u_lib.s9s_mb_2u(sch_1):page478_i79@pure_quanta.q_res(chips)';

PART_NAME
 R355 'Q_RES_0402LF-1K,1%,1/16W,CHIP,A':;

SECTION_NUMBER 1
 '@S9S_MB_2U_LIB.S9S_MB_2U(SCH_1):PAGE478_I73@PURE_QUANTA.Q_RES(CHIPS)':
 C_PATH='@s9s_mb_2u_lib.s9s_mb_2u(sch_1):page478_i73@pure_quanta.q_res(chips)';

PART_NAME
 R354 'Q_RES_0402LF-4.32K,1%,1/16W,CHA':;

SECTION_NUMBER 1
 '@S9S_MB_2U_LIB.S9S_MB_2U(SCH_1):PAGE478_I71@PURE_QUANTA.Q_RES(CHIPS)':
 C_PATH='@s9s_mb_2u_lib.s9s_mb_2u(sch_1):page478_i71@pure_quanta.q_res(chips)';

PART_NAME
 R353 'Q_RES_0402LF-150,1%,1/16W,CHIPA':;

SECTION_NUMBER 1
 '@S9S_MB_2U_LIB.S9S_MB_2U(SCH_1):PAGE478_I61@PURE_QUANTA.Q_RES(CHIPS)':
 C_PATH='@s9s_mb_2u_lib.s9s_mb_2u(sch_1):page478_i61@pure_quanta.q_res(chips)';

PART_NAME
 R352 'Q_RES_0402LF-150,1%,1/16W,CHIPA':;

SECTION_NUMBER 1
 '@S9S_MB_2U_LIB.S9S_MB_2U(SCH_1):PAGE478_I62@PURE_QUANTA.Q_RES(CHIPS)':
 C_PATH='@s9s_mb_2u_lib.s9s_mb_2u(sch_1):page478_i62@pure_quanta.q_res(chips)';

PART_NAME
 R351 'Q_RES_0402LF-150,1%,1/16W,CHIPA':;

SECTION_NUMBER 1
 '@S9S_MB_2U_LIB.S9S_MB_2U(SCH_1):PAGE478_I63@PURE_QUANTA.Q_RES(CHIPS)':
 C_PATH='@s9s_mb_2u_lib.s9s_mb_2u(sch_1):page478_i63@pure_quanta.q_res(chips)';

PART_NAME
 R350 'Q_RES_0402LF-0,5%,1/16W,EMPTY,A':;

SECTION_NUMBER 1
 '@S9S_MB_2U_LIB.S9S_MB_2U(SCH_1):PAGE478_I40@PURE_QUANTA.Q_RES(CHIPS)':
 C_PATH='@s9s_mb_2u_lib.s9s_mb_2u(sch_1):page478_i40@pure_quanta.q_res(chips)';

PART_NAME
 R349 'Q_RES_0402LF-0,5%,1/16W,EMPTY,A':;

SECTION_NUMBER 1
 '@S9S_MB_2U_LIB.S9S_MB_2U(SCH_1):PAGE478_I39@PURE_QUANTA.Q_RES(CHIPS)':
 C_PATH='@s9s_mb_2u_lib.s9s_mb_2u(sch_1):page478_i39@pure_quanta.q_res(chips)';

PART_NAME
 R348 'Q_RES_0402LF-0,5%,1/16W,EMPTY,A':;

SECTION_NUMBER 1
 '@S9S_MB_2U_LIB.S9S_MB_2U(SCH_1):PAGE478_I38@PURE_QUANTA.Q_RES(CHIPS)':
 C_PATH='@s9s_mb_2u_lib.s9s_mb_2u(sch_1):page478_i38@pure_quanta.q_res(chips)';

PART_NAME
 R347 'Q_RES_0402LF-33,5%,1/16W,CHIP,A':;

SECTION_NUMBER 1
 '@S9S_MB_2U_LIB.S9S_MB_2U(SCH_1):PAGE478_I60@PURE_QUANTA.Q_RES(CHIPS)':
 C_PATH='@s9s_mb_2u_lib.s9s_mb_2u(sch_1):page478_i60@pure_quanta.q_res(chips)';

PART_NAME
 R346 'Q_RES_0402LF-33,5%,1/16W,CHIP,A':;

SECTION_NUMBER 1
 '@S9S_MB_2U_LIB.S9S_MB_2U(SCH_1):PAGE478_I59@PURE_QUANTA.Q_RES(CHIPS)':
 C_PATH='@s9s_mb_2u_lib.s9s_mb_2u(sch_1):page478_i59@pure_quanta.q_res(chips)';

PART_NAME
 R345 'Q_RES_0402LF-0,5%,1/16W,CHIP,CA':;

SECTION_NUMBER 1
 '@S9S_MB_2U_LIB.S9S_MB_2U(SCH_1):PAGE478_I46@PURE_QUANTA.Q_RES(CHIPS)':
 C_PATH='@s9s_mb_2u_lib.s9s_mb_2u(sch_1):page478_i46@pure_quanta.q_res(chips)';

PART_NAME
 R344 'Q_RES_0402LF-0,5%,1/16W,CHIP,CA':;

SECTION_NUMBER 1
 '@S9S_MB_2U_LIB.S9S_MB_2U(SCH_1):PAGE478_I45@PURE_QUANTA.Q_RES(CHIPS)':
 C_PATH='@s9s_mb_2u_lib.s9s_mb_2u(sch_1):page478_i45@pure_quanta.q_res(chips)';

PART_NAME
 R343 'Q_RES_0402LF-33,5%,1/16W,CHIP,A':;

SECTION_NUMBER 1
 '@S9S_MB_2U_LIB.S9S_MB_2U(SCH_1):PAGE478_I53@PURE_QUANTA.Q_RES(CHIPS)':
 C_PATH='@s9s_mb_2u_lib.s9s_mb_2u(sch_1):page478_i53@pure_quanta.q_res(chips)';

PART_NAME
 R342 'Q_RES_0402LF-33,5%,1/16W,CHIP,A':;

SECTION_NUMBER 1
 '@S9S_MB_2U_LIB.S9S_MB_2U(SCH_1):PAGE478_I54@PURE_QUANTA.Q_RES(CHIPS)':
 C_PATH='@s9s_mb_2u_lib.s9s_mb_2u(sch_1):page478_i54@pure_quanta.q_res(chips)';

PART_NAME
 R341 'Q_RES_0402LF-0,5%,1/16W,CHIP,CA':;

SECTION_NUMBER 1
 '@S9S_MB_2U_LIB.S9S_MB_2U(SCH_1):PAGE478_I44@PURE_QUANTA.Q_RES(CHIPS)':
 C_PATH='@s9s_mb_2u_lib.s9s_mb_2u(sch_1):page478_i44@pure_quanta.q_res(chips)';

PART_NAME
 R340 'Q_RES_0402LF-0,5%,1/16W,CHIP,CA':;

SECTION_NUMBER 1
 '@S9S_MB_2U_LIB.S9S_MB_2U(SCH_1):PAGE478_I43@PURE_QUANTA.Q_RES(CHIPS)':
 C_PATH='@s9s_mb_2u_lib.s9s_mb_2u(sch_1):page478_i43@pure_quanta.q_res(chips)';

PART_NAME
 R339 'Q_RES_0402LF-33,5%,1/16W,CHIP,A':;

SECTION_NUMBER 1
 '@S9S_MB_2U_LIB.S9S_MB_2U(SCH_1):PAGE478_I52@PURE_QUANTA.Q_RES(CHIPS)':
 C_PATH='@s9s_mb_2u_lib.s9s_mb_2u(sch_1):page478_i52@pure_quanta.q_res(chips)';

PART_NAME
 R338 'Q_RES_0402LF-33,5%,1/16W,CHIP,A':;

SECTION_NUMBER 1
 '@S9S_MB_2U_LIB.S9S_MB_2U(SCH_1):PAGE478_I49@PURE_QUANTA.Q_RES(CHIPS)':
 C_PATH='@s9s_mb_2u_lib.s9s_mb_2u(sch_1):page478_i49@pure_quanta.q_res(chips)';

PART_NAME
 R337 'Q_RES_0402LF-0,5%,1/16W,CHIP,CA':;

SECTION_NUMBER 1
 '@S9S_MB_2U_LIB.S9S_MB_2U(SCH_1):PAGE478_I33@PURE_QUANTA.Q_RES(CHIPS)':
 C_PATH='@s9s_mb_2u_lib.s9s_mb_2u(sch_1):page478_i33@pure_quanta.q_res(chips)';

PART_NAME
 R336 'Q_RES_0402LF-0,5%,1/16W,CHIP,CA':;

SECTION_NUMBER 1
 '@S9S_MB_2U_LIB.S9S_MB_2U(SCH_1):PAGE478_I37@PURE_QUANTA.Q_RES(CHIPS)':
 C_PATH='@s9s_mb_2u_lib.s9s_mb_2u(sch_1):page478_i37@pure_quanta.q_res(chips)';

PART_NAME
 R89 'Q_RES_0402LF-1K,1%,1/16W,CHIP,A':;

SECTION_NUMBER 1
 '@S9S_MB_2U_LIB.S9S_MB_2U(SCH_1):PAGE478_I77@PURE_QUANTA.Q_RES(CHIPS)':
 C_PATH='@s9s_mb_2u_lib.s9s_mb_2u(sch_1):page478_i77@pure_quanta.q_res(chips)';

PART_NAME
 R88 'Q_RES_0402LF-150,1%,1/16W,CHIPA':;

SECTION_NUMBER 1
 '@S9S_MB_2U_LIB.S9S_MB_2U(SCH_1):PAGE478_I31@PURE_QUANTA.Q_RES(CHIPS)':
 C_PATH='@s9s_mb_2u_lib.s9s_mb_2u(sch_1):page478_i31@pure_quanta.q_res(chips)';

PART_NAME
 C1212 'Q_CAP_0402-0.1UF,25V,10%,X7R,CA':;

SECTION_NUMBER 1
 '@S9S_MB_2U_LIB.S9S_MB_2U(SCH_1):PAGE478_I89@PURE_QUANTA.Q_CAP(CHIPS)':
 C_PATH='@s9s_mb_2u_lib.s9s_mb_2u(sch_1):page478_i89@pure_quanta.q_cap(chips)';

PART_NAME
 C102 'Q_CAP_C0402-1UF,25V,10%,X6S,CHA':;

SECTION_NUMBER 1
 '@S9S_MB_2U_LIB.S9S_MB_2U(SCH_1):PAGE478_I19@PURE_QUANTA.Q_CAP(CHIPS)':
 C_PATH='@s9s_mb_2u_lib.s9s_mb_2u(sch_1):page478_i19@pure_quanta.q_cap(chips)';

PART_NAME
 C1045 'Q_CAP_C0402-22UF,4V,20%,X6S,CHA':;

SECTION_NUMBER 1
 '@S9S_MB_2U_LIB.S9S_MB_2U(SCH_1):PAGE364_I56@PURE_QUANTA.Q_CAP(CHIPS)':
 C_PATH='@s9s_mb_2u_lib.s9s_mb_2u(sch_1):page364_i56@pure_quanta.q_cap(chips)';

PART_NAME
 C1044 'Q_CAP_C0402-22UF,4V,20%,X6S,CHA':;

SECTION_NUMBER 1
 '@S9S_MB_2U_LIB.S9S_MB_2U(SCH_1):PAGE364_I54@PURE_QUANTA.Q_CAP(CHIPS)':
 C_PATH='@s9s_mb_2u_lib.s9s_mb_2u(sch_1):page364_i54@pure_quanta.q_cap(chips)';

PART_NAME
 C1043 'Q_CAP_C0402-22UF,4V,20%,X6S,CHA':;

SECTION_NUMBER 1
 '@S9S_MB_2U_LIB.S9S_MB_2U(SCH_1):PAGE364_I30@PURE_QUANTA.Q_CAP(CHIPS)':
 C_PATH='@s9s_mb_2u_lib.s9s_mb_2u(sch_1):page364_i30@pure_quanta.q_cap(chips)';

PART_NAME
 C1041 'Q_CAP_C0402-22UF,4V,20%,X6S,CHA':;

SECTION_NUMBER 1
 '@S9S_MB_2U_LIB.S9S_MB_2U(SCH_1):PAGE364_I59@PURE_QUANTA.Q_CAP(CHIPS)':
 C_PATH='@s9s_mb_2u_lib.s9s_mb_2u(sch_1):page364_i59@pure_quanta.q_cap(chips)';

PART_NAME
 C1040 'Q_CAP_C0402-22UF,4V,20%,X6S,CHA':;

SECTION_NUMBER 1
 '@S9S_MB_2U_LIB.S9S_MB_2U(SCH_1):PAGE364_I58@PURE_QUANTA.Q_CAP(CHIPS)':
 C_PATH='@s9s_mb_2u_lib.s9s_mb_2u(sch_1):page364_i58@pure_quanta.q_cap(chips)';

PART_NAME
 C1039 'Q_CAP_C0402-22UF,4V,20%,X6S,CHA':;

SECTION_NUMBER 1
 '@S9S_MB_2U_LIB.S9S_MB_2U(SCH_1):PAGE364_I32@PURE_QUANTA.Q_CAP(CHIPS)':
 C_PATH='@s9s_mb_2u_lib.s9s_mb_2u(sch_1):page364_i32@pure_quanta.q_cap(chips)';

PART_NAME
 C1038 'Q_CAP_C0402-22UF,4V,20%,X6S,CHA':;

SECTION_NUMBER 1
 '@S9S_MB_2U_LIB.S9S_MB_2U(SCH_1):PAGE364_I26@PURE_QUANTA.Q_CAP(CHIPS)':
 C_PATH='@s9s_mb_2u_lib.s9s_mb_2u(sch_1):page364_i26@pure_quanta.q_cap(chips)';

PART_NAME
 C1037 'Q_CAP_C0402-22UF,4V,20%,X6S,CHA':;

SECTION_NUMBER 1
 '@S9S_MB_2U_LIB.S9S_MB_2U(SCH_1):PAGE364_I61@PURE_QUANTA.Q_CAP(CHIPS)':
 C_PATH='@s9s_mb_2u_lib.s9s_mb_2u(sch_1):page364_i61@pure_quanta.q_cap(chips)';

PART_NAME
 C1036 'Q_CAP_C0402-22UF,4V,20%,X6S,CHA':;

SECTION_NUMBER 1
 '@S9S_MB_2U_LIB.S9S_MB_2U(SCH_1):PAGE364_I60@PURE_QUANTA.Q_CAP(CHIPS)':
 C_PATH='@s9s_mb_2u_lib.s9s_mb_2u(sch_1):page364_i60@pure_quanta.q_cap(chips)';

PART_NAME
 C1035 'Q_CAP_C0402-22UF,4V,20%,X6S,CHA':;

SECTION_NUMBER 1
 '@S9S_MB_2U_LIB.S9S_MB_2U(SCH_1):PAGE364_I33@PURE_QUANTA.Q_CAP(CHIPS)':
 C_PATH='@s9s_mb_2u_lib.s9s_mb_2u(sch_1):page364_i33@pure_quanta.q_cap(chips)';

PART_NAME
 C1034 'Q_CAP_C0402-22UF,4V,20%,X6S,CHA':;

SECTION_NUMBER 1
 '@S9S_MB_2U_LIB.S9S_MB_2U(SCH_1):PAGE364_I24@PURE_QUANTA.Q_CAP(CHIPS)':
 C_PATH='@s9s_mb_2u_lib.s9s_mb_2u(sch_1):page364_i24@pure_quanta.q_cap(chips)';

PART_NAME
 C1033 'Q_CAP_C0402-22UF,4V,20%,X6S,CHA':;

SECTION_NUMBER 1
 '@S9S_MB_2U_LIB.S9S_MB_2U(SCH_1):PAGE364_I64@PURE_QUANTA.Q_CAP(CHIPS)':
 C_PATH='@s9s_mb_2u_lib.s9s_mb_2u(sch_1):page364_i64@pure_quanta.q_cap(chips)';

PART_NAME
 C1032 'Q_CAP_C0402-22UF,4V,20%,X6S,CHA':;

SECTION_NUMBER 1
 '@S9S_MB_2U_LIB.S9S_MB_2U(SCH_1):PAGE364_I63@PURE_QUANTA.Q_CAP(CHIPS)':
 C_PATH='@s9s_mb_2u_lib.s9s_mb_2u(sch_1):page364_i63@pure_quanta.q_cap(chips)';

PART_NAME
 C1031 'Q_CAP_C0402-22UF,4V,20%,X6S,CHA':;

SECTION_NUMBER 1
 '@S9S_MB_2U_LIB.S9S_MB_2U(SCH_1):PAGE364_I35@PURE_QUANTA.Q_CAP(CHIPS)':
 C_PATH='@s9s_mb_2u_lib.s9s_mb_2u(sch_1):page364_i35@pure_quanta.q_cap(chips)';

PART_NAME
 C1030 'Q_CAP_C0402-22UF,4V,20%,X6S,CHA':;

SECTION_NUMBER 1
 '@S9S_MB_2U_LIB.S9S_MB_2U(SCH_1):PAGE364_I23@PURE_QUANTA.Q_CAP(CHIPS)':
 C_PATH='@s9s_mb_2u_lib.s9s_mb_2u(sch_1):page364_i23@pure_quanta.q_cap(chips)';

PART_NAME
 C1029 'Q_CAP_C0402-22UF,4V,20%,X6S,CHA':;

SECTION_NUMBER 1
 '@S9S_MB_2U_LIB.S9S_MB_2U(SCH_1):PAGE364_I67@PURE_QUANTA.Q_CAP(CHIPS)':
 C_PATH='@s9s_mb_2u_lib.s9s_mb_2u(sch_1):page364_i67@pure_quanta.q_cap(chips)';

PART_NAME
 C1028 'Q_CAP_C0402-22UF,4V,20%,X6S,CHA':;

SECTION_NUMBER 1
 '@S9S_MB_2U_LIB.S9S_MB_2U(SCH_1):PAGE364_I65@PURE_QUANTA.Q_CAP(CHIPS)':
 C_PATH='@s9s_mb_2u_lib.s9s_mb_2u(sch_1):page364_i65@pure_quanta.q_cap(chips)';

PART_NAME
 C1027 'Q_CAP_C0402-22UF,4V,20%,X6S,CHA':;

SECTION_NUMBER 1
 '@S9S_MB_2U_LIB.S9S_MB_2U(SCH_1):PAGE364_I36@PURE_QUANTA.Q_CAP(CHIPS)':
 C_PATH='@s9s_mb_2u_lib.s9s_mb_2u(sch_1):page364_i36@pure_quanta.q_cap(chips)';

PART_NAME
 C1026 'Q_CAP_C0402-22UF,4V,20%,X6S,CHA':;

SECTION_NUMBER 1
 '@S9S_MB_2U_LIB.S9S_MB_2U(SCH_1):PAGE364_I22@PURE_QUANTA.Q_CAP(CHIPS)':
 C_PATH='@s9s_mb_2u_lib.s9s_mb_2u(sch_1):page364_i22@pure_quanta.q_cap(chips)';

PART_NAME
 C1025 'Q_CAP_C0402-22UF,4V,20%,X6S,CHA':;

SECTION_NUMBER 1
 '@S9S_MB_2U_LIB.S9S_MB_2U(SCH_1):PAGE364_I68@PURE_QUANTA.Q_CAP(CHIPS)':
 C_PATH='@s9s_mb_2u_lib.s9s_mb_2u(sch_1):page364_i68@pure_quanta.q_cap(chips)';

PART_NAME
 C1024 'Q_CAP_C0402-22UF,4V,20%,X6S,CHA':;

SECTION_NUMBER 1
 '@S9S_MB_2U_LIB.S9S_MB_2U(SCH_1):PAGE364_I66@PURE_QUANTA.Q_CAP(CHIPS)':
 C_PATH='@s9s_mb_2u_lib.s9s_mb_2u(sch_1):page364_i66@pure_quanta.q_cap(chips)';

PART_NAME
 C1023 'Q_CAP_C0402-22UF,4V,20%,X6S,CHA':;

SECTION_NUMBER 1
 '@S9S_MB_2U_LIB.S9S_MB_2U(SCH_1):PAGE364_I37@PURE_QUANTA.Q_CAP(CHIPS)':
 C_PATH='@s9s_mb_2u_lib.s9s_mb_2u(sch_1):page364_i37@pure_quanta.q_cap(chips)';

PART_NAME
 C1022 'Q_CAP_C0402-22UF,4V,20%,X6S,CHA':;

SECTION_NUMBER 1
 '@S9S_MB_2U_LIB.S9S_MB_2U(SCH_1):PAGE364_I21@PURE_QUANTA.Q_CAP(CHIPS)':
 C_PATH='@s9s_mb_2u_lib.s9s_mb_2u(sch_1):page364_i21@pure_quanta.q_cap(chips)';

PART_NAME
 C1021 'Q_CAP_C0402-22UF,4V,20%,X6S,CHA':;

SECTION_NUMBER 1
 '@S9S_MB_2U_LIB.S9S_MB_2U(SCH_1):PAGE364_I70@PURE_QUANTA.Q_CAP(CHIPS)':
 C_PATH='@s9s_mb_2u_lib.s9s_mb_2u(sch_1):page364_i70@pure_quanta.q_cap(chips)';

PART_NAME
 C1020 'Q_CAP_C0402-22UF,4V,20%,X6S,CHA':;

SECTION_NUMBER 1
 '@S9S_MB_2U_LIB.S9S_MB_2U(SCH_1):PAGE364_I69@PURE_QUANTA.Q_CAP(CHIPS)':
 C_PATH='@s9s_mb_2u_lib.s9s_mb_2u(sch_1):page364_i69@pure_quanta.q_cap(chips)';

PART_NAME
 C1019 'Q_CAP_C0402-22UF,4V,20%,X6S,CHA':;

SECTION_NUMBER 1
 '@S9S_MB_2U_LIB.S9S_MB_2U(SCH_1):PAGE364_I38@PURE_QUANTA.Q_CAP(CHIPS)':
 C_PATH='@s9s_mb_2u_lib.s9s_mb_2u(sch_1):page364_i38@pure_quanta.q_cap(chips)';

PART_NAME
 C1018 'Q_CAP_C0402-22UF,4V,20%,X6S,CHA':;

SECTION_NUMBER 1
 '@S9S_MB_2U_LIB.S9S_MB_2U(SCH_1):PAGE364_I20@PURE_QUANTA.Q_CAP(CHIPS)':
 C_PATH='@s9s_mb_2u_lib.s9s_mb_2u(sch_1):page364_i20@pure_quanta.q_cap(chips)';

PART_NAME
 C1017 'Q_CAP_C0402-22UF,4V,20%,X6S,CHA':;

SECTION_NUMBER 1
 '@S9S_MB_2U_LIB.S9S_MB_2U(SCH_1):PAGE364_I72@PURE_QUANTA.Q_CAP(CHIPS)':
 C_PATH='@s9s_mb_2u_lib.s9s_mb_2u(sch_1):page364_i72@pure_quanta.q_cap(chips)';

PART_NAME
 C1016 'Q_CAP_C0402-22UF,4V,20%,X6S,CHA':;

SECTION_NUMBER 1
 '@S9S_MB_2U_LIB.S9S_MB_2U(SCH_1):PAGE364_I71@PURE_QUANTA.Q_CAP(CHIPS)':
 C_PATH='@s9s_mb_2u_lib.s9s_mb_2u(sch_1):page364_i71@pure_quanta.q_cap(chips)';

PART_NAME
 C1015 'Q_CAP_C0402-22UF,4V,20%,X6S,CHA':;

SECTION_NUMBER 1
 '@S9S_MB_2U_LIB.S9S_MB_2U(SCH_1):PAGE364_I39@PURE_QUANTA.Q_CAP(CHIPS)':
 C_PATH='@s9s_mb_2u_lib.s9s_mb_2u(sch_1):page364_i39@pure_quanta.q_cap(chips)';

PART_NAME
 C1014 'Q_CAP_C0402-22UF,4V,20%,X6S,CHA':;

SECTION_NUMBER 1
 '@S9S_MB_2U_LIB.S9S_MB_2U(SCH_1):PAGE364_I19@PURE_QUANTA.Q_CAP(CHIPS)':
 C_PATH='@s9s_mb_2u_lib.s9s_mb_2u(sch_1):page364_i19@pure_quanta.q_cap(chips)';

PART_NAME
 C1013 'Q_CAP_C0402-22UF,4V,20%,X6S,CHA':;

SECTION_NUMBER 1
 '@S9S_MB_2U_LIB.S9S_MB_2U(SCH_1):PAGE364_I74@PURE_QUANTA.Q_CAP(CHIPS)':
 C_PATH='@s9s_mb_2u_lib.s9s_mb_2u(sch_1):page364_i74@pure_quanta.q_cap(chips)';

PART_NAME
 C1012 'Q_CAP_C0402-22UF,4V,20%,X6S,CHA':;

SECTION_NUMBER 1
 '@S9S_MB_2U_LIB.S9S_MB_2U(SCH_1):PAGE364_I73@PURE_QUANTA.Q_CAP(CHIPS)':
 C_PATH='@s9s_mb_2u_lib.s9s_mb_2u(sch_1):page364_i73@pure_quanta.q_cap(chips)';

PART_NAME
 C1011 'Q_CAP_C0402-22UF,4V,20%,X6S,CHA':;

SECTION_NUMBER 1
 '@S9S_MB_2U_LIB.S9S_MB_2U(SCH_1):PAGE364_I40@PURE_QUANTA.Q_CAP(CHIPS)':
 C_PATH='@s9s_mb_2u_lib.s9s_mb_2u(sch_1):page364_i40@pure_quanta.q_cap(chips)';

PART_NAME
 C1010 'Q_CAP_C0402-22UF,4V,20%,X6S,CHA':;

SECTION_NUMBER 1
 '@S9S_MB_2U_LIB.S9S_MB_2U(SCH_1):PAGE364_I18@PURE_QUANTA.Q_CAP(CHIPS)':
 C_PATH='@s9s_mb_2u_lib.s9s_mb_2u(sch_1):page364_i18@pure_quanta.q_cap(chips)';

PART_NAME
 C1009 'Q_CAP_C0402-22UF,4V,20%,X6S,CHA':;

SECTION_NUMBER 1
 '@S9S_MB_2U_LIB.S9S_MB_2U(SCH_1):PAGE364_I77@PURE_QUANTA.Q_CAP(CHIPS)':
 C_PATH='@s9s_mb_2u_lib.s9s_mb_2u(sch_1):page364_i77@pure_quanta.q_cap(chips)';

PART_NAME
 C1008 'Q_CAP_C0402-22UF,4V,20%,X6S,CHA':;

SECTION_NUMBER 1
 '@S9S_MB_2U_LIB.S9S_MB_2U(SCH_1):PAGE364_I75@PURE_QUANTA.Q_CAP(CHIPS)':
 C_PATH='@s9s_mb_2u_lib.s9s_mb_2u(sch_1):page364_i75@pure_quanta.q_cap(chips)';

PART_NAME
 C1007 'Q_CAP_C0402-22UF,4V,20%,X6S,CHA':;

SECTION_NUMBER 1
 '@S9S_MB_2U_LIB.S9S_MB_2U(SCH_1):PAGE364_I41@PURE_QUANTA.Q_CAP(CHIPS)':
 C_PATH='@s9s_mb_2u_lib.s9s_mb_2u(sch_1):page364_i41@pure_quanta.q_cap(chips)';

PART_NAME
 C1006 'Q_CAP_C0402-22UF,4V,20%,X6S,CHA':;

SECTION_NUMBER 1
 '@S9S_MB_2U_LIB.S9S_MB_2U(SCH_1):PAGE364_I29@PURE_QUANTA.Q_CAP(CHIPS)':
 C_PATH='@s9s_mb_2u_lib.s9s_mb_2u(sch_1):page364_i29@pure_quanta.q_cap(chips)';

PART_NAME
 C1005 'Q_CAP_C0402-22UF,4V,20%,X6S,CHA':;

SECTION_NUMBER 1
 '@S9S_MB_2U_LIB.S9S_MB_2U(SCH_1):PAGE364_I80@PURE_QUANTA.Q_CAP(CHIPS)':
 C_PATH='@s9s_mb_2u_lib.s9s_mb_2u(sch_1):page364_i80@pure_quanta.q_cap(chips)';

PART_NAME
 C1004 'Q_CAP_C0402-22UF,4V,20%,X6S,CHA':;

SECTION_NUMBER 1
 '@S9S_MB_2U_LIB.S9S_MB_2U(SCH_1):PAGE364_I78@PURE_QUANTA.Q_CAP(CHIPS)':
 C_PATH='@s9s_mb_2u_lib.s9s_mb_2u(sch_1):page364_i78@pure_quanta.q_cap(chips)';

PART_NAME
 C1003 'Q_CAP_C0402-22UF,4V,20%,X6S,CHA':;

SECTION_NUMBER 1
 '@S9S_MB_2U_LIB.S9S_MB_2U(SCH_1):PAGE364_I42@PURE_QUANTA.Q_CAP(CHIPS)':
 C_PATH='@s9s_mb_2u_lib.s9s_mb_2u(sch_1):page364_i42@pure_quanta.q_cap(chips)';

PART_NAME
 C1002 'Q_CAP_C0402-22UF,4V,20%,X6S,CHA':;

SECTION_NUMBER 1
 '@S9S_MB_2U_LIB.S9S_MB_2U(SCH_1):PAGE364_I16@PURE_QUANTA.Q_CAP(CHIPS)':
 C_PATH='@s9s_mb_2u_lib.s9s_mb_2u(sch_1):page364_i16@pure_quanta.q_cap(chips)';

PART_NAME
 C1001 'Q_CAP_C0402-22UF,4V,20%,X6S,CHA':;

SECTION_NUMBER 1
 '@S9S_MB_2U_LIB.S9S_MB_2U(SCH_1):PAGE364_I82@PURE_QUANTA.Q_CAP(CHIPS)':
 C_PATH='@s9s_mb_2u_lib.s9s_mb_2u(sch_1):page364_i82@pure_quanta.q_cap(chips)';

PART_NAME
 C1000 'Q_CAP_C0402-22UF,4V,20%,X6S,CHA':;

SECTION_NUMBER 1
 '@S9S_MB_2U_LIB.S9S_MB_2U(SCH_1):PAGE364_I81@PURE_QUANTA.Q_CAP(CHIPS)':
 C_PATH='@s9s_mb_2u_lib.s9s_mb_2u(sch_1):page364_i81@pure_quanta.q_cap(chips)';

PART_NAME
 C999 'Q_CAP_C0402-22UF,4V,20%,X6S,CHA':;

SECTION_NUMBER 1
 '@S9S_MB_2U_LIB.S9S_MB_2U(SCH_1):PAGE364_I44@PURE_QUANTA.Q_CAP(CHIPS)':
 C_PATH='@s9s_mb_2u_lib.s9s_mb_2u(sch_1):page364_i44@pure_quanta.q_cap(chips)';

PART_NAME
 C998 'Q_CAP_C0402-22UF,4V,20%,X6S,CHA':;

SECTION_NUMBER 1
 '@S9S_MB_2U_LIB.S9S_MB_2U(SCH_1):PAGE364_I15@PURE_QUANTA.Q_CAP(CHIPS)':
 C_PATH='@s9s_mb_2u_lib.s9s_mb_2u(sch_1):page364_i15@pure_quanta.q_cap(chips)';

PART_NAME
 C997 'Q_CAP_C0402-22UF,4V,20%,X6S,CHA':;

SECTION_NUMBER 1
 '@S9S_MB_2U_LIB.S9S_MB_2U(SCH_1):PAGE364_I86@PURE_QUANTA.Q_CAP(CHIPS)':
 C_PATH='@s9s_mb_2u_lib.s9s_mb_2u(sch_1):page364_i86@pure_quanta.q_cap(chips)';

PART_NAME
 C996 'Q_CAP_C0402-22UF,4V,20%,X6S,CHA':;

SECTION_NUMBER 1
 '@S9S_MB_2U_LIB.S9S_MB_2U(SCH_1):PAGE364_I85@PURE_QUANTA.Q_CAP(CHIPS)':
 C_PATH='@s9s_mb_2u_lib.s9s_mb_2u(sch_1):page364_i85@pure_quanta.q_cap(chips)';

PART_NAME
 C995 'Q_CAP_C0402-22UF,4V,20%,X6S,CHA':;

SECTION_NUMBER 1
 '@S9S_MB_2U_LIB.S9S_MB_2U(SCH_1):PAGE364_I46@PURE_QUANTA.Q_CAP(CHIPS)':
 C_PATH='@s9s_mb_2u_lib.s9s_mb_2u(sch_1):page364_i46@pure_quanta.q_cap(chips)';

PART_NAME
 C994 'Q_CAP_C0402-22UF,4V,20%,X6S,CHA':;

SECTION_NUMBER 1
 '@S9S_MB_2U_LIB.S9S_MB_2U(SCH_1):PAGE364_I17@PURE_QUANTA.Q_CAP(CHIPS)':
 C_PATH='@s9s_mb_2u_lib.s9s_mb_2u(sch_1):page364_i17@pure_quanta.q_cap(chips)';

PART_NAME
 C993 'Q_CAP_C0402-22UF,4V,20%,X6S,CHA':;

SECTION_NUMBER 1
 '@S9S_MB_2U_LIB.S9S_MB_2U(SCH_1):PAGE364_I87@PURE_QUANTA.Q_CAP(CHIPS)':
 C_PATH='@s9s_mb_2u_lib.s9s_mb_2u(sch_1):page364_i87@pure_quanta.q_cap(chips)';

PART_NAME
 C992 'Q_CAP_C0402-22UF,4V,20%,X6S,CHA':;

SECTION_NUMBER 1
 '@S9S_MB_2U_LIB.S9S_MB_2U(SCH_1):PAGE364_I88@PURE_QUANTA.Q_CAP(CHIPS)':
 C_PATH='@s9s_mb_2u_lib.s9s_mb_2u(sch_1):page364_i88@pure_quanta.q_cap(chips)';

PART_NAME
 C991 'Q_CAP_C0402-22UF,4V,20%,X6S,CHA':;

SECTION_NUMBER 1
 '@S9S_MB_2U_LIB.S9S_MB_2U(SCH_1):PAGE364_I47@PURE_QUANTA.Q_CAP(CHIPS)':
 C_PATH='@s9s_mb_2u_lib.s9s_mb_2u(sch_1):page364_i47@pure_quanta.q_cap(chips)';

PART_NAME
 C990 'Q_CAP_C0402-22UF,4V,20%,X6S,CHA':;

SECTION_NUMBER 1
 '@S9S_MB_2U_LIB.S9S_MB_2U(SCH_1):PAGE364_I13@PURE_QUANTA.Q_CAP(CHIPS)':
 C_PATH='@s9s_mb_2u_lib.s9s_mb_2u(sch_1):page364_i13@pure_quanta.q_cap(chips)';

PART_NAME
 C989 'Q_CAP_C0402-22UF,4V,20%,X6S,CHA':;

SECTION_NUMBER 1
 '@S9S_MB_2U_LIB.S9S_MB_2U(SCH_1):PAGE364_I90@PURE_QUANTA.Q_CAP(CHIPS)':
 C_PATH='@s9s_mb_2u_lib.s9s_mb_2u(sch_1):page364_i90@pure_quanta.q_cap(chips)';

PART_NAME
 C988 'Q_CAP_C0402-22UF,4V,20%,X6S,CHA':;

SECTION_NUMBER 1
 '@S9S_MB_2U_LIB.S9S_MB_2U(SCH_1):PAGE364_I89@PURE_QUANTA.Q_CAP(CHIPS)':
 C_PATH='@s9s_mb_2u_lib.s9s_mb_2u(sch_1):page364_i89@pure_quanta.q_cap(chips)';

PART_NAME
 C987 'Q_CAP_C0402-22UF,4V,20%,X6S,CHA':;

SECTION_NUMBER 1
 '@S9S_MB_2U_LIB.S9S_MB_2U(SCH_1):PAGE364_I48@PURE_QUANTA.Q_CAP(CHIPS)':
 C_PATH='@s9s_mb_2u_lib.s9s_mb_2u(sch_1):page364_i48@pure_quanta.q_cap(chips)';

PART_NAME
 C986 'Q_CAP_C0402-22UF,4V,20%,X6S,CHA':;

SECTION_NUMBER 1
 '@S9S_MB_2U_LIB.S9S_MB_2U(SCH_1):PAGE364_I14@PURE_QUANTA.Q_CAP(CHIPS)':
 C_PATH='@s9s_mb_2u_lib.s9s_mb_2u(sch_1):page364_i14@pure_quanta.q_cap(chips)';

PART_NAME
 C985 'Q_CAP_C0402-22UF,4V,20%,X6S,CHA':;

SECTION_NUMBER 1
 '@S9S_MB_2U_LIB.S9S_MB_2U(SCH_1):PAGE364_I92@PURE_QUANTA.Q_CAP(CHIPS)':
 C_PATH='@s9s_mb_2u_lib.s9s_mb_2u(sch_1):page364_i92@pure_quanta.q_cap(chips)';

PART_NAME
 C984 'Q_CAP_C0402-22UF,4V,20%,X6S,CHA':;

SECTION_NUMBER 1
 '@S9S_MB_2U_LIB.S9S_MB_2U(SCH_1):PAGE364_I91@PURE_QUANTA.Q_CAP(CHIPS)':
 C_PATH='@s9s_mb_2u_lib.s9s_mb_2u(sch_1):page364_i91@pure_quanta.q_cap(chips)';

PART_NAME
 C983 'Q_CAP_C0402-22UF,4V,20%,X6S,CHA':;

SECTION_NUMBER 1
 '@S9S_MB_2U_LIB.S9S_MB_2U(SCH_1):PAGE364_I49@PURE_QUANTA.Q_CAP(CHIPS)':
 C_PATH='@s9s_mb_2u_lib.s9s_mb_2u(sch_1):page364_i49@pure_quanta.q_cap(chips)';

PART_NAME
 C982 'Q_CAP_C0402-22UF,4V,20%,X6S,CHA':;

SECTION_NUMBER 1
 '@S9S_MB_2U_LIB.S9S_MB_2U(SCH_1):PAGE364_I12@PURE_QUANTA.Q_CAP(CHIPS)':
 C_PATH='@s9s_mb_2u_lib.s9s_mb_2u(sch_1):page364_i12@pure_quanta.q_cap(chips)';

PART_NAME
 C981 'Q_CAP_C0402-22UF,4V,20%,X6S,CHA':;

SECTION_NUMBER 1
 '@S9S_MB_2U_LIB.S9S_MB_2U(SCH_1):PAGE364_I94@PURE_QUANTA.Q_CAP(CHIPS)':
 C_PATH='@s9s_mb_2u_lib.s9s_mb_2u(sch_1):page364_i94@pure_quanta.q_cap(chips)';

PART_NAME
 C980 'Q_CAP_C0402-22UF,4V,20%,X6S,CHA':;

SECTION_NUMBER 1
 '@S9S_MB_2U_LIB.S9S_MB_2U(SCH_1):PAGE364_I93@PURE_QUANTA.Q_CAP(CHIPS)':
 C_PATH='@s9s_mb_2u_lib.s9s_mb_2u(sch_1):page364_i93@pure_quanta.q_cap(chips)';

PART_NAME
 C979 'Q_CAP_C0402-22UF,4V,20%,X6S,CHA':;

SECTION_NUMBER 1
 '@S9S_MB_2U_LIB.S9S_MB_2U(SCH_1):PAGE364_I50@PURE_QUANTA.Q_CAP(CHIPS)':
 C_PATH='@s9s_mb_2u_lib.s9s_mb_2u(sch_1):page364_i50@pure_quanta.q_cap(chips)';

PART_NAME
 C978 'Q_CAP_C0402-22UF,4V,20%,X6S,CHA':;

SECTION_NUMBER 1
 '@S9S_MB_2U_LIB.S9S_MB_2U(SCH_1):PAGE364_I10@PURE_QUANTA.Q_CAP(CHIPS)':
 C_PATH='@s9s_mb_2u_lib.s9s_mb_2u(sch_1):page364_i10@pure_quanta.q_cap(chips)';

PART_NAME
 C977 'Q_CAP_C0402-22UF,4V,20%,X6S,CHA':;

SECTION_NUMBER 1
 '@S9S_MB_2U_LIB.S9S_MB_2U(SCH_1):PAGE364_I96@PURE_QUANTA.Q_CAP(CHIPS)':
 C_PATH='@s9s_mb_2u_lib.s9s_mb_2u(sch_1):page364_i96@pure_quanta.q_cap(chips)';

PART_NAME
 C976 'Q_CAP_C0402-22UF,4V,20%,X6S,CHA':;

SECTION_NUMBER 1
 '@S9S_MB_2U_LIB.S9S_MB_2U(SCH_1):PAGE364_I95@PURE_QUANTA.Q_CAP(CHIPS)':
 C_PATH='@s9s_mb_2u_lib.s9s_mb_2u(sch_1):page364_i95@pure_quanta.q_cap(chips)';

PART_NAME
 C975 'Q_CAP_C0402-22UF,4V,20%,X6S,CHA':;

SECTION_NUMBER 1
 '@S9S_MB_2U_LIB.S9S_MB_2U(SCH_1):PAGE364_I51@PURE_QUANTA.Q_CAP(CHIPS)':
 C_PATH='@s9s_mb_2u_lib.s9s_mb_2u(sch_1):page364_i51@pure_quanta.q_cap(chips)';

PART_NAME
 C974 'Q_CAP_C0402-22UF,4V,20%,X6S,CHA':;

SECTION_NUMBER 1
 '@S9S_MB_2U_LIB.S9S_MB_2U(SCH_1):PAGE364_I9@PURE_QUANTA.Q_CAP(CHIPS)':
 C_PATH='@s9s_mb_2u_lib.s9s_mb_2u(sch_1):page364_i9@pure_quanta.q_cap(chips)';

PART_NAME
 C973 'Q_CAP_C0402-22UF,4V,20%,X6S,CHA':;

SECTION_NUMBER 1
 '@S9S_MB_2U_LIB.S9S_MB_2U(SCH_1):PAGE364_I98@PURE_QUANTA.Q_CAP(CHIPS)':
 C_PATH='@s9s_mb_2u_lib.s9s_mb_2u(sch_1):page364_i98@pure_quanta.q_cap(chips)';

PART_NAME
 C972 'Q_CAP_C0402-22UF,4V,20%,X6S,CHA':;

SECTION_NUMBER 1
 '@S9S_MB_2U_LIB.S9S_MB_2U(SCH_1):PAGE364_I97@PURE_QUANTA.Q_CAP(CHIPS)':
 C_PATH='@s9s_mb_2u_lib.s9s_mb_2u(sch_1):page364_i97@pure_quanta.q_cap(chips)';

PART_NAME
 C971 'Q_CAP_C0402-22UF,4V,20%,X6S,CHA':;

SECTION_NUMBER 1
 '@S9S_MB_2U_LIB.S9S_MB_2U(SCH_1):PAGE364_I52@PURE_QUANTA.Q_CAP(CHIPS)':
 C_PATH='@s9s_mb_2u_lib.s9s_mb_2u(sch_1):page364_i52@pure_quanta.q_cap(chips)';

PART_NAME
 C970 'Q_CAP_C0402-22UF,4V,20%,X6S,CHA':;

SECTION_NUMBER 1
 '@S9S_MB_2U_LIB.S9S_MB_2U(SCH_1):PAGE364_I8@PURE_QUANTA.Q_CAP(CHIPS)':
 C_PATH='@s9s_mb_2u_lib.s9s_mb_2u(sch_1):page364_i8@pure_quanta.q_cap(chips)';

PART_NAME
 C969 'Q_CAP_C0402-22UF,4V,20%,X6S,CHA':;

SECTION_NUMBER 1
 '@S9S_MB_2U_LIB.S9S_MB_2U(SCH_1):PAGE364_I101@PURE_QUANTA.Q_CAP(CHIPS)':
 C_PATH='@s9s_mb_2u_lib.s9s_mb_2u(sch_1):page364_i101@pure_quanta.q_cap(chips)';

PART_NAME
 C968 'Q_CAP_C0402-22UF,4V,20%,X6S,CHA':;

SECTION_NUMBER 1
 '@S9S_MB_2U_LIB.S9S_MB_2U(SCH_1):PAGE364_I99@PURE_QUANTA.Q_CAP(CHIPS)':
 C_PATH='@s9s_mb_2u_lib.s9s_mb_2u(sch_1):page364_i99@pure_quanta.q_cap(chips)';

PART_NAME
 C967 'Q_CAP_C0402-22UF,4V,20%,X6S,CHA':;

SECTION_NUMBER 1
 '@S9S_MB_2U_LIB.S9S_MB_2U(SCH_1):PAGE364_I53@PURE_QUANTA.Q_CAP(CHIPS)':
 C_PATH='@s9s_mb_2u_lib.s9s_mb_2u(sch_1):page364_i53@pure_quanta.q_cap(chips)';

PART_NAME
 C966 'Q_CAP_C0402-22UF,4V,20%,X6S,CHA':;

SECTION_NUMBER 1
 '@S9S_MB_2U_LIB.S9S_MB_2U(SCH_1):PAGE364_I7@PURE_QUANTA.Q_CAP(CHIPS)':
 C_PATH='@s9s_mb_2u_lib.s9s_mb_2u(sch_1):page364_i7@pure_quanta.q_cap(chips)';

PART_NAME
 C590 'Q_CAP_C0402-22UF,4V,20%,X6S,CHA':;

SECTION_NUMBER 1
 '@S9S_MB_2U_LIB.S9S_MB_2U(SCH_1):PAGE364_I171@PURE_QUANTA.Q_CAP(CHIPS)':
 C_PATH='@s9s_mb_2u_lib.s9s_mb_2u(sch_1):page364_i171@pure_quanta.q_cap(chips)';

PART_NAME
 C422 'Q_CAP_C0402-22UF,4V,20%,X6S,CHA':;

SECTION_NUMBER 1
 '@S9S_MB_2U_LIB.S9S_MB_2U(SCH_1):PAGE364_I143@PURE_QUANTA.Q_CAP(CHIPS)':
 C_PATH='@s9s_mb_2u_lib.s9s_mb_2u(sch_1):page364_i143@pure_quanta.q_cap(chips)';

PART_NAME
 C421 'Q_CAP_C0402-22UF,4V,20%,X6S,CHA':;

SECTION_NUMBER 1
 '@S9S_MB_2U_LIB.S9S_MB_2U(SCH_1):PAGE364_I145@PURE_QUANTA.Q_CAP(CHIPS)':
 C_PATH='@s9s_mb_2u_lib.s9s_mb_2u(sch_1):page364_i145@pure_quanta.q_cap(chips)';

PART_NAME
 C420 'Q_CAP_C0402-22UF,4V,20%,X6S,CHA':;

SECTION_NUMBER 1
 '@S9S_MB_2U_LIB.S9S_MB_2U(SCH_1):PAGE364_I146@PURE_QUANTA.Q_CAP(CHIPS)':
 C_PATH='@s9s_mb_2u_lib.s9s_mb_2u(sch_1):page364_i146@pure_quanta.q_cap(chips)';

PART_NAME
 C419 'Q_CAP_C0402-22UF,4V,20%,X6S,CHA':;

SECTION_NUMBER 1
 '@S9S_MB_2U_LIB.S9S_MB_2U(SCH_1):PAGE364_I142@PURE_QUANTA.Q_CAP(CHIPS)':
 C_PATH='@s9s_mb_2u_lib.s9s_mb_2u(sch_1):page364_i142@pure_quanta.q_cap(chips)';

PART_NAME
 C418 'Q_CAP_C0402-22UF,4V,20%,X6S,CHA':;

SECTION_NUMBER 1
 '@S9S_MB_2U_LIB.S9S_MB_2U(SCH_1):PAGE364_I141@PURE_QUANTA.Q_CAP(CHIPS)':
 C_PATH='@s9s_mb_2u_lib.s9s_mb_2u(sch_1):page364_i141@pure_quanta.q_cap(chips)';

PART_NAME
 C417 'Q_CAP_C0402-22UF,4V,20%,X6S,CHA':;

SECTION_NUMBER 1
 '@S9S_MB_2U_LIB.S9S_MB_2U(SCH_1):PAGE364_I140@PURE_QUANTA.Q_CAP(CHIPS)':
 C_PATH='@s9s_mb_2u_lib.s9s_mb_2u(sch_1):page364_i140@pure_quanta.q_cap(chips)';

PART_NAME
 C416 'Q_CAP_C0402-22UF,4V,20%,X6S,CHA':;

SECTION_NUMBER 1
 '@S9S_MB_2U_LIB.S9S_MB_2U(SCH_1):PAGE364_I111@PURE_QUANTA.Q_CAP(CHIPS)':
 C_PATH='@s9s_mb_2u_lib.s9s_mb_2u(sch_1):page364_i111@pure_quanta.q_cap(chips)';

PART_NAME
 C415 'Q_CAP_C0402-22UF,4V,20%,X6S,CHA':;

SECTION_NUMBER 1
 '@S9S_MB_2U_LIB.S9S_MB_2U(SCH_1):PAGE364_I139@PURE_QUANTA.Q_CAP(CHIPS)':
 C_PATH='@s9s_mb_2u_lib.s9s_mb_2u(sch_1):page364_i139@pure_quanta.q_cap(chips)';

PART_NAME
 C414 'Q_CAP_C0402-22UF,4V,20%,X6S,CHA':;

SECTION_NUMBER 1
 '@S9S_MB_2U_LIB.S9S_MB_2U(SCH_1):PAGE364_I112@PURE_QUANTA.Q_CAP(CHIPS)':
 C_PATH='@s9s_mb_2u_lib.s9s_mb_2u(sch_1):page364_i112@pure_quanta.q_cap(chips)';

PART_NAME
 C413 'Q_CAP_C0402-22UF,4V,20%,X6S,CHA':;

SECTION_NUMBER 1
 '@S9S_MB_2U_LIB.S9S_MB_2U(SCH_1):PAGE364_I138@PURE_QUANTA.Q_CAP(CHIPS)':
 C_PATH='@s9s_mb_2u_lib.s9s_mb_2u(sch_1):page364_i138@pure_quanta.q_cap(chips)';

PART_NAME
 C412 'Q_CAP_C0402-22UF,4V,20%,X6S,CHA':;

SECTION_NUMBER 1
 '@S9S_MB_2U_LIB.S9S_MB_2U(SCH_1):PAGE364_I113@PURE_QUANTA.Q_CAP(CHIPS)':
 C_PATH='@s9s_mb_2u_lib.s9s_mb_2u(sch_1):page364_i113@pure_quanta.q_cap(chips)';

PART_NAME
 C411 'Q_CAP_C0402-22UF,4V,20%,X6S,CHA':;

SECTION_NUMBER 1
 '@S9S_MB_2U_LIB.S9S_MB_2U(SCH_1):PAGE364_I137@PURE_QUANTA.Q_CAP(CHIPS)':
 C_PATH='@s9s_mb_2u_lib.s9s_mb_2u(sch_1):page364_i137@pure_quanta.q_cap(chips)';

PART_NAME
 C410 'Q_CAP_C0402-22UF,4V,20%,X6S,CHA':;

SECTION_NUMBER 1
 '@S9S_MB_2U_LIB.S9S_MB_2U(SCH_1):PAGE364_I114@PURE_QUANTA.Q_CAP(CHIPS)':
 C_PATH='@s9s_mb_2u_lib.s9s_mb_2u(sch_1):page364_i114@pure_quanta.q_cap(chips)';

PART_NAME
 C409 'Q_CAP_C0402-22UF,4V,20%,X6S,CHA':;

SECTION_NUMBER 1
 '@S9S_MB_2U_LIB.S9S_MB_2U(SCH_1):PAGE364_I136@PURE_QUANTA.Q_CAP(CHIPS)':
 C_PATH='@s9s_mb_2u_lib.s9s_mb_2u(sch_1):page364_i136@pure_quanta.q_cap(chips)';

PART_NAME
 C408 'Q_CAP_C0402-22UF,4V,20%,X6S,CHA':;

SECTION_NUMBER 1
 '@S9S_MB_2U_LIB.S9S_MB_2U(SCH_1):PAGE364_I115@PURE_QUANTA.Q_CAP(CHIPS)':
 C_PATH='@s9s_mb_2u_lib.s9s_mb_2u(sch_1):page364_i115@pure_quanta.q_cap(chips)';

PART_NAME
 C407 'Q_CAP_C0402-22UF,4V,20%,X6S,CHA':;

SECTION_NUMBER 1
 '@S9S_MB_2U_LIB.S9S_MB_2U(SCH_1):PAGE364_I135@PURE_QUANTA.Q_CAP(CHIPS)':
 C_PATH='@s9s_mb_2u_lib.s9s_mb_2u(sch_1):page364_i135@pure_quanta.q_cap(chips)';

PART_NAME
 C406 'Q_CAP_C0402-22UF,4V,20%,X6S,CHA':;

SECTION_NUMBER 1
 '@S9S_MB_2U_LIB.S9S_MB_2U(SCH_1):PAGE364_I131@PURE_QUANTA.Q_CAP(CHIPS)':
 C_PATH='@s9s_mb_2u_lib.s9s_mb_2u(sch_1):page364_i131@pure_quanta.q_cap(chips)';

PART_NAME
 C405 'Q_CAP_C0402-22UF,4V,20%,X6S,CHA':;

SECTION_NUMBER 1
 '@S9S_MB_2U_LIB.S9S_MB_2U(SCH_1):PAGE364_I103@PURE_QUANTA.Q_CAP(CHIPS)':
 C_PATH='@s9s_mb_2u_lib.s9s_mb_2u(sch_1):page364_i103@pure_quanta.q_cap(chips)';

PART_NAME
 C404 'Q_CAP_C0402-22UF,4V,20%,X6S,CHA':;

SECTION_NUMBER 1
 '@S9S_MB_2U_LIB.S9S_MB_2U(SCH_1):PAGE364_I132@PURE_QUANTA.Q_CAP(CHIPS)':
 C_PATH='@s9s_mb_2u_lib.s9s_mb_2u(sch_1):page364_i132@pure_quanta.q_cap(chips)';

PART_NAME
 C403 'Q_CAP_C0402-22UF,4V,20%,X6S,CHA':;

SECTION_NUMBER 1
 '@S9S_MB_2U_LIB.S9S_MB_2U(SCH_1):PAGE364_I104@PURE_QUANTA.Q_CAP(CHIPS)':
 C_PATH='@s9s_mb_2u_lib.s9s_mb_2u(sch_1):page364_i104@pure_quanta.q_cap(chips)';

PART_NAME
 C402 'Q_CAP_C0402-22UF,4V,20%,X6S,CHA':;

SECTION_NUMBER 1
 '@S9S_MB_2U_LIB.S9S_MB_2U(SCH_1):PAGE364_I133@PURE_QUANTA.Q_CAP(CHIPS)':
 C_PATH='@s9s_mb_2u_lib.s9s_mb_2u(sch_1):page364_i133@pure_quanta.q_cap(chips)';

PART_NAME
 C401 'Q_CAP_C0402-22UF,4V,20%,X6S,CHA':;

SECTION_NUMBER 1
 '@S9S_MB_2U_LIB.S9S_MB_2U(SCH_1):PAGE364_I105@PURE_QUANTA.Q_CAP(CHIPS)':
 C_PATH='@s9s_mb_2u_lib.s9s_mb_2u(sch_1):page364_i105@pure_quanta.q_cap(chips)';

PART_NAME
 C400 'Q_CAP_C0402-22UF,4V,20%,X6S,CHA':;

SECTION_NUMBER 1
 '@S9S_MB_2U_LIB.S9S_MB_2U(SCH_1):PAGE364_I134@PURE_QUANTA.Q_CAP(CHIPS)':
 C_PATH='@s9s_mb_2u_lib.s9s_mb_2u(sch_1):page364_i134@pure_quanta.q_cap(chips)';

PART_NAME
 C399 'Q_CAP_C0402-22UF,4V,20%,X6S,CHA':;

SECTION_NUMBER 1
 '@S9S_MB_2U_LIB.S9S_MB_2U(SCH_1):PAGE364_I102@PURE_QUANTA.Q_CAP(CHIPS)':
 C_PATH='@s9s_mb_2u_lib.s9s_mb_2u(sch_1):page364_i102@pure_quanta.q_cap(chips)';

PART_NAME
 C220 'Q_CAP_0805-47UF,4V,20%,X6S,CH6A':;

SECTION_NUMBER 1
 '@S9S_MB_2U_LIB.S9S_MB_2U(SCH_1):PAGE364_I158@PURE_QUANTA.Q_CAP(CHIPS)':
 C_PATH='@s9s_mb_2u_lib.s9s_mb_2u(sch_1):page364_i158@pure_quanta.q_cap(chips)';

PART_NAME
 C219 'Q_CAP_0805-47UF,4V,20%,X6S,CH6A':;

SECTION_NUMBER 1
 '@S9S_MB_2U_LIB.S9S_MB_2U(SCH_1):PAGE364_I156@PURE_QUANTA.Q_CAP(CHIPS)':
 C_PATH='@s9s_mb_2u_lib.s9s_mb_2u(sch_1):page364_i156@pure_quanta.q_cap(chips)';

PART_NAME
 C218 'Q_CAP_0805-47UF,4V,20%,X6S,CH6A':;

SECTION_NUMBER 1
 '@S9S_MB_2U_LIB.S9S_MB_2U(SCH_1):PAGE364_I155@PURE_QUANTA.Q_CAP(CHIPS)':
 C_PATH='@s9s_mb_2u_lib.s9s_mb_2u(sch_1):page364_i155@pure_quanta.q_cap(chips)';

PART_NAME
 C217 'Q_CAP_0805-47UF,4V,20%,X6S,CH6A':;

SECTION_NUMBER 1
 '@S9S_MB_2U_LIB.S9S_MB_2U(SCH_1):PAGE364_I154@PURE_QUANTA.Q_CAP(CHIPS)':
 C_PATH='@s9s_mb_2u_lib.s9s_mb_2u(sch_1):page364_i154@pure_quanta.q_cap(chips)';

PART_NAME
 C216 'Q_CAP_0805-47UF,4V,20%,X6S,CH6A':;

SECTION_NUMBER 1
 '@S9S_MB_2U_LIB.S9S_MB_2U(SCH_1):PAGE364_I153@PURE_QUANTA.Q_CAP(CHIPS)':
 C_PATH='@s9s_mb_2u_lib.s9s_mb_2u(sch_1):page364_i153@pure_quanta.q_cap(chips)';

PART_NAME
 C215 'Q_CAP_0805-47UF,4V,20%,X6S,CH6A':;

SECTION_NUMBER 1
 '@S9S_MB_2U_LIB.S9S_MB_2U(SCH_1):PAGE364_I152@PURE_QUANTA.Q_CAP(CHIPS)':
 C_PATH='@s9s_mb_2u_lib.s9s_mb_2u(sch_1):page364_i152@pure_quanta.q_cap(chips)';

PART_NAME
 C214 'Q_CAP_0805-47UF,4V,20%,X6S,CH6A':;

SECTION_NUMBER 1
 '@S9S_MB_2U_LIB.S9S_MB_2U(SCH_1):PAGE364_I151@PURE_QUANTA.Q_CAP(CHIPS)':
 C_PATH='@s9s_mb_2u_lib.s9s_mb_2u(sch_1):page364_i151@pure_quanta.q_cap(chips)';

PART_NAME
 C213 'Q_CAP_0805-47UF,4V,20%,X6S,CH6A':;

SECTION_NUMBER 1
 '@S9S_MB_2U_LIB.S9S_MB_2U(SCH_1):PAGE364_I149@PURE_QUANTA.Q_CAP(CHIPS)':
 C_PATH='@s9s_mb_2u_lib.s9s_mb_2u(sch_1):page364_i149@pure_quanta.q_cap(chips)';

PART_NAME
 C212 'Q_CAP_0805-47UF,4V,20%,X6S,CH6A':;

SECTION_NUMBER 1
 '@S9S_MB_2U_LIB.S9S_MB_2U(SCH_1):PAGE364_I159@PURE_QUANTA.Q_CAP(CHIPS)':
 C_PATH='@s9s_mb_2u_lib.s9s_mb_2u(sch_1):page364_i159@pure_quanta.q_cap(chips)';

PART_NAME
 C101 'Q_CAP_0805-47UF,4V,20%,X6S,CH6A':;

SECTION_NUMBER 1
 '@S9S_MB_2U_LIB.S9S_MB_2U(SCH_1):PAGE364_I148@PURE_QUANTA.Q_CAP(CHIPS)':
 C_PATH='@s9s_mb_2u_lib.s9s_mb_2u(sch_1):page364_i148@pure_quanta.q_cap(chips)';

PART_NAME
 U9 'GTL2014PW-GTL2014PW,SMLF,IC,ALA':;

SECTION_NUMBER 1
 '@S9S_MB_2U_LIB.S9S_MB_2U(SCH_1):PAGE480_I34@PURE_QUANTA.GTL2014PW(CHIPS)':
 C_PATH='@s9s_mb_2u_lib.s9s_mb_2u(sch_1):page480_i34@pure_quanta.gtl2014pw(chips)';

PART_NAME
 R315 'Q_RES_0402LF-33,5%,1/16W,CHIP,A':;

SECTION_NUMBER 1
 '@S9S_MB_2U_LIB.S9S_MB_2U(SCH_1):PAGE480_I92@PURE_QUANTA.Q_RES(CHIPS)':
 C_PATH='@s9s_mb_2u_lib.s9s_mb_2u(sch_1):page480_i92@pure_quanta.q_res(chips)';

PART_NAME
 R314 'Q_RES_0402LF-49.9     ,1%  ,1/B':;

SECTION_NUMBER 1
 '@S9S_MB_2U_LIB.S9S_MB_2U(SCH_1):PAGE480_I89@PURE_QUANTA.Q_RES(CHIPS)':
 C_PATH='@s9s_mb_2u_lib.s9s_mb_2u(sch_1):page480_i89@pure_quanta.q_res(chips)';

PART_NAME
 R313 'Q_RES_0402LF-33,5%,1/16W,EMPTYA':;

SECTION_NUMBER 1
 '@S9S_MB_2U_LIB.S9S_MB_2U(SCH_1):PAGE480_I86@PURE_QUANTA.Q_RES(CHIPS)':
 C_PATH='@s9s_mb_2u_lib.s9s_mb_2u(sch_1):page480_i86@pure_quanta.q_res(chips)';

PART_NAME
 R312 'Q_RES_0402LF-33,5%,1/16W,EMPTYA':;

SECTION_NUMBER 1
 '@S9S_MB_2U_LIB.S9S_MB_2U(SCH_1):PAGE480_I85@PURE_QUANTA.Q_RES(CHIPS)':
 C_PATH='@s9s_mb_2u_lib.s9s_mb_2u(sch_1):page480_i85@pure_quanta.q_res(chips)';

PART_NAME
 R311 'Q_RES_0402LF-1K,1%,1/16W,CHIP,A':;

SECTION_NUMBER 1
 '@S9S_MB_2U_LIB.S9S_MB_2U(SCH_1):PAGE480_I44@PURE_QUANTA.Q_RES(CHIPS)':
 C_PATH='@s9s_mb_2u_lib.s9s_mb_2u(sch_1):page480_i44@pure_quanta.q_res(chips)';

PART_NAME
 R310 'Q_RES_0402LF-4.32K,1%,1/16W,CHA':;

SECTION_NUMBER 1
 '@S9S_MB_2U_LIB.S9S_MB_2U(SCH_1):PAGE480_I45@PURE_QUANTA.Q_RES(CHIPS)':
 C_PATH='@s9s_mb_2u_lib.s9s_mb_2u(sch_1):page480_i45@pure_quanta.q_res(chips)';

PART_NAME
 R309 'Q_RES_0402LF-0,5%,1/16W,CHIP,CA':;

SECTION_NUMBER 1
 '@S9S_MB_2U_LIB.S9S_MB_2U(SCH_1):PAGE480_I93@PURE_QUANTA.Q_RES(CHIPS)':
 C_PATH='@s9s_mb_2u_lib.s9s_mb_2u(sch_1):page480_i93@pure_quanta.q_res(chips)';

PART_NAME
 R308 'Q_RES_0402LF-0,5%,1/16W,EMPTY,A':;

SECTION_NUMBER 1
 '@S9S_MB_2U_LIB.S9S_MB_2U(SCH_1):PAGE480_I91@PURE_QUANTA.Q_RES(CHIPS)':
 C_PATH='@s9s_mb_2u_lib.s9s_mb_2u(sch_1):page480_i91@pure_quanta.q_res(chips)';

PART_NAME
 R307 'Q_RES_0402LF-0,5%,1/16W,EMPTY,A':;

SECTION_NUMBER 1
 '@S9S_MB_2U_LIB.S9S_MB_2U(SCH_1):PAGE480_I82@PURE_QUANTA.Q_RES(CHIPS)':
 C_PATH='@s9s_mb_2u_lib.s9s_mb_2u(sch_1):page480_i82@pure_quanta.q_res(chips)';

PART_NAME
 R306 'Q_RES_0402LF-0,5%,1/16W,EMPTY,A':;

SECTION_NUMBER 1
 '@S9S_MB_2U_LIB.S9S_MB_2U(SCH_1):PAGE480_I71@PURE_QUANTA.Q_RES(CHIPS)':
 C_PATH='@s9s_mb_2u_lib.s9s_mb_2u(sch_1):page480_i71@pure_quanta.q_res(chips)';

PART_NAME
 R305 'Q_RES_0402LF-0,5%,1/16W,CHIP,CA':;

SECTION_NUMBER 1
 '@S9S_MB_2U_LIB.S9S_MB_2U(SCH_1):PAGE480_I77@PURE_QUANTA.Q_RES(CHIPS)':
 C_PATH='@s9s_mb_2u_lib.s9s_mb_2u(sch_1):page480_i77@pure_quanta.q_res(chips)';

PART_NAME
 R304 'Q_RES_0402LF-33.2,1%,1/16W,CHIA':;

SECTION_NUMBER 1
 '@S9S_MB_2U_LIB.S9S_MB_2U(SCH_1):PAGE480_I72@PURE_QUANTA.Q_RES(CHIPS)':
 C_PATH='@s9s_mb_2u_lib.s9s_mb_2u(sch_1):page480_i72@pure_quanta.q_res(chips)';

PART_NAME
 R303 'Q_RES_0402LF-301,1%,1/16W,CHIPA':;

SECTION_NUMBER 1
 '@S9S_MB_2U_LIB.S9S_MB_2U(SCH_1):PAGE480_I76@PURE_QUANTA.Q_RES(CHIPS)':
 C_PATH='@s9s_mb_2u_lib.s9s_mb_2u(sch_1):page480_i76@pure_quanta.q_res(chips)';

PART_NAME
 R302 'Q_RES_0402LF-33.2,1%,1/16W,CHIA':;

SECTION_NUMBER 1
 '@S9S_MB_2U_LIB.S9S_MB_2U(SCH_1):PAGE480_I75@PURE_QUANTA.Q_RES(CHIPS)':
 C_PATH='@s9s_mb_2u_lib.s9s_mb_2u(sch_1):page480_i75@pure_quanta.q_res(chips)';

PART_NAME
 R301 'Q_RES_0402LF-301,1%,1/16W,CHIPA':;

SECTION_NUMBER 1
 '@S9S_MB_2U_LIB.S9S_MB_2U(SCH_1):PAGE480_I73@PURE_QUANTA.Q_RES(CHIPS)':
 C_PATH='@s9s_mb_2u_lib.s9s_mb_2u(sch_1):page480_i73@pure_quanta.q_res(chips)';

PART_NAME
 R300 'Q_RES_0402LF-0,5%,1/16W,CHIP,CA':;

SECTION_NUMBER 1
 '@S9S_MB_2U_LIB.S9S_MB_2U(SCH_1):PAGE480_I69@PURE_QUANTA.Q_RES(CHIPS)':
 C_PATH='@s9s_mb_2u_lib.s9s_mb_2u(sch_1):page480_i69@pure_quanta.q_res(chips)';

PART_NAME
 R299 'Q_RES_0402LF-0,5%,1/16W,CHIP,CA':;

SECTION_NUMBER 1
 '@S9S_MB_2U_LIB.S9S_MB_2U(SCH_1):PAGE480_I63@PURE_QUANTA.Q_RES(CHIPS)':
 C_PATH='@s9s_mb_2u_lib.s9s_mb_2u(sch_1):page480_i63@pure_quanta.q_res(chips)';

PART_NAME
 R298 'Q_RES_0402LF-301,1%,1/16W,CHIPA':;

SECTION_NUMBER 1
 '@S9S_MB_2U_LIB.S9S_MB_2U(SCH_1):PAGE480_I67@PURE_QUANTA.Q_RES(CHIPS)':
 C_PATH='@s9s_mb_2u_lib.s9s_mb_2u(sch_1):page480_i67@pure_quanta.q_res(chips)';

PART_NAME
 R297 'Q_RES_0402LF-0,5%,1/16W,CHIP,CA':;

SECTION_NUMBER 1
 '@S9S_MB_2U_LIB.S9S_MB_2U(SCH_1):PAGE480_I23@PURE_QUANTA.Q_RES(CHIPS)':
 C_PATH='@s9s_mb_2u_lib.s9s_mb_2u(sch_1):page480_i23@pure_quanta.q_res(chips)';

PART_NAME
 R296 'Q_RES_0402LF-301,1%,1/16W,CHIPA':;

SECTION_NUMBER 1
 '@S9S_MB_2U_LIB.S9S_MB_2U(SCH_1):PAGE480_I65@PURE_QUANTA.Q_RES(CHIPS)':
 C_PATH='@s9s_mb_2u_lib.s9s_mb_2u(sch_1):page480_i65@pure_quanta.q_res(chips)';

PART_NAME
 R83 'Q_RES_0402LF-1K,1%,1/16W,CHIP,A':;

SECTION_NUMBER 1
 '@S9S_MB_2U_LIB.S9S_MB_2U(SCH_1):PAGE480_I41@PURE_QUANTA.Q_RES(CHIPS)':
 C_PATH='@s9s_mb_2u_lib.s9s_mb_2u(sch_1):page480_i41@pure_quanta.q_res(chips)';

PART_NAME
 R82 'Q_RES_0402LF-150,1%,1/16W,CHIPA':;

SECTION_NUMBER 1
 '@S9S_MB_2U_LIB.S9S_MB_2U(SCH_1):PAGE480_I30@PURE_QUANTA.Q_RES(CHIPS)':
 C_PATH='@s9s_mb_2u_lib.s9s_mb_2u(sch_1):page480_i30@pure_quanta.q_res(chips)';

PART_NAME
 C107 'Q_CAP_0402-0.1UF,25V,10%,X7R,CA':;

SECTION_NUMBER 1
 '@S9S_MB_2U_LIB.S9S_MB_2U(SCH_1):PAGE480_I95@PURE_QUANTA.Q_CAP(CHIPS)':
 C_PATH='@s9s_mb_2u_lib.s9s_mb_2u(sch_1):page480_i95@pure_quanta.q_cap(chips)';

PART_NAME
 C100 'Q_CAP_C0402-1UF,25V,10%,X6S,CHA':;

SECTION_NUMBER 1
 '@S9S_MB_2U_LIB.S9S_MB_2U(SCH_1):PAGE480_I43@PURE_QUANTA.Q_CAP(CHIPS)':
 C_PATH='@s9s_mb_2u_lib.s9s_mb_2u(sch_1):page480_i43@pure_quanta.q_cap(chips)';

PART_NAME
 U8 'GTL2014PW-GTL2014PW,SMLF,IC,ALA':;

SECTION_NUMBER 1
 '@S9S_MB_2U_LIB.S9S_MB_2U(SCH_1):PAGE484_I85@PURE_QUANTA.GTL2014PW(CHIPS)':
 C_PATH='@s9s_mb_2u_lib.s9s_mb_2u(sch_1):page484_i85@pure_quanta.gtl2014pw(chips)';

PART_NAME
 R1775 'Q_RES_0402LF-2K,1%,1/16W,EMPTYA':;

SECTION_NUMBER 1
 '@S9S_MB_2U_LIB.S9S_MB_2U(SCH_1):PAGE484_I124@PURE_QUANTA.Q_RES(CHIPS)':
 C_PATH='@s9s_mb_2u_lib.s9s_mb_2u(sch_1):page484_i124@pure_quanta.q_res(chips)';

PART_NAME
 R1774 'Q_RES_0402LF-2K,1%,1/16W,EMPTYA':;

SECTION_NUMBER 1
 '@S9S_MB_2U_LIB.S9S_MB_2U(SCH_1):PAGE484_I122@PURE_QUANTA.Q_RES(CHIPS)':
 C_PATH='@s9s_mb_2u_lib.s9s_mb_2u(sch_1):page484_i122@pure_quanta.q_res(chips)';

PART_NAME
 R228 'Q_RES_0402LF-0,5%,1/16W,EMPTY,A':;

SECTION_NUMBER 1
 '@S9S_MB_2U_LIB.S9S_MB_2U(SCH_1):PAGE484_I81@PURE_QUANTA.Q_RES(CHIPS)':
 C_PATH='@s9s_mb_2u_lib.s9s_mb_2u(sch_1):page484_i81@pure_quanta.q_res(chips)';

PART_NAME
 R227 'Q_RES_0402LF-0,5%,1/16W,EMPTY,A':;

SECTION_NUMBER 1
 '@S9S_MB_2U_LIB.S9S_MB_2U(SCH_1):PAGE484_I80@PURE_QUANTA.Q_RES(CHIPS)':
 C_PATH='@s9s_mb_2u_lib.s9s_mb_2u(sch_1):page484_i80@pure_quanta.q_res(chips)';

PART_NAME
 R226 'Q_RES_0402LF-0,5%,1/16W,EMPTY,A':;

SECTION_NUMBER 1
 '@S9S_MB_2U_LIB.S9S_MB_2U(SCH_1):PAGE484_I79@PURE_QUANTA.Q_RES(CHIPS)':
 C_PATH='@s9s_mb_2u_lib.s9s_mb_2u(sch_1):page484_i79@pure_quanta.q_res(chips)';

PART_NAME
 R225 'Q_RES_0402LF-0,5%,1/16W,EMPTY,A':;

SECTION_NUMBER 1
 '@S9S_MB_2U_LIB.S9S_MB_2U(SCH_1):PAGE484_I75@PURE_QUANTA.Q_RES(CHIPS)':
 C_PATH='@s9s_mb_2u_lib.s9s_mb_2u(sch_1):page484_i75@pure_quanta.q_res(chips)';

PART_NAME
 R224 'Q_RES_0402LF-1K,1%,1/16W,CHIP,A':;

SECTION_NUMBER 1
 '@S9S_MB_2U_LIB.S9S_MB_2U(SCH_1):PAGE484_I117@PURE_QUANTA.Q_RES(CHIPS)':
 C_PATH='@s9s_mb_2u_lib.s9s_mb_2u(sch_1):page484_i117@pure_quanta.q_res(chips)';

PART_NAME
 R223 'Q_RES_0402LF-4.32K,1%,1/16W,CHA':;

SECTION_NUMBER 1
 '@S9S_MB_2U_LIB.S9S_MB_2U(SCH_1):PAGE484_I116@PURE_QUANTA.Q_RES(CHIPS)':
 C_PATH='@s9s_mb_2u_lib.s9s_mb_2u(sch_1):page484_i116@pure_quanta.q_res(chips)';

PART_NAME
 R222 'Q_RES_0402LF-100,1%,1/16W,EMPTA':;

SECTION_NUMBER 1
 '@S9S_MB_2U_LIB.S9S_MB_2U(SCH_1):PAGE484_I62@PURE_QUANTA.Q_RES(CHIPS)':
 C_PATH='@s9s_mb_2u_lib.s9s_mb_2u(sch_1):page484_i62@pure_quanta.q_res(chips)';

PART_NAME
 R221 'Q_RES_0402LF-100,1%,1/16W,EMPTA':;

SECTION_NUMBER 1
 '@S9S_MB_2U_LIB.S9S_MB_2U(SCH_1):PAGE484_I53@PURE_QUANTA.Q_RES(CHIPS)':
 C_PATH='@s9s_mb_2u_lib.s9s_mb_2u(sch_1):page484_i53@pure_quanta.q_res(chips)';

PART_NAME
 R220 'Q_RES_0402LF-100,1%,1/16W,CHIPA':;

SECTION_NUMBER 1
 '@S9S_MB_2U_LIB.S9S_MB_2U(SCH_1):PAGE484_I63@PURE_QUANTA.Q_RES(CHIPS)':
 C_PATH='@s9s_mb_2u_lib.s9s_mb_2u(sch_1):page484_i63@pure_quanta.q_res(chips)';

PART_NAME
 R219 'Q_RES_0402LF-100,1%,1/16W,CHIPA':;

SECTION_NUMBER 1
 '@S9S_MB_2U_LIB.S9S_MB_2U(SCH_1):PAGE484_I54@PURE_QUANTA.Q_RES(CHIPS)':
 C_PATH='@s9s_mb_2u_lib.s9s_mb_2u(sch_1):page484_i54@pure_quanta.q_res(chips)';

PART_NAME
 R218 'Q_RES_0402LF-0,5%,1/16W,CHIP,CA':;

SECTION_NUMBER 1
 '@S9S_MB_2U_LIB.S9S_MB_2U(SCH_1):PAGE484_I93@PURE_QUANTA.Q_RES(CHIPS)':
 C_PATH='@s9s_mb_2u_lib.s9s_mb_2u(sch_1):page484_i93@pure_quanta.q_res(chips)';

PART_NAME
 R217 'Q_RES_0402LF-0,5%,1/16W,CHIP,CA':;

SECTION_NUMBER 1
 '@S9S_MB_2U_LIB.S9S_MB_2U(SCH_1):PAGE484_I92@PURE_QUANTA.Q_RES(CHIPS)':
 C_PATH='@s9s_mb_2u_lib.s9s_mb_2u(sch_1):page484_i92@pure_quanta.q_res(chips)';

PART_NAME
 R216 'Q_RES_0402LF-0,5%,1/16W,CHIP,CA':;

SECTION_NUMBER 1
 '@S9S_MB_2U_LIB.S9S_MB_2U(SCH_1):PAGE484_I94@PURE_QUANTA.Q_RES(CHIPS)':
 C_PATH='@s9s_mb_2u_lib.s9s_mb_2u(sch_1):page484_i94@pure_quanta.q_res(chips)';

PART_NAME
 R215 'Q_RES_0402LF-0,5%,1/16W,CHIP,CA':;

SECTION_NUMBER 1
 '@S9S_MB_2U_LIB.S9S_MB_2U(SCH_1):PAGE484_I91@PURE_QUANTA.Q_RES(CHIPS)':
 C_PATH='@s9s_mb_2u_lib.s9s_mb_2u(sch_1):page484_i91@pure_quanta.q_res(chips)';

PART_NAME
 R214 'Q_RES_0402LF-0,5%,1/16W,EMPTY,A':;

SECTION_NUMBER 1
 '@S9S_MB_2U_LIB.S9S_MB_2U(SCH_1):PAGE484_I90@PURE_QUANTA.Q_RES(CHIPS)':
 C_PATH='@s9s_mb_2u_lib.s9s_mb_2u(sch_1):page484_i90@pure_quanta.q_res(chips)';

PART_NAME
 R213 'Q_RES_0402LF-0,5%,1/16W,EMPTY,A':;

SECTION_NUMBER 1
 '@S9S_MB_2U_LIB.S9S_MB_2U(SCH_1):PAGE484_I89@PURE_QUANTA.Q_RES(CHIPS)':
 C_PATH='@s9s_mb_2u_lib.s9s_mb_2u(sch_1):page484_i89@pure_quanta.q_res(chips)';

PART_NAME
 R212 'Q_RES_0402LF-0,5%,1/16W,EMPTY,A':;

SECTION_NUMBER 1
 '@S9S_MB_2U_LIB.S9S_MB_2U(SCH_1):PAGE484_I88@PURE_QUANTA.Q_RES(CHIPS)':
 C_PATH='@s9s_mb_2u_lib.s9s_mb_2u(sch_1):page484_i88@pure_quanta.q_res(chips)';

PART_NAME
 R211 'Q_RES_0402LF-0,5%,1/16W,EMPTY,A':;

SECTION_NUMBER 1
 '@S9S_MB_2U_LIB.S9S_MB_2U(SCH_1):PAGE484_I87@PURE_QUANTA.Q_RES(CHIPS)':
 C_PATH='@s9s_mb_2u_lib.s9s_mb_2u(sch_1):page484_i87@pure_quanta.q_res(chips)';

PART_NAME
 R210 'Q_RES_0402LF-0,5%,1/16W,CHIP,CA':;

SECTION_NUMBER 1
 '@S9S_MB_2U_LIB.S9S_MB_2U(SCH_1):PAGE484_I66@PURE_QUANTA.Q_RES(CHIPS)':
 C_PATH='@s9s_mb_2u_lib.s9s_mb_2u(sch_1):page484_i66@pure_quanta.q_res(chips)';

PART_NAME
 R209 'Q_RES_0402LF-0,5%,1/16W,EMPTY,A':;

SECTION_NUMBER 1
 '@S9S_MB_2U_LIB.S9S_MB_2U(SCH_1):PAGE484_I65@PURE_QUANTA.Q_RES(CHIPS)':
 C_PATH='@s9s_mb_2u_lib.s9s_mb_2u(sch_1):page484_i65@pure_quanta.q_res(chips)';

PART_NAME
 R208 'Q_RES_0402LF-0,5%,1/16W,CHIP,CA':;

SECTION_NUMBER 1
 '@S9S_MB_2U_LIB.S9S_MB_2U(SCH_1):PAGE484_I26@PURE_QUANTA.Q_RES(CHIPS)':
 C_PATH='@s9s_mb_2u_lib.s9s_mb_2u(sch_1):page484_i26@pure_quanta.q_res(chips)';

PART_NAME
 R207 'Q_RES_0402LF-0,5%,1/16W,EMPTY,A':;

SECTION_NUMBER 1
 '@S9S_MB_2U_LIB.S9S_MB_2U(SCH_1):PAGE484_I23@PURE_QUANTA.Q_RES(CHIPS)':
 C_PATH='@s9s_mb_2u_lib.s9s_mb_2u(sch_1):page484_i23@pure_quanta.q_res(chips)';

PART_NAME
 R206 'Q_RES_0402LF-33,5%,1/16W,CHIP,A':;

SECTION_NUMBER 1
 '@S9S_MB_2U_LIB.S9S_MB_2U(SCH_1):PAGE484_I99@PURE_QUANTA.Q_RES(CHIPS)':
 C_PATH='@s9s_mb_2u_lib.s9s_mb_2u(sch_1):page484_i99@pure_quanta.q_res(chips)';

PART_NAME
 R205 'Q_RES_0402LF-33,5%,1/16W,CHIP,A':;

SECTION_NUMBER 1
 '@S9S_MB_2U_LIB.S9S_MB_2U(SCH_1):PAGE484_I101@PURE_QUANTA.Q_RES(CHIPS)':
 C_PATH='@s9s_mb_2u_lib.s9s_mb_2u(sch_1):page484_i101@pure_quanta.q_res(chips)';

PART_NAME
 R204 'Q_RES_0402LF-33,5%,1/16W,CHIP,A':;

SECTION_NUMBER 1
 '@S9S_MB_2U_LIB.S9S_MB_2U(SCH_1):PAGE484_I100@PURE_QUANTA.Q_RES(CHIPS)':
 C_PATH='@s9s_mb_2u_lib.s9s_mb_2u(sch_1):page484_i100@pure_quanta.q_res(chips)';

PART_NAME
 R203 'Q_RES_0402LF-33,5%,1/16W,CHIP,A':;

SECTION_NUMBER 1
 '@S9S_MB_2U_LIB.S9S_MB_2U(SCH_1):PAGE484_I98@PURE_QUANTA.Q_RES(CHIPS)':
 C_PATH='@s9s_mb_2u_lib.s9s_mb_2u(sch_1):page484_i98@pure_quanta.q_res(chips)';

PART_NAME
 R202 'Q_RES_0402LF-100,1%,1/16W,EMPTA':;

SECTION_NUMBER 1
 '@S9S_MB_2U_LIB.S9S_MB_2U(SCH_1):PAGE484_I110@PURE_QUANTA.Q_RES(CHIPS)':
 C_PATH='@s9s_mb_2u_lib.s9s_mb_2u(sch_1):page484_i110@pure_quanta.q_res(chips)';

PART_NAME
 R201 'Q_RES_0402LF-100,1%,1/16W,EMPTA':;

SECTION_NUMBER 1
 '@S9S_MB_2U_LIB.S9S_MB_2U(SCH_1):PAGE484_I108@PURE_QUANTA.Q_RES(CHIPS)':
 C_PATH='@s9s_mb_2u_lib.s9s_mb_2u(sch_1):page484_i108@pure_quanta.q_res(chips)';

PART_NAME
 R200 'Q_RES_0402LF-100,1%,1/16W,EMPTA':;

SECTION_NUMBER 1
 '@S9S_MB_2U_LIB.S9S_MB_2U(SCH_1):PAGE484_I102@PURE_QUANTA.Q_RES(CHIPS)':
 C_PATH='@s9s_mb_2u_lib.s9s_mb_2u(sch_1):page484_i102@pure_quanta.q_res(chips)';

PART_NAME
 R199 'Q_RES_0402LF-100,1%,1/16W,EMPTA':;

SECTION_NUMBER 1
 '@S9S_MB_2U_LIB.S9S_MB_2U(SCH_1):PAGE484_I111@PURE_QUANTA.Q_RES(CHIPS)':
 C_PATH='@s9s_mb_2u_lib.s9s_mb_2u(sch_1):page484_i111@pure_quanta.q_res(chips)';

PART_NAME
 R81 'Q_RES_0402LF-1K,1%,1/16W,CHIP,A':;

SECTION_NUMBER 1
 '@S9S_MB_2U_LIB.S9S_MB_2U(SCH_1):PAGE484_I78@PURE_QUANTA.Q_RES(CHIPS)':
 C_PATH='@s9s_mb_2u_lib.s9s_mb_2u(sch_1):page484_i78@pure_quanta.q_res(chips)';

PART_NAME
 Q28 'MOSFET_N_123-BSS123-7-F,SMLF,IA':;

SECTION_NUMBER 1
 '@S9S_MB_2U_LIB.S9S_MB_2U(SCH_1):PAGE484_I121@PURE_QUANTA.MOSFET_N_123(CHIPS)':
 C_PATH='@s9s_mb_2u_lib.s9s_mb_2u(sch_1):page484_i121@pure_quanta.mosfet_n_123(chi~
ps)';

PART_NAME
 Q27 'MOSFET_N_123-BSS123-7-F,SMLF,IA':;

SECTION_NUMBER 1
 '@S9S_MB_2U_LIB.S9S_MB_2U(SCH_1):PAGE484_I120@PURE_QUANTA.MOSFET_N_123(CHIPS)':
 C_PATH='@s9s_mb_2u_lib.s9s_mb_2u(sch_1):page484_i120@pure_quanta.mosfet_n_123(chi~
ps)';

PART_NAME
 C106 'Q_CAP_0402-0.1UF,25V,10%,X7R,CA':;

SECTION_NUMBER 1
 '@S9S_MB_2U_LIB.S9S_MB_2U(SCH_1):PAGE484_I114@PURE_QUANTA.Q_CAP(CHIPS)':
 C_PATH='@s9s_mb_2u_lib.s9s_mb_2u(sch_1):page484_i114@pure_quanta.q_cap(chips)';

PART_NAME
 C99 'Q_CAP_C0402-1UF,25V,10%,X6S,CHA':;

SECTION_NUMBER 1
 '@S9S_MB_2U_LIB.S9S_MB_2U(SCH_1):PAGE484_I82@PURE_QUANTA.Q_CAP(CHIPS)':
 C_PATH='@s9s_mb_2u_lib.s9s_mb_2u(sch_1):page484_i82@pure_quanta.q_cap(chips)';

PART_NAME
 R80 'Q_RES_0402LF-196K,1%,1/16W,CHIA':;

SECTION_NUMBER 1
 '@S9S_MB_2U_LIB.S9S_MB_2U(SCH_1):PAGE390_I2@PURE_QUANTA.Q_RES(CHIPS)':
 C_PATH='@s9s_mb_2u_lib.s9s_mb_2u(sch_1):page390_i2@pure_quanta.q_res(chips)';

PART_NAME
 J24 'SCONN288_ADR50001P003C01-SCONNA':;

SECTION_NUMBER 1
 '@S9S_MB_2U_LIB.S9S_MB_2U(SCH_1):PAGE390_I178@PURE_QUANTA.SCONN288_ADR50001P003C01(CHIPS)':
 C_PATH='@s9s_mb_2u_lib.s9s_mb_2u(sch_1):page390_i178@pure_quanta.sconn288_adr5000~
1p003c01(chips)';

SECTION_NUMBER 2
 '@S9S_MB_2U_LIB.S9S_MB_2U(SCH_1):PAGE390_I179@PURE_QUANTA.SCONN288_ADR50001P003C01(CHIPS)':
 C_PATH='@s9s_mb_2u_lib.s9s_mb_2u(sch_1):page390_i179@pure_quanta.sconn288_adr5000~
1p003c01(chips)';

SECTION_NUMBER 3
 '@S9S_MB_2U_LIB.S9S_MB_2U(SCH_1):PAGE390_I180@PURE_QUANTA.SCONN288_ADR50001P003C01(CHIPS)':
 C_PATH='@s9s_mb_2u_lib.s9s_mb_2u(sch_1):page390_i180@pure_quanta.sconn288_adr5000~
1p003c01(chips)';

PART_NAME
 C98 'Q_CAP_C0805-10UF,16V,10%,X7R,CA':;

SECTION_NUMBER 1
 '@S9S_MB_2U_LIB.S9S_MB_2U(SCH_1):PAGE390_I146@PURE_QUANTA.Q_CAP(CHIPS)':
 C_PATH='@s9s_mb_2u_lib.s9s_mb_2u(sch_1):page390_i146@pure_quanta.q_cap(chips)';

PART_NAME
 C97 'Q_CAP_C0805-10UF,16V,10%,X7R,CA':;

SECTION_NUMBER 1
 '@S9S_MB_2U_LIB.S9S_MB_2U(SCH_1):PAGE390_I124@PURE_QUANTA.Q_CAP(CHIPS)':
 C_PATH='@s9s_mb_2u_lib.s9s_mb_2u(sch_1):page390_i124@pure_quanta.q_cap(chips)';

PART_NAME
 C96 'Q_CAP_C0402-2.2UF,6.3V,20%,X6SA':;

SECTION_NUMBER 1
 '@S9S_MB_2U_LIB.S9S_MB_2U(SCH_1):PAGE390_I123@PURE_QUANTA.Q_CAP(CHIPS)':
 C_PATH='@s9s_mb_2u_lib.s9s_mb_2u(sch_1):page390_i123@pure_quanta.q_cap(chips)';

PART_NAME
 R79 'Q_RES_0402LF-10K,1%,1/16W,CHIPA':;

SECTION_NUMBER 1
 '@S9S_MB_2U_LIB.S9S_MB_2U(SCH_1):PAGE391_I2@PURE_QUANTA.Q_RES(CHIPS)':
 C_PATH='@s9s_mb_2u_lib.s9s_mb_2u(sch_1):page391_i2@pure_quanta.q_res(chips)';

PART_NAME
 J25 'SCONN288_ADR50001P013C01-SCONNA':;

SECTION_NUMBER 1
 '@S9S_MB_2U_LIB.S9S_MB_2U(SCH_1):PAGE391_I180@PURE_QUANTA.SCONN288_ADR50001P013C01(CHIPS)':
 C_PATH='@s9s_mb_2u_lib.s9s_mb_2u(sch_1):page391_i180@pure_quanta.sconn288_adr5000~
1p013c01(chips)';

SECTION_NUMBER 2
 '@S9S_MB_2U_LIB.S9S_MB_2U(SCH_1):PAGE391_I179@PURE_QUANTA.SCONN288_ADR50001P013C01(CHIPS)':
 C_PATH='@s9s_mb_2u_lib.s9s_mb_2u(sch_1):page391_i179@pure_quanta.sconn288_adr5000~
1p013c01(chips)';

SECTION_NUMBER 3
 '@S9S_MB_2U_LIB.S9S_MB_2U(SCH_1):PAGE391_I178@PURE_QUANTA.SCONN288_ADR50001P013C01(CHIPS)':
 C_PATH='@s9s_mb_2u_lib.s9s_mb_2u(sch_1):page391_i178@pure_quanta.sconn288_adr5000~
1p013c01(chips)';

PART_NAME
 C95 'Q_CAP_C0805-10UF,16V,10%,X7R,CA':;

SECTION_NUMBER 1
 '@S9S_MB_2U_LIB.S9S_MB_2U(SCH_1):PAGE391_I130@PURE_QUANTA.Q_CAP(CHIPS)':
 C_PATH='@s9s_mb_2u_lib.s9s_mb_2u(sch_1):page391_i130@pure_quanta.q_cap(chips)';

PART_NAME
 C94 'Q_CAP_C0805-10UF,16V,10%,X7R,CA':;

SECTION_NUMBER 1
 '@S9S_MB_2U_LIB.S9S_MB_2U(SCH_1):PAGE391_I127@PURE_QUANTA.Q_CAP(CHIPS)':
 C_PATH='@s9s_mb_2u_lib.s9s_mb_2u(sch_1):page391_i127@pure_quanta.q_cap(chips)';

PART_NAME
 C93 'Q_CAP_C0402-2.2UF,6.3V,20%,X6SA':;

SECTION_NUMBER 1
 '@S9S_MB_2U_LIB.S9S_MB_2U(SCH_1):PAGE391_I122@PURE_QUANTA.Q_CAP(CHIPS)':
 C_PATH='@s9s_mb_2u_lib.s9s_mb_2u(sch_1):page391_i122@pure_quanta.q_cap(chips)';

PART_NAME
 R78 'Q_RES_0402LF-15.4K,1%,1/16W,CHA':;

SECTION_NUMBER 1
 '@S9S_MB_2U_LIB.S9S_MB_2U(SCH_1):PAGE392_I2@PURE_QUANTA.Q_RES(CHIPS)':
 C_PATH='@s9s_mb_2u_lib.s9s_mb_2u(sch_1):page392_i2@pure_quanta.q_res(chips)';

PART_NAME
 J26 'SCONN288_ADR50001P003C01-SCONNA':;

SECTION_NUMBER 1
 '@S9S_MB_2U_LIB.S9S_MB_2U(SCH_1):PAGE392_I180@PURE_QUANTA.SCONN288_ADR50001P003C01(CHIPS)':
 C_PATH='@s9s_mb_2u_lib.s9s_mb_2u(sch_1):page392_i180@pure_quanta.sconn288_adr5000~
1p003c01(chips)';

SECTION_NUMBER 2
 '@S9S_MB_2U_LIB.S9S_MB_2U(SCH_1):PAGE392_I178@PURE_QUANTA.SCONN288_ADR50001P003C01(CHIPS)':
 C_PATH='@s9s_mb_2u_lib.s9s_mb_2u(sch_1):page392_i178@pure_quanta.sconn288_adr5000~
1p003c01(chips)';

SECTION_NUMBER 3
 '@S9S_MB_2U_LIB.S9S_MB_2U(SCH_1):PAGE392_I179@PURE_QUANTA.SCONN288_ADR50001P003C01(CHIPS)':
 C_PATH='@s9s_mb_2u_lib.s9s_mb_2u(sch_1):page392_i179@pure_quanta.sconn288_adr5000~
1p003c01(chips)';

PART_NAME
 C92 'Q_CAP_C0805-10UF,16V,10%,X7R,CA':;

SECTION_NUMBER 1
 '@S9S_MB_2U_LIB.S9S_MB_2U(SCH_1):PAGE392_I128@PURE_QUANTA.Q_CAP(CHIPS)':
 C_PATH='@s9s_mb_2u_lib.s9s_mb_2u(sch_1):page392_i128@pure_quanta.q_cap(chips)';

PART_NAME
 C91 'Q_CAP_C0805-10UF,16V,10%,X7R,CA':;

SECTION_NUMBER 1
 '@S9S_MB_2U_LIB.S9S_MB_2U(SCH_1):PAGE392_I126@PURE_QUANTA.Q_CAP(CHIPS)':
 C_PATH='@s9s_mb_2u_lib.s9s_mb_2u(sch_1):page392_i126@pure_quanta.q_cap(chips)';

PART_NAME
 C90 'Q_CAP_C0402-2.2UF,6.3V,20%,X6SA':;

SECTION_NUMBER 1
 '@S9S_MB_2U_LIB.S9S_MB_2U(SCH_1):PAGE392_I122@PURE_QUANTA.Q_CAP(CHIPS)':
 C_PATH='@s9s_mb_2u_lib.s9s_mb_2u(sch_1):page392_i122@pure_quanta.q_cap(chips)';

PART_NAME
 R77 'Q_RES_0402LF-23.2K,1%,1/16W,CHA':;

SECTION_NUMBER 1
 '@S9S_MB_2U_LIB.S9S_MB_2U(SCH_1):PAGE393_I10@PURE_QUANTA.Q_RES(CHIPS)':
 C_PATH='@s9s_mb_2u_lib.s9s_mb_2u(sch_1):page393_i10@pure_quanta.q_res(chips)';

PART_NAME
 J27 'SCONN288_ADR50001P013C01-SCONNA':;

SECTION_NUMBER 1
 '@S9S_MB_2U_LIB.S9S_MB_2U(SCH_1):PAGE393_I179@PURE_QUANTA.SCONN288_ADR50001P013C01(CHIPS)':
 C_PATH='@s9s_mb_2u_lib.s9s_mb_2u(sch_1):page393_i179@pure_quanta.sconn288_adr5000~
1p013c01(chips)';

SECTION_NUMBER 2
 '@S9S_MB_2U_LIB.S9S_MB_2U(SCH_1):PAGE393_I177@PURE_QUANTA.SCONN288_ADR50001P013C01(CHIPS)':
 C_PATH='@s9s_mb_2u_lib.s9s_mb_2u(sch_1):page393_i177@pure_quanta.sconn288_adr5000~
1p013c01(chips)';

SECTION_NUMBER 3
 '@S9S_MB_2U_LIB.S9S_MB_2U(SCH_1):PAGE393_I178@PURE_QUANTA.SCONN288_ADR50001P013C01(CHIPS)':
 C_PATH='@s9s_mb_2u_lib.s9s_mb_2u(sch_1):page393_i178@pure_quanta.sconn288_adr5000~
1p013c01(chips)';

PART_NAME
 C89 'Q_CAP_C0805-10UF,16V,10%,X7R,CA':;

SECTION_NUMBER 1
 '@S9S_MB_2U_LIB.S9S_MB_2U(SCH_1):PAGE393_I160@PURE_QUANTA.Q_CAP(CHIPS)':
 C_PATH='@s9s_mb_2u_lib.s9s_mb_2u(sch_1):page393_i160@pure_quanta.q_cap(chips)';

PART_NAME
 C88 'Q_CAP_C0805-10UF,16V,10%,X7R,CA':;

SECTION_NUMBER 1
 '@S9S_MB_2U_LIB.S9S_MB_2U(SCH_1):PAGE393_I123@PURE_QUANTA.Q_CAP(CHIPS)':
 C_PATH='@s9s_mb_2u_lib.s9s_mb_2u(sch_1):page393_i123@pure_quanta.q_cap(chips)';

PART_NAME
 C87 'Q_CAP_C0402-2.2UF,6.3V,20%,X6SA':;

SECTION_NUMBER 1
 '@S9S_MB_2U_LIB.S9S_MB_2U(SCH_1):PAGE393_I121@PURE_QUANTA.Q_CAP(CHIPS)':
 C_PATH='@s9s_mb_2u_lib.s9s_mb_2u(sch_1):page393_i121@pure_quanta.q_cap(chips)';

PART_NAME
 R76 'Q_RES_0402LF-35.7K,1%,1/16W,CHA':;

SECTION_NUMBER 1
 '@S9S_MB_2U_LIB.S9S_MB_2U(SCH_1):PAGE394_I46@PURE_QUANTA.Q_RES(CHIPS)':
 C_PATH='@s9s_mb_2u_lib.s9s_mb_2u(sch_1):page394_i46@pure_quanta.q_res(chips)';

PART_NAME
 J28 'SCONN288_ADR50001P003C01-SCONNA':;

SECTION_NUMBER 1
 '@S9S_MB_2U_LIB.S9S_MB_2U(SCH_1):PAGE394_I47@PURE_QUANTA.SCONN288_ADR50001P003C01(CHIPS)':
 C_PATH='@s9s_mb_2u_lib.s9s_mb_2u(sch_1):page394_i47@pure_quanta.sconn288_adr50001~
p003c01(chips)';

SECTION_NUMBER 2
 '@S9S_MB_2U_LIB.S9S_MB_2U(SCH_1):PAGE394_I124@PURE_QUANTA.SCONN288_ADR50001P003C01(CHIPS)':
 C_PATH='@s9s_mb_2u_lib.s9s_mb_2u(sch_1):page394_i124@pure_quanta.sconn288_adr5000~
1p003c01(chips)';

SECTION_NUMBER 3
 '@S9S_MB_2U_LIB.S9S_MB_2U(SCH_1):PAGE394_I176@PURE_QUANTA.SCONN288_ADR50001P003C01(CHIPS)':
 C_PATH='@s9s_mb_2u_lib.s9s_mb_2u(sch_1):page394_i176@pure_quanta.sconn288_adr5000~
1p003c01(chips)';

PART_NAME
 C86 'Q_CAP_C0805-10UF,16V,10%,X7R,CA':;

SECTION_NUMBER 1
 '@S9S_MB_2U_LIB.S9S_MB_2U(SCH_1):PAGE394_I128@PURE_QUANTA.Q_CAP(CHIPS)':
 C_PATH='@s9s_mb_2u_lib.s9s_mb_2u(sch_1):page394_i128@pure_quanta.q_cap(chips)';

PART_NAME
 C85 'Q_CAP_C0805-10UF,16V,10%,X7R,CA':;

SECTION_NUMBER 1
 '@S9S_MB_2U_LIB.S9S_MB_2U(SCH_1):PAGE394_I125@PURE_QUANTA.Q_CAP(CHIPS)':
 C_PATH='@s9s_mb_2u_lib.s9s_mb_2u(sch_1):page394_i125@pure_quanta.q_cap(chips)';

PART_NAME
 C84 'Q_CAP_C0402-2.2UF,6.3V,20%,X6SA':;

SECTION_NUMBER 1
 '@S9S_MB_2U_LIB.S9S_MB_2U(SCH_1):PAGE394_I121@PURE_QUANTA.Q_CAP(CHIPS)':
 C_PATH='@s9s_mb_2u_lib.s9s_mb_2u(sch_1):page394_i121@pure_quanta.q_cap(chips)';

PART_NAME
 R75 'Q_RES_0402LF-54.9K,1%,1/16W,CHA':;

SECTION_NUMBER 1
 '@S9S_MB_2U_LIB.S9S_MB_2U(SCH_1):PAGE395_I47@PURE_QUANTA.Q_RES(CHIPS)':
 C_PATH='@s9s_mb_2u_lib.s9s_mb_2u(sch_1):page395_i47@pure_quanta.q_res(chips)';

PART_NAME
 J29 'SCONN288_ADR50001P013C01-SCONNA':;

SECTION_NUMBER 1
 '@S9S_MB_2U_LIB.S9S_MB_2U(SCH_1):PAGE395_I179@PURE_QUANTA.SCONN288_ADR50001P013C01(CHIPS)':
 C_PATH='@s9s_mb_2u_lib.s9s_mb_2u(sch_1):page395_i179@pure_quanta.sconn288_adr5000~
1p013c01(chips)';

SECTION_NUMBER 2
 '@S9S_MB_2U_LIB.S9S_MB_2U(SCH_1):PAGE395_I177@PURE_QUANTA.SCONN288_ADR50001P013C01(CHIPS)':
 C_PATH='@s9s_mb_2u_lib.s9s_mb_2u(sch_1):page395_i177@pure_quanta.sconn288_adr5000~
1p013c01(chips)';

SECTION_NUMBER 3
 '@S9S_MB_2U_LIB.S9S_MB_2U(SCH_1):PAGE395_I178@PURE_QUANTA.SCONN288_ADR50001P013C01(CHIPS)':
 C_PATH='@s9s_mb_2u_lib.s9s_mb_2u(sch_1):page395_i178@pure_quanta.sconn288_adr5000~
1p013c01(chips)';

PART_NAME
 C83 'Q_CAP_C0805-10UF,16V,10%,X7R,CA':;

SECTION_NUMBER 1
 '@S9S_MB_2U_LIB.S9S_MB_2U(SCH_1):PAGE395_I126@PURE_QUANTA.Q_CAP(CHIPS)':
 C_PATH='@s9s_mb_2u_lib.s9s_mb_2u(sch_1):page395_i126@pure_quanta.q_cap(chips)';

PART_NAME
 C82 'Q_CAP_C0805-10UF,16V,10%,X7R,CA':;

SECTION_NUMBER 1
 '@S9S_MB_2U_LIB.S9S_MB_2U(SCH_1):PAGE395_I124@PURE_QUANTA.Q_CAP(CHIPS)':
 C_PATH='@s9s_mb_2u_lib.s9s_mb_2u(sch_1):page395_i124@pure_quanta.q_cap(chips)';

PART_NAME
 C81 'Q_CAP_C0402-2.2UF,6.3V,20%,X6SA':;

SECTION_NUMBER 1
 '@S9S_MB_2U_LIB.S9S_MB_2U(SCH_1):PAGE395_I120@PURE_QUANTA.Q_CAP(CHIPS)':
 C_PATH='@s9s_mb_2u_lib.s9s_mb_2u(sch_1):page395_i120@pure_quanta.q_cap(chips)';

PART_NAME
 R74 'Q_RES_0402LF-84.5K,1%,1/16W,CHA':;

SECTION_NUMBER 1
 '@S9S_MB_2U_LIB.S9S_MB_2U(SCH_1):PAGE396_I5@PURE_QUANTA.Q_RES(CHIPS)':
 C_PATH='@s9s_mb_2u_lib.s9s_mb_2u(sch_1):page396_i5@pure_quanta.q_res(chips)';

PART_NAME
 J30 'SCONN288_ADR50001P003C01-SCONNA':;

SECTION_NUMBER 1
 '@S9S_MB_2U_LIB.S9S_MB_2U(SCH_1):PAGE396_I179@PURE_QUANTA.SCONN288_ADR50001P003C01(CHIPS)':
 C_PATH='@s9s_mb_2u_lib.s9s_mb_2u(sch_1):page396_i179@pure_quanta.sconn288_adr5000~
1p003c01(chips)';

SECTION_NUMBER 2
 '@S9S_MB_2U_LIB.S9S_MB_2U(SCH_1):PAGE396_I177@PURE_QUANTA.SCONN288_ADR50001P003C01(CHIPS)':
 C_PATH='@s9s_mb_2u_lib.s9s_mb_2u(sch_1):page396_i177@pure_quanta.sconn288_adr5000~
1p003c01(chips)';

SECTION_NUMBER 3
 '@S9S_MB_2U_LIB.S9S_MB_2U(SCH_1):PAGE396_I178@PURE_QUANTA.SCONN288_ADR50001P003C01(CHIPS)':
 C_PATH='@s9s_mb_2u_lib.s9s_mb_2u(sch_1):page396_i178@pure_quanta.sconn288_adr5000~
1p003c01(chips)';

PART_NAME
 C80 'Q_CAP_C0805-10UF,16V,10%,X7R,CA':;

SECTION_NUMBER 1
 '@S9S_MB_2U_LIB.S9S_MB_2U(SCH_1):PAGE396_I59@PURE_QUANTA.Q_CAP(CHIPS)':
 C_PATH='@s9s_mb_2u_lib.s9s_mb_2u(sch_1):page396_i59@pure_quanta.q_cap(chips)';

PART_NAME
 C79 'Q_CAP_C0805-10UF,16V,10%,X7R,CA':;

SECTION_NUMBER 1
 '@S9S_MB_2U_LIB.S9S_MB_2U(SCH_1):PAGE396_I56@PURE_QUANTA.Q_CAP(CHIPS)':
 C_PATH='@s9s_mb_2u_lib.s9s_mb_2u(sch_1):page396_i56@pure_quanta.q_cap(chips)';

PART_NAME
 C78 'Q_CAP_C0402-2.2UF,6.3V,20%,X6SA':;

SECTION_NUMBER 1
 '@S9S_MB_2U_LIB.S9S_MB_2U(SCH_1):PAGE396_I54@PURE_QUANTA.Q_CAP(CHIPS)':
 C_PATH='@s9s_mb_2u_lib.s9s_mb_2u(sch_1):page396_i54@pure_quanta.q_cap(chips)';

PART_NAME
 R73 'Q_RES_0402LF-127K,1%,1/16W,CHIA':;

SECTION_NUMBER 1
 '@S9S_MB_2U_LIB.S9S_MB_2U(SCH_1):PAGE397_I3@PURE_QUANTA.Q_RES(CHIPS)':
 C_PATH='@s9s_mb_2u_lib.s9s_mb_2u(sch_1):page397_i3@pure_quanta.q_res(chips)';

PART_NAME
 J31 'SCONN288_ADR50001P013C01-SCONNA':;

SECTION_NUMBER 1
 '@S9S_MB_2U_LIB.S9S_MB_2U(SCH_1):PAGE397_I180@PURE_QUANTA.SCONN288_ADR50001P013C01(CHIPS)':
 C_PATH='@s9s_mb_2u_lib.s9s_mb_2u(sch_1):page397_i180@pure_quanta.sconn288_adr5000~
1p013c01(chips)';

SECTION_NUMBER 2
 '@S9S_MB_2U_LIB.S9S_MB_2U(SCH_1):PAGE397_I179@PURE_QUANTA.SCONN288_ADR50001P013C01(CHIPS)':
 C_PATH='@s9s_mb_2u_lib.s9s_mb_2u(sch_1):page397_i179@pure_quanta.sconn288_adr5000~
1p013c01(chips)';

SECTION_NUMBER 3
 '@S9S_MB_2U_LIB.S9S_MB_2U(SCH_1):PAGE397_I178@PURE_QUANTA.SCONN288_ADR50001P013C01(CHIPS)':
 C_PATH='@s9s_mb_2u_lib.s9s_mb_2u(sch_1):page397_i178@pure_quanta.sconn288_adr5000~
1p013c01(chips)';

PART_NAME
 C77 'Q_CAP_C0805-10UF,16V,10%,X7R,CA':;

SECTION_NUMBER 1
 '@S9S_MB_2U_LIB.S9S_MB_2U(SCH_1):PAGE397_I126@PURE_QUANTA.Q_CAP(CHIPS)':
 C_PATH='@s9s_mb_2u_lib.s9s_mb_2u(sch_1):page397_i126@pure_quanta.q_cap(chips)';

PART_NAME
 C76 'Q_CAP_C0805-10UF,16V,10%,X7R,CA':;

SECTION_NUMBER 1
 '@S9S_MB_2U_LIB.S9S_MB_2U(SCH_1):PAGE397_I125@PURE_QUANTA.Q_CAP(CHIPS)':
 C_PATH='@s9s_mb_2u_lib.s9s_mb_2u(sch_1):page397_i125@pure_quanta.q_cap(chips)';

PART_NAME
 C75 'Q_CAP_C0402-2.2UF,6.3V,20%,X6SA':;

SECTION_NUMBER 1
 '@S9S_MB_2U_LIB.S9S_MB_2U(SCH_1):PAGE397_I124@PURE_QUANTA.Q_CAP(CHIPS)':
 C_PATH='@s9s_mb_2u_lib.s9s_mb_2u(sch_1):page397_i124@pure_quanta.q_cap(chips)';

PART_NAME
 R72 'Q_RES_0402LF-196K,1%,1/16W,CHIA':;

SECTION_NUMBER 1
 '@S9S_MB_2U_LIB.S9S_MB_2U(SCH_1):PAGE398_I2@PURE_QUANTA.Q_RES(CHIPS)':
 C_PATH='@s9s_mb_2u_lib.s9s_mb_2u(sch_1):page398_i2@pure_quanta.q_res(chips)';

PART_NAME
 J32 'SCONN288_ADR50001P003C01-SCONNA':;

SECTION_NUMBER 1
 '@S9S_MB_2U_LIB.S9S_MB_2U(SCH_1):PAGE398_I179@PURE_QUANTA.SCONN288_ADR50001P003C01(CHIPS)':
 C_PATH='@s9s_mb_2u_lib.s9s_mb_2u(sch_1):page398_i179@pure_quanta.sconn288_adr5000~
1p003c01(chips)';

SECTION_NUMBER 2
 '@S9S_MB_2U_LIB.S9S_MB_2U(SCH_1):PAGE398_I178@PURE_QUANTA.SCONN288_ADR50001P003C01(CHIPS)':
 C_PATH='@s9s_mb_2u_lib.s9s_mb_2u(sch_1):page398_i178@pure_quanta.sconn288_adr5000~
1p003c01(chips)';

SECTION_NUMBER 3
 '@S9S_MB_2U_LIB.S9S_MB_2U(SCH_1):PAGE398_I177@PURE_QUANTA.SCONN288_ADR50001P003C01(CHIPS)':
 C_PATH='@s9s_mb_2u_lib.s9s_mb_2u(sch_1):page398_i177@pure_quanta.sconn288_adr5000~
1p003c01(chips)';

PART_NAME
 C74 'Q_CAP_C0805-10UF,16V,10%,X7R,CA':;

SECTION_NUMBER 1
 '@S9S_MB_2U_LIB.S9S_MB_2U(SCH_1):PAGE398_I122@PURE_QUANTA.Q_CAP(CHIPS)':
 C_PATH='@s9s_mb_2u_lib.s9s_mb_2u(sch_1):page398_i122@pure_quanta.q_cap(chips)';

PART_NAME
 C73 'Q_CAP_C0805-10UF,16V,10%,X7R,CA':;

SECTION_NUMBER 1
 '@S9S_MB_2U_LIB.S9S_MB_2U(SCH_1):PAGE398_I120@PURE_QUANTA.Q_CAP(CHIPS)':
 C_PATH='@s9s_mb_2u_lib.s9s_mb_2u(sch_1):page398_i120@pure_quanta.q_cap(chips)';

PART_NAME
 C72 'Q_CAP_C0402-2.2UF,6.3V,20%,X6SA':;

SECTION_NUMBER 1
 '@S9S_MB_2U_LIB.S9S_MB_2U(SCH_1):PAGE398_I116@PURE_QUANTA.Q_CAP(CHIPS)':
 C_PATH='@s9s_mb_2u_lib.s9s_mb_2u(sch_1):page398_i116@pure_quanta.q_cap(chips)';

PART_NAME
 U1 'SOCKET4677_AZIFS035P001C01-SOCA':;

SECTION_NUMBER 1
 '@S9S_MB_2U_LIB.S9S_MB_2U(SCH_1):PAGE340_I51@PURE_QUANTA.SOCKET4677_AZIFS035P001C01(CHIPS)':
 C_PATH='@s9s_mb_2u_lib.s9s_mb_2u(sch_1):page340_i51@pure_quanta.socket4677_azifs0~
35p001c01(chips)';

SECTION_NUMBER 2
 '@S9S_MB_2U_LIB.S9S_MB_2U(SCH_1):PAGE341_I29@PURE_QUANTA.SOCKET4677_AZIFS035P001C01(CHIPS)':
 C_PATH='@s9s_mb_2u_lib.s9s_mb_2u(sch_1):page341_i29@pure_quanta.socket4677_azifs0~
35p001c01(chips)';

SECTION_NUMBER 3
 '@S9S_MB_2U_LIB.S9S_MB_2U(SCH_1):PAGE342_I5@PURE_QUANTA.SOCKET4677_AZIFS035P001C01(CHIPS)':
 C_PATH='@s9s_mb_2u_lib.s9s_mb_2u(sch_1):page342_i5@pure_quanta.socket4677_azifs03~
5p001c01(chips)';

SECTION_NUMBER 4
 '@S9S_MB_2U_LIB.S9S_MB_2U(SCH_1):PAGE343_I16@PURE_QUANTA.SOCKET4677_AZIFS035P001C01(CHIPS)':
 C_PATH='@s9s_mb_2u_lib.s9s_mb_2u(sch_1):page343_i16@pure_quanta.socket4677_azifs0~
35p001c01(chips)';

SECTION_NUMBER 5
 '@S9S_MB_2U_LIB.S9S_MB_2U(SCH_1):PAGE344_I1@PURE_QUANTA.SOCKET4677_AZIFS035P001C01(CHIPS)':
 C_PATH='@s9s_mb_2u_lib.s9s_mb_2u(sch_1):page344_i1@pure_quanta.socket4677_azifs03~
5p001c01(chips)';

SECTION_NUMBER 6
 '@S9S_MB_2U_LIB.S9S_MB_2U(SCH_1):PAGE345_I2@PURE_QUANTA.SOCKET4677_AZIFS035P001C01(CHIPS)':
 C_PATH='@s9s_mb_2u_lib.s9s_mb_2u(sch_1):page345_i2@pure_quanta.socket4677_azifs03~
5p001c01(chips)';

SECTION_NUMBER 7
 '@S9S_MB_2U_LIB.S9S_MB_2U(SCH_1):PAGE346_I23@PURE_QUANTA.SOCKET4677_AZIFS035P001C01(CHIPS)':
 C_PATH='@s9s_mb_2u_lib.s9s_mb_2u(sch_1):page346_i23@pure_quanta.socket4677_azifs0~
35p001c01(chips)';

SECTION_NUMBER 8
 '@S9S_MB_2U_LIB.S9S_MB_2U(SCH_1):PAGE347_I2@PURE_QUANTA.SOCKET4677_AZIFS035P001C01(CHIPS)':
 C_PATH='@s9s_mb_2u_lib.s9s_mb_2u(sch_1):page347_i2@pure_quanta.socket4677_azifs03~
5p001c01(chips)';

SECTION_NUMBER 9
 '@S9S_MB_2U_LIB.S9S_MB_2U(SCH_1):PAGE348_I91@PURE_QUANTA.SOCKET4677_AZIFS035P001C01(CHIPS)':
 C_PATH='@s9s_mb_2u_lib.s9s_mb_2u(sch_1):page348_i91@pure_quanta.socket4677_azifs0~
35p001c01(chips)';

SECTION_NUMBER 10
 '@S9S_MB_2U_LIB.S9S_MB_2U(SCH_1):PAGE349_I91@PURE_QUANTA.SOCKET4677_AZIFS035P001C01(CHIPS)':
 C_PATH='@s9s_mb_2u_lib.s9s_mb_2u(sch_1):page349_i91@pure_quanta.socket4677_azifs0~
35p001c01(chips)';

SECTION_NUMBER 11
 '@S9S_MB_2U_LIB.S9S_MB_2U(SCH_1):PAGE350_I91@PURE_QUANTA.SOCKET4677_AZIFS035P001C01(CHIPS)':
 C_PATH='@s9s_mb_2u_lib.s9s_mb_2u(sch_1):page350_i91@pure_quanta.socket4677_azifs0~
35p001c01(chips)';

SECTION_NUMBER 12
 '@S9S_MB_2U_LIB.S9S_MB_2U(SCH_1):PAGE351_I7@PURE_QUANTA.SOCKET4677_AZIFS035P001C01(CHIPS)':
 C_PATH='@s9s_mb_2u_lib.s9s_mb_2u(sch_1):page351_i7@pure_quanta.socket4677_azifs03~
5p001c01(chips)';

SECTION_NUMBER 13
 '@S9S_MB_2U_LIB.S9S_MB_2U(SCH_1):PAGE352_I168@PURE_QUANTA.SOCKET4677_AZIFS035P001C01(CHIPS)':
 C_PATH='@s9s_mb_2u_lib.s9s_mb_2u(sch_1):page352_i168@pure_quanta.socket4677_azifs~
035p001c01(chips)';

SECTION_NUMBER 14
 '@S9S_MB_2U_LIB.S9S_MB_2U(SCH_1):PAGE353_I168@PURE_QUANTA.SOCKET4677_AZIFS035P001C01(CHIPS)':
 C_PATH='@s9s_mb_2u_lib.s9s_mb_2u(sch_1):page353_i168@pure_quanta.socket4677_azifs~
035p001c01(chips)';

SECTION_NUMBER 15
 '@S9S_MB_2U_LIB.S9S_MB_2U(SCH_1):PAGE354_I20@PURE_QUANTA.SOCKET4677_AZIFS035P001C01(CHIPS)':
 C_PATH='@s9s_mb_2u_lib.s9s_mb_2u(sch_1):page354_i20@pure_quanta.socket4677_azifs0~
35p001c01(chips)';

SECTION_NUMBER 16
 '@S9S_MB_2U_LIB.S9S_MB_2U(SCH_1):PAGE355_I20@PURE_QUANTA.SOCKET4677_AZIFS035P001C01(CHIPS)':
 C_PATH='@s9s_mb_2u_lib.s9s_mb_2u(sch_1):page355_i20@pure_quanta.socket4677_azifs0~
35p001c01(chips)';

SECTION_NUMBER 17
 '@S9S_MB_2U_LIB.S9S_MB_2U(SCH_1):PAGE356_I80@PURE_QUANTA.SOCKET4677_AZIFS035P001C01(CHIPS)':
 C_PATH='@s9s_mb_2u_lib.s9s_mb_2u(sch_1):page356_i80@pure_quanta.socket4677_azifs0~
35p001c01(chips)';

SECTION_NUMBER 18
 '@S9S_MB_2U_LIB.S9S_MB_2U(SCH_1):PAGE356_I69@PURE_QUANTA.SOCKET4677_AZIFS035P001C01(CHIPS)':
 C_PATH='@s9s_mb_2u_lib.s9s_mb_2u(sch_1):page356_i69@pure_quanta.socket4677_azifs0~
35p001c01(chips)';

SECTION_NUMBER 19
 '@S9S_MB_2U_LIB.S9S_MB_2U(SCH_1):PAGE357_I54@PURE_QUANTA.SOCKET4677_AZIFS035P001C01(CHIPS)':
 C_PATH='@s9s_mb_2u_lib.s9s_mb_2u(sch_1):page357_i54@pure_quanta.socket4677_azifs0~
35p001c01(chips)';

SECTION_NUMBER 20
 '@S9S_MB_2U_LIB.S9S_MB_2U(SCH_1):PAGE357_I12@PURE_QUANTA.SOCKET4677_AZIFS035P001C01(CHIPS)':
 C_PATH='@s9s_mb_2u_lib.s9s_mb_2u(sch_1):page357_i12@pure_quanta.socket4677_azifs0~
35p001c01(chips)';

SECTION_NUMBER 21
 '@S9S_MB_2U_LIB.S9S_MB_2U(SCH_1):PAGE358_I18@PURE_QUANTA.SOCKET4677_AZIFS035P001C01(CHIPS)':
 C_PATH='@s9s_mb_2u_lib.s9s_mb_2u(sch_1):page358_i18@pure_quanta.socket4677_azifs0~
35p001c01(chips)';

SECTION_NUMBER 22
 '@S9S_MB_2U_LIB.S9S_MB_2U(SCH_1):PAGE359_I51@PURE_QUANTA.SOCKET4677_AZIFS035P001C01(CHIPS)':
 C_PATH='@s9s_mb_2u_lib.s9s_mb_2u(sch_1):page359_i51@pure_quanta.socket4677_azifs0~
35p001c01(chips)';

SECTION_NUMBER 23
 '@S9S_MB_2U_LIB.S9S_MB_2U(SCH_1):PAGE64_I21@PURE_QUANTA.SOCKET4677_AZIFS035P001C01(CHIPS)':
 C_PATH='@s9s_mb_2u_lib.s9s_mb_2u(sch_1):page64_i21@pure_quanta.socket4677_azifs03~
5p001c01(chips)';

SECTION_NUMBER 24
 '@S9S_MB_2U_LIB.S9S_MB_2U(SCH_1):PAGE65_I16@PURE_QUANTA.SOCKET4677_AZIFS035P001C01(CHIPS)':
 C_PATH='@s9s_mb_2u_lib.s9s_mb_2u(sch_1):page65_i16@pure_quanta.socket4677_azifs03~
5p001c01(chips)';

SECTION_NUMBER 25
 '@S9S_MB_2U_LIB.S9S_MB_2U(SCH_1):PAGE66_I16@PURE_QUANTA.SOCKET4677_AZIFS035P001C01(CHIPS)':
 C_PATH='@s9s_mb_2u_lib.s9s_mb_2u(sch_1):page66_i16@pure_quanta.socket4677_azifs03~
5p001c01(chips)';

SECTION_NUMBER 26
 '@S9S_MB_2U_LIB.S9S_MB_2U(SCH_1):PAGE67_I1@PURE_QUANTA.SOCKET4677_AZIFS035P001C01(CHIPS)':
 C_PATH='@s9s_mb_2u_lib.s9s_mb_2u(sch_1):page67_i1@pure_quanta.socket4677_azifs035~
p001c01(chips)';

SECTION_NUMBER 27
 '@S9S_MB_2U_LIB.S9S_MB_2U(SCH_1):PAGE67_I3@PURE_QUANTA.SOCKET4677_AZIFS035P001C01(CHIPS)':
 C_PATH='@s9s_mb_2u_lib.s9s_mb_2u(sch_1):page67_i3@pure_quanta.socket4677_azifs035~
p001c01(chips)';

SECTION_NUMBER 28
 '@S9S_MB_2U_LIB.S9S_MB_2U(SCH_1):PAGE68_I1@PURE_QUANTA.SOCKET4677_AZIFS035P001C01(CHIPS)':
 C_PATH='@s9s_mb_2u_lib.s9s_mb_2u(sch_1):page68_i1@pure_quanta.socket4677_azifs035~
p001c01(chips)';

SECTION_NUMBER 29
 '@S9S_MB_2U_LIB.S9S_MB_2U(SCH_1):PAGE68_I8@PURE_QUANTA.SOCKET4677_AZIFS035P001C01(CHIPS)':
 C_PATH='@s9s_mb_2u_lib.s9s_mb_2u(sch_1):page68_i8@pure_quanta.socket4677_azifs035~
p001c01(chips)';

SECTION_NUMBER 30
 '@S9S_MB_2U_LIB.S9S_MB_2U(SCH_1):PAGE69_I1@PURE_QUANTA.SOCKET4677_AZIFS035P001C01(CHIPS)':
 C_PATH='@s9s_mb_2u_lib.s9s_mb_2u(sch_1):page69_i1@pure_quanta.socket4677_azifs035~
p001c01(chips)';

SECTION_NUMBER 31
 '@S9S_MB_2U_LIB.S9S_MB_2U(SCH_1):PAGE360_I2@PURE_QUANTA.SOCKET4677_AZIFS035P001C01(CHIPS)':
 C_PATH='@s9s_mb_2u_lib.s9s_mb_2u(sch_1):page360_i2@pure_quanta.socket4677_azifs03~
5p001c01(chips)';

SECTION_NUMBER 32
 '@S9S_MB_2U_LIB.S9S_MB_2U(SCH_1):PAGE360_I5@PURE_QUANTA.SOCKET4677_AZIFS035P001C01(CHIPS)':
 C_PATH='@s9s_mb_2u_lib.s9s_mb_2u(sch_1):page360_i5@pure_quanta.socket4677_azifs03~
5p001c01(chips)';

SECTION_NUMBER 33
 '@S9S_MB_2U_LIB.S9S_MB_2U(SCH_1):PAGE360_I8@PURE_QUANTA.SOCKET4677_AZIFS035P001C01(CHIPS)':
 C_PATH='@s9s_mb_2u_lib.s9s_mb_2u(sch_1):page360_i8@pure_quanta.socket4677_azifs03~
5p001c01(chips)';

SECTION_NUMBER 34
 '@S9S_MB_2U_LIB.S9S_MB_2U(SCH_1):PAGE361_I2@PURE_QUANTA.SOCKET4677_AZIFS035P001C01(CHIPS)':
 C_PATH='@s9s_mb_2u_lib.s9s_mb_2u(sch_1):page361_i2@pure_quanta.socket4677_azifs03~
5p001c01(chips)';

SECTION_NUMBER 35
 '@S9S_MB_2U_LIB.S9S_MB_2U(SCH_1):PAGE361_I5@PURE_QUANTA.SOCKET4677_AZIFS035P001C01(CHIPS)':
 C_PATH='@s9s_mb_2u_lib.s9s_mb_2u(sch_1):page361_i5@pure_quanta.socket4677_azifs03~
5p001c01(chips)';

SECTION_NUMBER 36
 '@S9S_MB_2U_LIB.S9S_MB_2U(SCH_1):PAGE361_I8@PURE_QUANTA.SOCKET4677_AZIFS035P001C01(CHIPS)':
 C_PATH='@s9s_mb_2u_lib.s9s_mb_2u(sch_1):page361_i8@pure_quanta.socket4677_azifs03~
5p001c01(chips)';

SECTION_NUMBER 37
 '@S9S_MB_2U_LIB.S9S_MB_2U(SCH_1):PAGE362_I2@PURE_QUANTA.SOCKET4677_AZIFS035P001C01(CHIPS)':
 C_PATH='@s9s_mb_2u_lib.s9s_mb_2u(sch_1):page362_i2@pure_quanta.socket4677_azifs03~
5p001c01(chips)';

SECTION_NUMBER 38
 '@S9S_MB_2U_LIB.S9S_MB_2U(SCH_1):PAGE362_I5@PURE_QUANTA.SOCKET4677_AZIFS035P001C01(CHIPS)':
 C_PATH='@s9s_mb_2u_lib.s9s_mb_2u(sch_1):page362_i5@pure_quanta.socket4677_azifs03~
5p001c01(chips)';

SECTION_NUMBER 39
 '@S9S_MB_2U_LIB.S9S_MB_2U(SCH_1):PAGE362_I8@PURE_QUANTA.SOCKET4677_AZIFS035P001C01(CHIPS)':
 C_PATH='@s9s_mb_2u_lib.s9s_mb_2u(sch_1):page362_i8@pure_quanta.socket4677_azifs03~
5p001c01(chips)';

SECTION_NUMBER 40
 '@S9S_MB_2U_LIB.S9S_MB_2U(SCH_1):PAGE363_I2@PURE_QUANTA.SOCKET4677_AZIFS035P001C01(CHIPS)':
 C_PATH='@s9s_mb_2u_lib.s9s_mb_2u(sch_1):page363_i2@pure_quanta.socket4677_azifs03~
5p001c01(chips)';

SECTION_NUMBER 41
 '@S9S_MB_2U_LIB.S9S_MB_2U(SCH_1):PAGE363_I5@PURE_QUANTA.SOCKET4677_AZIFS035P001C01(CHIPS)':
 C_PATH='@s9s_mb_2u_lib.s9s_mb_2u(sch_1):page363_i5@pure_quanta.socket4677_azifs03~
5p001c01(chips)';

SECTION_NUMBER 42
 '@S9S_MB_2U_LIB.S9S_MB_2U(SCH_1):PAGE363_I8@PURE_QUANTA.SOCKET4677_AZIFS035P001C01(CHIPS)':
 C_PATH='@s9s_mb_2u_lib.s9s_mb_2u(sch_1):page363_i8@pure_quanta.socket4677_azifs03~
5p001c01(chips)';

PART_NAME
 C71 'Q_CAP_C0402-10UF,6.3V,20%,X6S,A':;

SECTION_NUMBER 1
 '@S9S_MB_2U_LIB.S9S_MB_2U(SCH_1):PAGE68_I4@PURE_QUANTA.Q_CAP(CHIPS)':
 C_PATH='@s9s_mb_2u_lib.s9s_mb_2u(sch_1):page68_i4@pure_quanta.q_cap(chips)';

PART_NAME
 R48 'Q_RES_0402LF-127K,1%,1/16W,CHIA':;

SECTION_NUMBER 1
 '@S9S_MB_2U_LIB.S9S_MB_2U(SCH_1):PAGE389_I2@PURE_QUANTA.Q_RES(CHIPS)':
 C_PATH='@s9s_mb_2u_lib.s9s_mb_2u(sch_1):page389_i2@pure_quanta.q_res(chips)';

PART_NAME
 J23 'SCONN288_ADR50001P013C01-SCONNA':;

SECTION_NUMBER 1
 '@S9S_MB_2U_LIB.S9S_MB_2U(SCH_1):PAGE389_I25@PURE_QUANTA.SCONN288_ADR50001P013C01(CHIPS)':
 C_PATH='@s9s_mb_2u_lib.s9s_mb_2u(sch_1):page389_i25@pure_quanta.sconn288_adr50001~
p013c01(chips)';

SECTION_NUMBER 2
 '@S9S_MB_2U_LIB.S9S_MB_2U(SCH_1):PAGE389_I126@PURE_QUANTA.SCONN288_ADR50001P013C01(CHIPS)':
 C_PATH='@s9s_mb_2u_lib.s9s_mb_2u(sch_1):page389_i126@pure_quanta.sconn288_adr5000~
1p013c01(chips)';

SECTION_NUMBER 3
 '@S9S_MB_2U_LIB.S9S_MB_2U(SCH_1):PAGE389_I175@PURE_QUANTA.SCONN288_ADR50001P013C01(CHIPS)':
 C_PATH='@s9s_mb_2u_lib.s9s_mb_2u(sch_1):page389_i175@pure_quanta.sconn288_adr5000~
1p013c01(chips)';

PART_NAME
 C70 'Q_CAP_C0805-10UF,16V,10%,X7R,CA':;

SECTION_NUMBER 1
 '@S9S_MB_2U_LIB.S9S_MB_2U(SCH_1):PAGE389_I129@PURE_QUANTA.Q_CAP(CHIPS)':
 C_PATH='@s9s_mb_2u_lib.s9s_mb_2u(sch_1):page389_i129@pure_quanta.q_cap(chips)';

PART_NAME
 C69 'Q_CAP_C0805-10UF,16V,10%,X7R,CA':;

SECTION_NUMBER 1
 '@S9S_MB_2U_LIB.S9S_MB_2U(SCH_1):PAGE389_I127@PURE_QUANTA.Q_CAP(CHIPS)':
 C_PATH='@s9s_mb_2u_lib.s9s_mb_2u(sch_1):page389_i127@pure_quanta.q_cap(chips)';

PART_NAME
 C68 'Q_CAP_C0402-2.2UF,6.3V,20%,X6SA':;

SECTION_NUMBER 1
 '@S9S_MB_2U_LIB.S9S_MB_2U(SCH_1):PAGE389_I122@PURE_QUANTA.Q_CAP(CHIPS)':
 C_PATH='@s9s_mb_2u_lib.s9s_mb_2u(sch_1):page389_i122@pure_quanta.q_cap(chips)';

PART_NAME
 R47 'Q_RES_0402LF-84.5K,1%,1/16W,CHA':;

SECTION_NUMBER 1
 '@S9S_MB_2U_LIB.S9S_MB_2U(SCH_1):PAGE388_I2@PURE_QUANTA.Q_RES(CHIPS)':
 C_PATH='@s9s_mb_2u_lib.s9s_mb_2u(sch_1):page388_i2@pure_quanta.q_res(chips)';

PART_NAME
 J22 'SCONN288_ADR50001P003C01-SCONNA':;

SECTION_NUMBER 1
 '@S9S_MB_2U_LIB.S9S_MB_2U(SCH_1):PAGE388_I51@PURE_QUANTA.SCONN288_ADR50001P003C01(CHIPS)':
 C_PATH='@s9s_mb_2u_lib.s9s_mb_2u(sch_1):page388_i51@pure_quanta.sconn288_adr50001~
p003c01(chips)';

SECTION_NUMBER 2
 '@S9S_MB_2U_LIB.S9S_MB_2U(SCH_1):PAGE388_I125@PURE_QUANTA.SCONN288_ADR50001P003C01(CHIPS)':
 C_PATH='@s9s_mb_2u_lib.s9s_mb_2u(sch_1):page388_i125@pure_quanta.sconn288_adr5000~
1p003c01(chips)';

SECTION_NUMBER 3
 '@S9S_MB_2U_LIB.S9S_MB_2U(SCH_1):PAGE388_I176@PURE_QUANTA.SCONN288_ADR50001P003C01(CHIPS)':
 C_PATH='@s9s_mb_2u_lib.s9s_mb_2u(sch_1):page388_i176@pure_quanta.sconn288_adr5000~
1p003c01(chips)';

PART_NAME
 C67 'Q_CAP_C0805-10UF,16V,10%,X7R,CA':;

SECTION_NUMBER 1
 '@S9S_MB_2U_LIB.S9S_MB_2U(SCH_1):PAGE388_I128@PURE_QUANTA.Q_CAP(CHIPS)':
 C_PATH='@s9s_mb_2u_lib.s9s_mb_2u(sch_1):page388_i128@pure_quanta.q_cap(chips)';

PART_NAME
 C66 'Q_CAP_C0805-10UF,16V,10%,X7R,CA':;

SECTION_NUMBER 1
 '@S9S_MB_2U_LIB.S9S_MB_2U(SCH_1):PAGE388_I126@PURE_QUANTA.Q_CAP(CHIPS)':
 C_PATH='@s9s_mb_2u_lib.s9s_mb_2u(sch_1):page388_i126@pure_quanta.q_cap(chips)';

PART_NAME
 C65 'Q_CAP_C0402-2.2UF,6.3V,20%,X6SA':;

SECTION_NUMBER 1
 '@S9S_MB_2U_LIB.S9S_MB_2U(SCH_1):PAGE388_I122@PURE_QUANTA.Q_CAP(CHIPS)':
 C_PATH='@s9s_mb_2u_lib.s9s_mb_2u(sch_1):page388_i122@pure_quanta.q_cap(chips)';

PART_NAME
 R46 'Q_RES_0402LF-54.9K,1%,1/16W,CHA':;

SECTION_NUMBER 1
 '@S9S_MB_2U_LIB.S9S_MB_2U(SCH_1):PAGE387_I2@PURE_QUANTA.Q_RES(CHIPS)':
 C_PATH='@s9s_mb_2u_lib.s9s_mb_2u(sch_1):page387_i2@pure_quanta.q_res(chips)';

PART_NAME
 J21 'SCONN288_ADR50001P013C01-SCONNA':;

SECTION_NUMBER 1
 '@S9S_MB_2U_LIB.S9S_MB_2U(SCH_1):PAGE387_I13@PURE_QUANTA.SCONN288_ADR50001P013C01(CHIPS)':
 C_PATH='@s9s_mb_2u_lib.s9s_mb_2u(sch_1):page387_i13@pure_quanta.sconn288_adr50001~
p013c01(chips)';

SECTION_NUMBER 2
 '@S9S_MB_2U_LIB.S9S_MB_2U(SCH_1):PAGE387_I126@PURE_QUANTA.SCONN288_ADR50001P013C01(CHIPS)':
 C_PATH='@s9s_mb_2u_lib.s9s_mb_2u(sch_1):page387_i126@pure_quanta.sconn288_adr5000~
1p013c01(chips)';

SECTION_NUMBER 3
 '@S9S_MB_2U_LIB.S9S_MB_2U(SCH_1):PAGE387_I169@PURE_QUANTA.SCONN288_ADR50001P013C01(CHIPS)':
 C_PATH='@s9s_mb_2u_lib.s9s_mb_2u(sch_1):page387_i169@pure_quanta.sconn288_adr5000~
1p013c01(chips)';

PART_NAME
 C64 'Q_CAP_C0805-10UF,16V,10%,X7R,CA':;

SECTION_NUMBER 1
 '@S9S_MB_2U_LIB.S9S_MB_2U(SCH_1):PAGE387_I167@PURE_QUANTA.Q_CAP(CHIPS)':
 C_PATH='@s9s_mb_2u_lib.s9s_mb_2u(sch_1):page387_i167@pure_quanta.q_cap(chips)';

PART_NAME
 C63 'Q_CAP_C0805-10UF,16V,10%,X7R,CA':;

SECTION_NUMBER 1
 '@S9S_MB_2U_LIB.S9S_MB_2U(SCH_1):PAGE387_I127@PURE_QUANTA.Q_CAP(CHIPS)':
 C_PATH='@s9s_mb_2u_lib.s9s_mb_2u(sch_1):page387_i127@pure_quanta.q_cap(chips)';

PART_NAME
 C62 'Q_CAP_C0402-2.2UF,6.3V,20%,X6SA':;

SECTION_NUMBER 1
 '@S9S_MB_2U_LIB.S9S_MB_2U(SCH_1):PAGE387_I124@PURE_QUANTA.Q_CAP(CHIPS)':
 C_PATH='@s9s_mb_2u_lib.s9s_mb_2u(sch_1):page387_i124@pure_quanta.q_cap(chips)';

PART_NAME
 R45 'Q_RES_0402LF-35.7K,1%,1/16W,CHA':;

SECTION_NUMBER 1
 '@S9S_MB_2U_LIB.S9S_MB_2U(SCH_1):PAGE386_I46@PURE_QUANTA.Q_RES(CHIPS)':
 C_PATH='@s9s_mb_2u_lib.s9s_mb_2u(sch_1):page386_i46@pure_quanta.q_res(chips)';

PART_NAME
 J20 'SCONN288_ADR50001P003C01-SCONNA':;

SECTION_NUMBER 1
 '@S9S_MB_2U_LIB.S9S_MB_2U(SCH_1):PAGE386_I47@PURE_QUANTA.SCONN288_ADR50001P003C01(CHIPS)':
 C_PATH='@s9s_mb_2u_lib.s9s_mb_2u(sch_1):page386_i47@pure_quanta.sconn288_adr50001~
p003c01(chips)';

SECTION_NUMBER 2
 '@S9S_MB_2U_LIB.S9S_MB_2U(SCH_1):PAGE386_I124@PURE_QUANTA.SCONN288_ADR50001P003C01(CHIPS)':
 C_PATH='@s9s_mb_2u_lib.s9s_mb_2u(sch_1):page386_i124@pure_quanta.sconn288_adr5000~
1p003c01(chips)';

SECTION_NUMBER 3
 '@S9S_MB_2U_LIB.S9S_MB_2U(SCH_1):PAGE386_I176@PURE_QUANTA.SCONN288_ADR50001P003C01(CHIPS)':
 C_PATH='@s9s_mb_2u_lib.s9s_mb_2u(sch_1):page386_i176@pure_quanta.sconn288_adr5000~
1p003c01(chips)';

PART_NAME
 C61 'Q_CAP_C0805-10UF,16V,10%,X7R,CA':;

SECTION_NUMBER 1
 '@S9S_MB_2U_LIB.S9S_MB_2U(SCH_1):PAGE386_I127@PURE_QUANTA.Q_CAP(CHIPS)':
 C_PATH='@s9s_mb_2u_lib.s9s_mb_2u(sch_1):page386_i127@pure_quanta.q_cap(chips)';

PART_NAME
 C60 'Q_CAP_C0805-10UF,16V,10%,X7R,CA':;

SECTION_NUMBER 1
 '@S9S_MB_2U_LIB.S9S_MB_2U(SCH_1):PAGE386_I125@PURE_QUANTA.Q_CAP(CHIPS)':
 C_PATH='@s9s_mb_2u_lib.s9s_mb_2u(sch_1):page386_i125@pure_quanta.q_cap(chips)';

PART_NAME
 C59 'Q_CAP_C0402-2.2UF,6.3V,20%,X6SA':;

SECTION_NUMBER 1
 '@S9S_MB_2U_LIB.S9S_MB_2U(SCH_1):PAGE386_I121@PURE_QUANTA.Q_CAP(CHIPS)':
 C_PATH='@s9s_mb_2u_lib.s9s_mb_2u(sch_1):page386_i121@pure_quanta.q_cap(chips)';

PART_NAME
 R44 'Q_RES_0402LF-23.2K,1%,1/16W,CHA':;

SECTION_NUMBER 1
 '@S9S_MB_2U_LIB.S9S_MB_2U(SCH_1):PAGE385_I3@PURE_QUANTA.Q_RES(CHIPS)':
 C_PATH='@s9s_mb_2u_lib.s9s_mb_2u(sch_1):page385_i3@pure_quanta.q_res(chips)';

PART_NAME
 J19 'SCONN288_ADR50001P013C01-SCONNA':;

SECTION_NUMBER 1
 '@S9S_MB_2U_LIB.S9S_MB_2U(SCH_1):PAGE385_I25@PURE_QUANTA.SCONN288_ADR50001P013C01(CHIPS)':
 C_PATH='@s9s_mb_2u_lib.s9s_mb_2u(sch_1):page385_i25@pure_quanta.sconn288_adr50001~
p013c01(chips)';

SECTION_NUMBER 2
 '@S9S_MB_2U_LIB.S9S_MB_2U(SCH_1):PAGE385_I126@PURE_QUANTA.SCONN288_ADR50001P013C01(CHIPS)':
 C_PATH='@s9s_mb_2u_lib.s9s_mb_2u(sch_1):page385_i126@pure_quanta.sconn288_adr5000~
1p013c01(chips)';

SECTION_NUMBER 3
 '@S9S_MB_2U_LIB.S9S_MB_2U(SCH_1):PAGE385_I175@PURE_QUANTA.SCONN288_ADR50001P013C01(CHIPS)':
 C_PATH='@s9s_mb_2u_lib.s9s_mb_2u(sch_1):page385_i175@pure_quanta.sconn288_adr5000~
1p013c01(chips)';

PART_NAME
 C58 'Q_CAP_C0805-10UF,16V,10%,X7R,CA':;

SECTION_NUMBER 1
 '@S9S_MB_2U_LIB.S9S_MB_2U(SCH_1):PAGE385_I124@PURE_QUANTA.Q_CAP(CHIPS)':
 C_PATH='@s9s_mb_2u_lib.s9s_mb_2u(sch_1):page385_i124@pure_quanta.q_cap(chips)';

PART_NAME
 C57 'Q_CAP_C0805-10UF,16V,10%,X7R,CA':;

SECTION_NUMBER 1
 '@S9S_MB_2U_LIB.S9S_MB_2U(SCH_1):PAGE385_I122@PURE_QUANTA.Q_CAP(CHIPS)':
 C_PATH='@s9s_mb_2u_lib.s9s_mb_2u(sch_1):page385_i122@pure_quanta.q_cap(chips)';

PART_NAME
 C56 'Q_CAP_C0402-2.2UF,6.3V,20%,X6SA':;

SECTION_NUMBER 1
 '@S9S_MB_2U_LIB.S9S_MB_2U(SCH_1):PAGE385_I121@PURE_QUANTA.Q_CAP(CHIPS)':
 C_PATH='@s9s_mb_2u_lib.s9s_mb_2u(sch_1):page385_i121@pure_quanta.q_cap(chips)';

PART_NAME
 R43 'Q_RES_0402LF-15.4K,1%,1/16W,CHA':;

SECTION_NUMBER 1
 '@S9S_MB_2U_LIB.S9S_MB_2U(SCH_1):PAGE384_I2@PURE_QUANTA.Q_RES(CHIPS)':
 C_PATH='@s9s_mb_2u_lib.s9s_mb_2u(sch_1):page384_i2@pure_quanta.q_res(chips)';

PART_NAME
 J18 'SCONN288_ADR50001P003C01-SCONNA':;

SECTION_NUMBER 1
 '@S9S_MB_2U_LIB.S9S_MB_2U(SCH_1):PAGE384_I24@PURE_QUANTA.SCONN288_ADR50001P003C01(CHIPS)':
 C_PATH='@s9s_mb_2u_lib.s9s_mb_2u(sch_1):page384_i24@pure_quanta.sconn288_adr50001~
p003c01(chips)';

SECTION_NUMBER 2
 '@S9S_MB_2U_LIB.S9S_MB_2U(SCH_1):PAGE384_I125@PURE_QUANTA.SCONN288_ADR50001P003C01(CHIPS)':
 C_PATH='@s9s_mb_2u_lib.s9s_mb_2u(sch_1):page384_i125@pure_quanta.sconn288_adr5000~
1p003c01(chips)';

SECTION_NUMBER 3
 '@S9S_MB_2U_LIB.S9S_MB_2U(SCH_1):PAGE384_I175@PURE_QUANTA.SCONN288_ADR50001P003C01(CHIPS)':
 C_PATH='@s9s_mb_2u_lib.s9s_mb_2u(sch_1):page384_i175@pure_quanta.sconn288_adr5000~
1p003c01(chips)';

PART_NAME
 C55 'Q_CAP_C0805-10UF,16V,10%,X7R,CA':;

SECTION_NUMBER 1
 '@S9S_MB_2U_LIB.S9S_MB_2U(SCH_1):PAGE384_I128@PURE_QUANTA.Q_CAP(CHIPS)':
 C_PATH='@s9s_mb_2u_lib.s9s_mb_2u(sch_1):page384_i128@pure_quanta.q_cap(chips)';

PART_NAME
 C54 'Q_CAP_C0805-10UF,16V,10%,X7R,CA':;

SECTION_NUMBER 1
 '@S9S_MB_2U_LIB.S9S_MB_2U(SCH_1):PAGE384_I126@PURE_QUANTA.Q_CAP(CHIPS)':
 C_PATH='@s9s_mb_2u_lib.s9s_mb_2u(sch_1):page384_i126@pure_quanta.q_cap(chips)';

PART_NAME
 C53 'Q_CAP_C0402-2.2UF,6.3V,20%,X6SA':;

SECTION_NUMBER 1
 '@S9S_MB_2U_LIB.S9S_MB_2U(SCH_1):PAGE384_I122@PURE_QUANTA.Q_CAP(CHIPS)':
 C_PATH='@s9s_mb_2u_lib.s9s_mb_2u(sch_1):page384_i122@pure_quanta.q_cap(chips)';

PART_NAME
 R42 'Q_RES_0402LF-10K,1%,1/16W,CHIPA':;

SECTION_NUMBER 1
 '@S9S_MB_2U_LIB.S9S_MB_2U(SCH_1):PAGE383_I11@PURE_QUANTA.Q_RES(CHIPS)':
 C_PATH='@s9s_mb_2u_lib.s9s_mb_2u(sch_1):page383_i11@pure_quanta.q_res(chips)';

PART_NAME
 J17 'SCONN288_ADR50001P013C01-SCONNA':;

SECTION_NUMBER 1
 '@S9S_MB_2U_LIB.S9S_MB_2U(SCH_1):PAGE383_I12@PURE_QUANTA.SCONN288_ADR50001P013C01(CHIPS)':
 C_PATH='@s9s_mb_2u_lib.s9s_mb_2u(sch_1):page383_i12@pure_quanta.sconn288_adr50001~
p013c01(chips)';

SECTION_NUMBER 2
 '@S9S_MB_2U_LIB.S9S_MB_2U(SCH_1):PAGE383_I126@PURE_QUANTA.SCONN288_ADR50001P013C01(CHIPS)':
 C_PATH='@s9s_mb_2u_lib.s9s_mb_2u(sch_1):page383_i126@pure_quanta.sconn288_adr5000~
1p013c01(chips)';

SECTION_NUMBER 3
 '@S9S_MB_2U_LIB.S9S_MB_2U(SCH_1):PAGE383_I147@PURE_QUANTA.SCONN288_ADR50001P013C01(CHIPS)':
 C_PATH='@s9s_mb_2u_lib.s9s_mb_2u(sch_1):page383_i147@pure_quanta.sconn288_adr5000~
1p013c01(chips)';

PART_NAME
 C52 'Q_CAP_C0805-10UF,16V,10%,X7R,CA':;

SECTION_NUMBER 1
 '@S9S_MB_2U_LIB.S9S_MB_2U(SCH_1):PAGE383_I145@PURE_QUANTA.Q_CAP(CHIPS)':
 C_PATH='@s9s_mb_2u_lib.s9s_mb_2u(sch_1):page383_i145@pure_quanta.q_cap(chips)';

PART_NAME
 C51 'Q_CAP_C0805-10UF,16V,10%,X7R,CA':;

SECTION_NUMBER 1
 '@S9S_MB_2U_LIB.S9S_MB_2U(SCH_1):PAGE383_I123@PURE_QUANTA.Q_CAP(CHIPS)':
 C_PATH='@s9s_mb_2u_lib.s9s_mb_2u(sch_1):page383_i123@pure_quanta.q_cap(chips)';

PART_NAME
 C50 'Q_CAP_C0402-2.2UF,6.3V,20%,X6SA':;

SECTION_NUMBER 1
 '@S9S_MB_2U_LIB.S9S_MB_2U(SCH_1):PAGE383_I122@PURE_QUANTA.Q_CAP(CHIPS)':
 C_PATH='@s9s_mb_2u_lib.s9s_mb_2u(sch_1):page383_i122@pure_quanta.q_cap(chips)';

PART_NAME
 R41 'Q_RES_0402LF-196K,1%,1/16W,CHIA':;

SECTION_NUMBER 1
 '@S9S_MB_2U_LIB.S9S_MB_2U(SCH_1):PAGE382_I5@PURE_QUANTA.Q_RES(CHIPS)':
 C_PATH='@s9s_mb_2u_lib.s9s_mb_2u(sch_1):page382_i5@pure_quanta.q_res(chips)';

PART_NAME
 J16 'SCONN288_ADR50001P003C01-SCONNA':;

SECTION_NUMBER 1
 '@S9S_MB_2U_LIB.S9S_MB_2U(SCH_1):PAGE382_I6@PURE_QUANTA.SCONN288_ADR50001P003C01(CHIPS)':
 C_PATH='@s9s_mb_2u_lib.s9s_mb_2u(sch_1):page382_i6@pure_quanta.sconn288_adr50001p~
003c01(chips)';

SECTION_NUMBER 2
 '@S9S_MB_2U_LIB.S9S_MB_2U(SCH_1):PAGE382_I132@PURE_QUANTA.SCONN288_ADR50001P003C01(CHIPS)':
 C_PATH='@s9s_mb_2u_lib.s9s_mb_2u(sch_1):page382_i132@pure_quanta.sconn288_adr5000~
1p003c01(chips)';

SECTION_NUMBER 3
 '@S9S_MB_2U_LIB.S9S_MB_2U(SCH_1):PAGE382_I64@PURE_QUANTA.SCONN288_ADR50001P003C01(CHIPS)':
 C_PATH='@s9s_mb_2u_lib.s9s_mb_2u(sch_1):page382_i64@pure_quanta.sconn288_adr50001~
p003c01(chips)';

PART_NAME
 C49 'Q_CAP_C0805-10UF,16V,10%,X7R,CA':;

SECTION_NUMBER 1
 '@S9S_MB_2U_LIB.S9S_MB_2U(SCH_1):PAGE382_I62@PURE_QUANTA.Q_CAP(CHIPS)':
 C_PATH='@s9s_mb_2u_lib.s9s_mb_2u(sch_1):page382_i62@pure_quanta.q_cap(chips)';

PART_NAME
 C48 'Q_CAP_C0805-10UF,16V,10%,X7R,CA':;

SECTION_NUMBER 1
 '@S9S_MB_2U_LIB.S9S_MB_2U(SCH_1):PAGE382_I59@PURE_QUANTA.Q_CAP(CHIPS)':
 C_PATH='@s9s_mb_2u_lib.s9s_mb_2u(sch_1):page382_i59@pure_quanta.q_cap(chips)';

PART_NAME
 C47 'Q_CAP_C0402-2.2UF,6.3V,20%,X6SA':;

SECTION_NUMBER 1
 '@S9S_MB_2U_LIB.S9S_MB_2U(SCH_1):PAGE382_I56@PURE_QUANTA.Q_CAP(CHIPS)':
 C_PATH='@s9s_mb_2u_lib.s9s_mb_2u(sch_1):page382_i56@pure_quanta.q_cap(chips)';

PART_NAME
 R40 'Q_RES_0402LF-127K,1%,1/16W,CHIA':;

SECTION_NUMBER 1
 '@S9S_MB_2U_LIB.S9S_MB_2U(SCH_1):PAGE381_I47@PURE_QUANTA.Q_RES(CHIPS)':
 C_PATH='@s9s_mb_2u_lib.s9s_mb_2u(sch_1):page381_i47@pure_quanta.q_res(chips)';

PART_NAME
 J15 'SCONN288_ADR50001P013C01-SCONNA':;

SECTION_NUMBER 1
 '@S9S_MB_2U_LIB.S9S_MB_2U(SCH_1):PAGE381_I48@PURE_QUANTA.SCONN288_ADR50001P013C01(CHIPS)':
 C_PATH='@s9s_mb_2u_lib.s9s_mb_2u(sch_1):page381_i48@pure_quanta.sconn288_adr50001~
p013c01(chips)';

SECTION_NUMBER 2
 '@S9S_MB_2U_LIB.S9S_MB_2U(SCH_1):PAGE381_I124@PURE_QUANTA.SCONN288_ADR50001P013C01(CHIPS)':
 C_PATH='@s9s_mb_2u_lib.s9s_mb_2u(sch_1):page381_i124@pure_quanta.sconn288_adr5000~
1p013c01(chips)';

SECTION_NUMBER 3
 '@S9S_MB_2U_LIB.S9S_MB_2U(SCH_1):PAGE381_I176@PURE_QUANTA.SCONN288_ADR50001P013C01(CHIPS)':
 C_PATH='@s9s_mb_2u_lib.s9s_mb_2u(sch_1):page381_i176@pure_quanta.sconn288_adr5000~
1p013c01(chips)';

PART_NAME
 C46 'Q_CAP_C0805-10UF,16V,10%,X7R,CA':;

SECTION_NUMBER 1
 '@S9S_MB_2U_LIB.S9S_MB_2U(SCH_1):PAGE381_I127@PURE_QUANTA.Q_CAP(CHIPS)':
 C_PATH='@s9s_mb_2u_lib.s9s_mb_2u(sch_1):page381_i127@pure_quanta.q_cap(chips)';

PART_NAME
 C45 'Q_CAP_C0805-10UF,16V,10%,X7R,CA':;

SECTION_NUMBER 1
 '@S9S_MB_2U_LIB.S9S_MB_2U(SCH_1):PAGE381_I125@PURE_QUANTA.Q_CAP(CHIPS)':
 C_PATH='@s9s_mb_2u_lib.s9s_mb_2u(sch_1):page381_i125@pure_quanta.q_cap(chips)';

PART_NAME
 C44 'Q_CAP_C0402-2.2UF,6.3V,20%,X6SA':;

SECTION_NUMBER 1
 '@S9S_MB_2U_LIB.S9S_MB_2U(SCH_1):PAGE381_I121@PURE_QUANTA.Q_CAP(CHIPS)':
 C_PATH='@s9s_mb_2u_lib.s9s_mb_2u(sch_1):page381_i121@pure_quanta.q_cap(chips)';

PART_NAME
 R39 'Q_RES_0402LF-84.5K,1%,1/16W,CHA':;

SECTION_NUMBER 1
 '@S9S_MB_2U_LIB.S9S_MB_2U(SCH_1):PAGE380_I46@PURE_QUANTA.Q_RES(CHIPS)':
 C_PATH='@s9s_mb_2u_lib.s9s_mb_2u(sch_1):page380_i46@pure_quanta.q_res(chips)';

PART_NAME
 J14 'SCONN288_ADR50001P003C01-SCONNA':;

SECTION_NUMBER 1
 '@S9S_MB_2U_LIB.S9S_MB_2U(SCH_1):PAGE380_I47@PURE_QUANTA.SCONN288_ADR50001P003C01(CHIPS)':
 C_PATH='@s9s_mb_2u_lib.s9s_mb_2u(sch_1):page380_i47@pure_quanta.sconn288_adr50001~
p003c01(chips)';

SECTION_NUMBER 2
 '@S9S_MB_2U_LIB.S9S_MB_2U(SCH_1):PAGE380_I124@PURE_QUANTA.SCONN288_ADR50001P003C01(CHIPS)':
 C_PATH='@s9s_mb_2u_lib.s9s_mb_2u(sch_1):page380_i124@pure_quanta.sconn288_adr5000~
1p003c01(chips)';

SECTION_NUMBER 3
 '@S9S_MB_2U_LIB.S9S_MB_2U(SCH_1):PAGE380_I176@PURE_QUANTA.SCONN288_ADR50001P003C01(CHIPS)':
 C_PATH='@s9s_mb_2u_lib.s9s_mb_2u(sch_1):page380_i176@pure_quanta.sconn288_adr5000~
1p003c01(chips)';

PART_NAME
 C43 'Q_CAP_C0805-10UF,16V,10%,X7R,CA':;

SECTION_NUMBER 1
 '@S9S_MB_2U_LIB.S9S_MB_2U(SCH_1):PAGE380_I128@PURE_QUANTA.Q_CAP(CHIPS)':
 C_PATH='@s9s_mb_2u_lib.s9s_mb_2u(sch_1):page380_i128@pure_quanta.q_cap(chips)';

PART_NAME
 C42 'Q_CAP_C0805-10UF,16V,10%,X7R,CA':;

SECTION_NUMBER 1
 '@S9S_MB_2U_LIB.S9S_MB_2U(SCH_1):PAGE380_I125@PURE_QUANTA.Q_CAP(CHIPS)':
 C_PATH='@s9s_mb_2u_lib.s9s_mb_2u(sch_1):page380_i125@pure_quanta.q_cap(chips)';

PART_NAME
 C41 'Q_CAP_C0402-2.2UF,6.3V,20%,X6SA':;

SECTION_NUMBER 1
 '@S9S_MB_2U_LIB.S9S_MB_2U(SCH_1):PAGE380_I121@PURE_QUANTA.Q_CAP(CHIPS)':
 C_PATH='@s9s_mb_2u_lib.s9s_mb_2u(sch_1):page380_i121@pure_quanta.q_cap(chips)';

PART_NAME
 R38 'Q_RES_0402LF-54.9K,1%,1/16W,CHA':;

SECTION_NUMBER 1
 '@S9S_MB_2U_LIB.S9S_MB_2U(SCH_1):PAGE379_I10@PURE_QUANTA.Q_RES(CHIPS)':
 C_PATH='@s9s_mb_2u_lib.s9s_mb_2u(sch_1):page379_i10@pure_quanta.q_res(chips)';

PART_NAME
 J13 'SCONN288_ADR50001P013C01-SCONNA':;

SECTION_NUMBER 1
 '@S9S_MB_2U_LIB.S9S_MB_2U(SCH_1):PAGE379_I11@PURE_QUANTA.SCONN288_ADR50001P013C01(CHIPS)':
 C_PATH='@s9s_mb_2u_lib.s9s_mb_2u(sch_1):page379_i11@pure_quanta.sconn288_adr50001~
p013c01(chips)';

SECTION_NUMBER 2
 '@S9S_MB_2U_LIB.S9S_MB_2U(SCH_1):PAGE379_I127@PURE_QUANTA.SCONN288_ADR50001P013C01(CHIPS)':
 C_PATH='@s9s_mb_2u_lib.s9s_mb_2u(sch_1):page379_i127@pure_quanta.sconn288_adr5000~
1p013c01(chips)';

SECTION_NUMBER 3
 '@S9S_MB_2U_LIB.S9S_MB_2U(SCH_1):PAGE379_I164@PURE_QUANTA.SCONN288_ADR50001P013C01(CHIPS)':
 C_PATH='@s9s_mb_2u_lib.s9s_mb_2u(sch_1):page379_i164@pure_quanta.sconn288_adr5000~
1p013c01(chips)';

PART_NAME
 C40 'Q_CAP_C0805-10UF,16V,10%,X7R,CA':;

SECTION_NUMBER 1
 '@S9S_MB_2U_LIB.S9S_MB_2U(SCH_1):PAGE379_I162@PURE_QUANTA.Q_CAP(CHIPS)':
 C_PATH='@s9s_mb_2u_lib.s9s_mb_2u(sch_1):page379_i162@pure_quanta.q_cap(chips)';

PART_NAME
 C39 'Q_CAP_C0805-10UF,16V,10%,X7R,CA':;

SECTION_NUMBER 1
 '@S9S_MB_2U_LIB.S9S_MB_2U(SCH_1):PAGE379_I125@PURE_QUANTA.Q_CAP(CHIPS)':
 C_PATH='@s9s_mb_2u_lib.s9s_mb_2u(sch_1):page379_i125@pure_quanta.q_cap(chips)';

PART_NAME
 C38 'Q_CAP_C0402-2.2UF,6.3V,20%,X6SA':;

SECTION_NUMBER 1
 '@S9S_MB_2U_LIB.S9S_MB_2U(SCH_1):PAGE379_I123@PURE_QUANTA.Q_CAP(CHIPS)':
 C_PATH='@s9s_mb_2u_lib.s9s_mb_2u(sch_1):page379_i123@pure_quanta.q_cap(chips)';

PART_NAME
 R37 'Q_RES_0402LF-35.7K,1%,1/16W,CHA':;

SECTION_NUMBER 1
 '@S9S_MB_2U_LIB.S9S_MB_2U(SCH_1):PAGE378_I2@PURE_QUANTA.Q_RES(CHIPS)':
 C_PATH='@s9s_mb_2u_lib.s9s_mb_2u(sch_1):page378_i2@pure_quanta.q_res(chips)';

PART_NAME
 J12 'SCONN288_ADR50001P003C01-SCONNA':;

SECTION_NUMBER 1
 '@S9S_MB_2U_LIB.S9S_MB_2U(SCH_1):PAGE378_I24@PURE_QUANTA.SCONN288_ADR50001P003C01(CHIPS)':
 C_PATH='@s9s_mb_2u_lib.s9s_mb_2u(sch_1):page378_i24@pure_quanta.sconn288_adr50001~
p003c01(chips)';

SECTION_NUMBER 2
 '@S9S_MB_2U_LIB.S9S_MB_2U(SCH_1):PAGE378_I125@PURE_QUANTA.SCONN288_ADR50001P003C01(CHIPS)':
 C_PATH='@s9s_mb_2u_lib.s9s_mb_2u(sch_1):page378_i125@pure_quanta.sconn288_adr5000~
1p003c01(chips)';

SECTION_NUMBER 3
 '@S9S_MB_2U_LIB.S9S_MB_2U(SCH_1):PAGE378_I175@PURE_QUANTA.SCONN288_ADR50001P003C01(CHIPS)':
 C_PATH='@s9s_mb_2u_lib.s9s_mb_2u(sch_1):page378_i175@pure_quanta.sconn288_adr5000~
1p003c01(chips)';

PART_NAME
 C37 'Q_CAP_C0805-10UF,16V,10%,X7R,CA':;

SECTION_NUMBER 1
 '@S9S_MB_2U_LIB.S9S_MB_2U(SCH_1):PAGE378_I128@PURE_QUANTA.Q_CAP(CHIPS)':
 C_PATH='@s9s_mb_2u_lib.s9s_mb_2u(sch_1):page378_i128@pure_quanta.q_cap(chips)';

PART_NAME
 C36 'Q_CAP_C0805-10UF,16V,10%,X7R,CA':;

SECTION_NUMBER 1
 '@S9S_MB_2U_LIB.S9S_MB_2U(SCH_1):PAGE378_I126@PURE_QUANTA.Q_CAP(CHIPS)':
 C_PATH='@s9s_mb_2u_lib.s9s_mb_2u(sch_1):page378_i126@pure_quanta.q_cap(chips)';

PART_NAME
 C35 'Q_CAP_C0402-2.2UF,6.3V,20%,X6SA':;

SECTION_NUMBER 1
 '@S9S_MB_2U_LIB.S9S_MB_2U(SCH_1):PAGE378_I122@PURE_QUANTA.Q_CAP(CHIPS)':
 C_PATH='@s9s_mb_2u_lib.s9s_mb_2u(sch_1):page378_i122@pure_quanta.q_cap(chips)';

PART_NAME
 R36 'Q_RES_0402LF-23.2K,1%,1/16W,CHA':;

SECTION_NUMBER 1
 '@S9S_MB_2U_LIB.S9S_MB_2U(SCH_1):PAGE377_I2@PURE_QUANTA.Q_RES(CHIPS)':
 C_PATH='@s9s_mb_2u_lib.s9s_mb_2u(sch_1):page377_i2@pure_quanta.q_res(chips)';

PART_NAME
 J11 'SCONN288_ADR50001P013C01-SCONNA':;

SECTION_NUMBER 1
 '@S9S_MB_2U_LIB.S9S_MB_2U(SCH_1):PAGE377_I25@PURE_QUANTA.SCONN288_ADR50001P013C01(CHIPS)':
 C_PATH='@s9s_mb_2u_lib.s9s_mb_2u(sch_1):page377_i25@pure_quanta.sconn288_adr50001~
p013c01(chips)';

SECTION_NUMBER 2
 '@S9S_MB_2U_LIB.S9S_MB_2U(SCH_1):PAGE377_I126@PURE_QUANTA.SCONN288_ADR50001P013C01(CHIPS)':
 C_PATH='@s9s_mb_2u_lib.s9s_mb_2u(sch_1):page377_i126@pure_quanta.sconn288_adr5000~
1p013c01(chips)';

SECTION_NUMBER 3
 '@S9S_MB_2U_LIB.S9S_MB_2U(SCH_1):PAGE377_I175@PURE_QUANTA.SCONN288_ADR50001P013C01(CHIPS)':
 C_PATH='@s9s_mb_2u_lib.s9s_mb_2u(sch_1):page377_i175@pure_quanta.sconn288_adr5000~
1p013c01(chips)';

PART_NAME
 C34 'Q_CAP_C0805-10UF,16V,10%,X7R,CA':;

SECTION_NUMBER 1
 '@S9S_MB_2U_LIB.S9S_MB_2U(SCH_1):PAGE377_I130@PURE_QUANTA.Q_CAP(CHIPS)':
 C_PATH='@s9s_mb_2u_lib.s9s_mb_2u(sch_1):page377_i130@pure_quanta.q_cap(chips)';

PART_NAME
 C33 'Q_CAP_C0805-10UF,16V,10%,X7R,CA':;

SECTION_NUMBER 1
 '@S9S_MB_2U_LIB.S9S_MB_2U(SCH_1):PAGE377_I127@PURE_QUANTA.Q_CAP(CHIPS)':
 C_PATH='@s9s_mb_2u_lib.s9s_mb_2u(sch_1):page377_i127@pure_quanta.q_cap(chips)';

PART_NAME
 C32 'Q_CAP_C0402-2.2UF,6.3V,20%,X6SA':;

SECTION_NUMBER 1
 '@S9S_MB_2U_LIB.S9S_MB_2U(SCH_1):PAGE377_I122@PURE_QUANTA.Q_CAP(CHIPS)':
 C_PATH='@s9s_mb_2u_lib.s9s_mb_2u(sch_1):page377_i122@pure_quanta.q_cap(chips)';

PART_NAME
 R35 'Q_RES_0402LF-15.4K,1%,1/16W,CHA':;

SECTION_NUMBER 1
 '@S9S_MB_2U_LIB.S9S_MB_2U(SCH_1):PAGE376_I2@PURE_QUANTA.Q_RES(CHIPS)':
 C_PATH='@s9s_mb_2u_lib.s9s_mb_2u(sch_1):page376_i2@pure_quanta.q_res(chips)';

PART_NAME
 J10 'SCONN288_ADR50001P003C01-SCONNA':;

SECTION_NUMBER 1
 '@S9S_MB_2U_LIB.S9S_MB_2U(SCH_1):PAGE376_I13@PURE_QUANTA.SCONN288_ADR50001P003C01(CHIPS)':
 C_PATH='@s9s_mb_2u_lib.s9s_mb_2u(sch_1):page376_i13@pure_quanta.sconn288_adr50001~
p003c01(chips)';

SECTION_NUMBER 2
 '@S9S_MB_2U_LIB.S9S_MB_2U(SCH_1):PAGE376_I127@PURE_QUANTA.SCONN288_ADR50001P003C01(CHIPS)':
 C_PATH='@s9s_mb_2u_lib.s9s_mb_2u(sch_1):page376_i127@pure_quanta.sconn288_adr5000~
1p003c01(chips)';

SECTION_NUMBER 3
 '@S9S_MB_2U_LIB.S9S_MB_2U(SCH_1):PAGE376_I148@PURE_QUANTA.SCONN288_ADR50001P003C01(CHIPS)':
 C_PATH='@s9s_mb_2u_lib.s9s_mb_2u(sch_1):page376_i148@pure_quanta.sconn288_adr5000~
1p003c01(chips)';

PART_NAME
 C31 'Q_CAP_C0805-10UF,16V,10%,X7R,CA':;

SECTION_NUMBER 1
 '@S9S_MB_2U_LIB.S9S_MB_2U(SCH_1):PAGE376_I146@PURE_QUANTA.Q_CAP(CHIPS)':
 C_PATH='@s9s_mb_2u_lib.s9s_mb_2u(sch_1):page376_i146@pure_quanta.q_cap(chips)';

PART_NAME
 C30 'Q_CAP_C0805-10UF,16V,10%,X7R,CA':;

SECTION_NUMBER 1
 '@S9S_MB_2U_LIB.S9S_MB_2U(SCH_1):PAGE376_I124@PURE_QUANTA.Q_CAP(CHIPS)':
 C_PATH='@s9s_mb_2u_lib.s9s_mb_2u(sch_1):page376_i124@pure_quanta.q_cap(chips)';

PART_NAME
 C29 'Q_CAP_C0402-2.2UF,6.3V,20%,X6SA':;

SECTION_NUMBER 1
 '@S9S_MB_2U_LIB.S9S_MB_2U(SCH_1):PAGE376_I123@PURE_QUANTA.Q_CAP(CHIPS)':
 C_PATH='@s9s_mb_2u_lib.s9s_mb_2u(sch_1):page376_i123@pure_quanta.q_cap(chips)';

PART_NAME
 R34 'Q_RES_0402LF-10K,1%,1/16W,CHIPA':;

SECTION_NUMBER 1
 '@S9S_MB_2U_LIB.S9S_MB_2U(SCH_1):PAGE375_I11@PURE_QUANTA.Q_RES(CHIPS)':
 C_PATH='@s9s_mb_2u_lib.s9s_mb_2u(sch_1):page375_i11@pure_quanta.q_res(chips)';

PART_NAME
 J9 'SCONN288_ADR50001P013C01-SCONNA':;

SECTION_NUMBER 1
 '@S9S_MB_2U_LIB.S9S_MB_2U(SCH_1):PAGE375_I12@PURE_QUANTA.SCONN288_ADR50001P013C01(CHIPS)':
 C_PATH='@s9s_mb_2u_lib.s9s_mb_2u(sch_1):page375_i12@pure_quanta.sconn288_adr50001~
p013c01(chips)';

SECTION_NUMBER 2
 '@S9S_MB_2U_LIB.S9S_MB_2U(SCH_1):PAGE375_I126@PURE_QUANTA.SCONN288_ADR50001P013C01(CHIPS)':
 C_PATH='@s9s_mb_2u_lib.s9s_mb_2u(sch_1):page375_i126@pure_quanta.sconn288_adr5000~
1p013c01(chips)';

SECTION_NUMBER 3
 '@S9S_MB_2U_LIB.S9S_MB_2U(SCH_1):PAGE375_I147@PURE_QUANTA.SCONN288_ADR50001P013C01(CHIPS)':
 C_PATH='@s9s_mb_2u_lib.s9s_mb_2u(sch_1):page375_i147@pure_quanta.sconn288_adr5000~
1p013c01(chips)';

PART_NAME
 C28 'Q_CAP_C0805-10UF,16V,10%,X7R,CA':;

SECTION_NUMBER 1
 '@S9S_MB_2U_LIB.S9S_MB_2U(SCH_1):PAGE375_I145@PURE_QUANTA.Q_CAP(CHIPS)':
 C_PATH='@s9s_mb_2u_lib.s9s_mb_2u(sch_1):page375_i145@pure_quanta.q_cap(chips)';

PART_NAME
 C27 'Q_CAP_C0805-10UF,16V,10%,X7R,CA':;

SECTION_NUMBER 1
 '@S9S_MB_2U_LIB.S9S_MB_2U(SCH_1):PAGE375_I123@PURE_QUANTA.Q_CAP(CHIPS)':
 C_PATH='@s9s_mb_2u_lib.s9s_mb_2u(sch_1):page375_i123@pure_quanta.q_cap(chips)';

PART_NAME
 C26 'Q_CAP_C0402-2.2UF,6.3V,20%,X6SA':;

SECTION_NUMBER 1
 '@S9S_MB_2U_LIB.S9S_MB_2U(SCH_1):PAGE375_I122@PURE_QUANTA.Q_CAP(CHIPS)':
 C_PATH='@s9s_mb_2u_lib.s9s_mb_2u(sch_1):page375_i122@pure_quanta.q_cap(chips)';

PART_NAME
 R33 'Q_RES_0402LF-196K,1%,1/16W,CHIA':;

SECTION_NUMBER 1
 '@S9S_MB_2U_LIB.S9S_MB_2U(SCH_1):PAGE374_I2@PURE_QUANTA.Q_RES(CHIPS)':
 C_PATH='@s9s_mb_2u_lib.s9s_mb_2u(sch_1):page374_i2@pure_quanta.q_res(chips)';

PART_NAME
 J8 'SCONN288_ADR50001P003C01-SCONNA':;

SECTION_NUMBER 1
 '@S9S_MB_2U_LIB.S9S_MB_2U(SCH_1):PAGE374_I50@PURE_QUANTA.SCONN288_ADR50001P003C01(CHIPS)':
 C_PATH='@s9s_mb_2u_lib.s9s_mb_2u(sch_1):page374_i50@pure_quanta.sconn288_adr50001~
p003c01(chips)';

SECTION_NUMBER 2
 '@S9S_MB_2U_LIB.S9S_MB_2U(SCH_1):PAGE374_I124@PURE_QUANTA.SCONN288_ADR50001P003C01(CHIPS)':
 C_PATH='@s9s_mb_2u_lib.s9s_mb_2u(sch_1):page374_i124@pure_quanta.sconn288_adr5000~
1p003c01(chips)';

SECTION_NUMBER 3
 '@S9S_MB_2U_LIB.S9S_MB_2U(SCH_1):PAGE374_I175@PURE_QUANTA.SCONN288_ADR50001P003C01(CHIPS)':
 C_PATH='@s9s_mb_2u_lib.s9s_mb_2u(sch_1):page374_i175@pure_quanta.sconn288_adr5000~
1p003c01(chips)';

PART_NAME
 C25 'Q_CAP_C0805-22UF,16V,20%,X6S,CA':;

SECTION_NUMBER 1
 '@S9S_MB_2U_LIB.S9S_MB_2U(SCH_1):PAGE374_I127@PURE_QUANTA.Q_CAP(CHIPS)':
 C_PATH='@s9s_mb_2u_lib.s9s_mb_2u(sch_1):page374_i127@pure_quanta.q_cap(chips)';

PART_NAME
 C24 'Q_CAP_C0805-10UF,16V,10%,X7R,CA':;

SECTION_NUMBER 1
 '@S9S_MB_2U_LIB.S9S_MB_2U(SCH_1):PAGE374_I125@PURE_QUANTA.Q_CAP(CHIPS)':
 C_PATH='@s9s_mb_2u_lib.s9s_mb_2u(sch_1):page374_i125@pure_quanta.q_cap(chips)';

PART_NAME
 C23 'Q_CAP_C0402-2.2UF,6.3V,20%,X6SA':;

SECTION_NUMBER 1
 '@S9S_MB_2U_LIB.S9S_MB_2U(SCH_1):PAGE374_I121@PURE_QUANTA.Q_CAP(CHIPS)':
 C_PATH='@s9s_mb_2u_lib.s9s_mb_2u(sch_1):page374_i121@pure_quanta.q_cap(chips)';

PART_NAME
 R32 'Q_RES_0402LF-127K,1%,1/16W,CHIA':;

SECTION_NUMBER 1
 '@S9S_MB_2U_LIB.S9S_MB_2U(SCH_1):PAGE373_I2@PURE_QUANTA.Q_RES(CHIPS)':
 C_PATH='@s9s_mb_2u_lib.s9s_mb_2u(sch_1):page373_i2@pure_quanta.q_res(chips)';

PART_NAME
 J7 'SCONN288_ADR50001P013C01-SCONNA':;

SECTION_NUMBER 1
 '@S9S_MB_2U_LIB.S9S_MB_2U(SCH_1):PAGE373_I12@PURE_QUANTA.SCONN288_ADR50001P013C01(CHIPS)':
 C_PATH='@s9s_mb_2u_lib.s9s_mb_2u(sch_1):page373_i12@pure_quanta.sconn288_adr50001~
p013c01(chips)';

SECTION_NUMBER 2
 '@S9S_MB_2U_LIB.S9S_MB_2U(SCH_1):PAGE373_I125@PURE_QUANTA.SCONN288_ADR50001P013C01(CHIPS)':
 C_PATH='@s9s_mb_2u_lib.s9s_mb_2u(sch_1):page373_i125@pure_quanta.sconn288_adr5000~
1p013c01(chips)';

SECTION_NUMBER 3
 '@S9S_MB_2U_LIB.S9S_MB_2U(SCH_1):PAGE373_I168@PURE_QUANTA.SCONN288_ADR50001P013C01(CHIPS)':
 C_PATH='@s9s_mb_2u_lib.s9s_mb_2u(sch_1):page373_i168@pure_quanta.sconn288_adr5000~
1p013c01(chips)';

PART_NAME
 C22 'Q_CAP_C0805-10UF,16V,10%,X7R,CA':;

SECTION_NUMBER 1
 '@S9S_MB_2U_LIB.S9S_MB_2U(SCH_1):PAGE373_I166@PURE_QUANTA.Q_CAP(CHIPS)':
 C_PATH='@s9s_mb_2u_lib.s9s_mb_2u(sch_1):page373_i166@pure_quanta.q_cap(chips)';

PART_NAME
 C21 'Q_CAP_C0805-10UF,16V,10%,X7R,CA':;

SECTION_NUMBER 1
 '@S9S_MB_2U_LIB.S9S_MB_2U(SCH_1):PAGE373_I126@PURE_QUANTA.Q_CAP(CHIPS)':
 C_PATH='@s9s_mb_2u_lib.s9s_mb_2u(sch_1):page373_i126@pure_quanta.q_cap(chips)';

PART_NAME
 C20 'Q_CAP_C0402-2.2UF,6.3V,20%,X6SA':;

SECTION_NUMBER 1
 '@S9S_MB_2U_LIB.S9S_MB_2U(SCH_1):PAGE373_I123@PURE_QUANTA.Q_CAP(CHIPS)':
 C_PATH='@s9s_mb_2u_lib.s9s_mb_2u(sch_1):page373_i123@pure_quanta.q_cap(chips)';

PART_NAME
 R31 'Q_RES_0402LF-84.5K,1%,1/16W,CHA':;

SECTION_NUMBER 1
 '@S9S_MB_2U_LIB.S9S_MB_2U(SCH_1):PAGE372_I45@PURE_QUANTA.Q_RES(CHIPS)':
 C_PATH='@s9s_mb_2u_lib.s9s_mb_2u(sch_1):page372_i45@pure_quanta.q_res(chips)';

PART_NAME
 J6 'SCONN288_ADR50001P003C01-SCONNA':;

SECTION_NUMBER 1
 '@S9S_MB_2U_LIB.S9S_MB_2U(SCH_1):PAGE372_I46@PURE_QUANTA.SCONN288_ADR50001P003C01(CHIPS)':
 C_PATH='@s9s_mb_2u_lib.s9s_mb_2u(sch_1):page372_i46@pure_quanta.sconn288_adr50001~
p003c01(chips)';

SECTION_NUMBER 2
 '@S9S_MB_2U_LIB.S9S_MB_2U(SCH_1):PAGE372_I123@PURE_QUANTA.SCONN288_ADR50001P003C01(CHIPS)':
 C_PATH='@s9s_mb_2u_lib.s9s_mb_2u(sch_1):page372_i123@pure_quanta.sconn288_adr5000~
1p003c01(chips)';

SECTION_NUMBER 3
 '@S9S_MB_2U_LIB.S9S_MB_2U(SCH_1):PAGE372_I175@PURE_QUANTA.SCONN288_ADR50001P003C01(CHIPS)':
 C_PATH='@s9s_mb_2u_lib.s9s_mb_2u(sch_1):page372_i175@pure_quanta.sconn288_adr5000~
1p003c01(chips)';

PART_NAME
 C19 'Q_CAP_C0805-10UF,16V,10%,X7R,CA':;

SECTION_NUMBER 1
 '@S9S_MB_2U_LIB.S9S_MB_2U(SCH_1):PAGE372_I127@PURE_QUANTA.Q_CAP(CHIPS)':
 C_PATH='@s9s_mb_2u_lib.s9s_mb_2u(sch_1):page372_i127@pure_quanta.q_cap(chips)';

PART_NAME
 C18 'Q_CAP_C0805-10UF,16V,10%,X7R,CA':;

SECTION_NUMBER 1
 '@S9S_MB_2U_LIB.S9S_MB_2U(SCH_1):PAGE372_I124@PURE_QUANTA.Q_CAP(CHIPS)':
 C_PATH='@s9s_mb_2u_lib.s9s_mb_2u(sch_1):page372_i124@pure_quanta.q_cap(chips)';

PART_NAME
 C17 'Q_CAP_C0402-2.2UF,6.3V,20%,X6SA':;

SECTION_NUMBER 1
 '@S9S_MB_2U_LIB.S9S_MB_2U(SCH_1):PAGE372_I120@PURE_QUANTA.Q_CAP(CHIPS)':
 C_PATH='@s9s_mb_2u_lib.s9s_mb_2u(sch_1):page372_i120@pure_quanta.q_cap(chips)';

PART_NAME
 R30 'Q_RES_0402LF-54.9K,1%,1/16W,CHA':;

SECTION_NUMBER 1
 '@S9S_MB_2U_LIB.S9S_MB_2U(SCH_1):PAGE371_I3@PURE_QUANTA.Q_RES(CHIPS)':
 C_PATH='@s9s_mb_2u_lib.s9s_mb_2u(sch_1):page371_i3@pure_quanta.q_res(chips)';

PART_NAME
 J5 'SCONN288_ADR50001P013C01-SCONNA':;

SECTION_NUMBER 1
 '@S9S_MB_2U_LIB.S9S_MB_2U(SCH_1):PAGE371_I24@PURE_QUANTA.SCONN288_ADR50001P013C01(CHIPS)':
 C_PATH='@s9s_mb_2u_lib.s9s_mb_2u(sch_1):page371_i24@pure_quanta.sconn288_adr50001~
p013c01(chips)';

SECTION_NUMBER 2
 '@S9S_MB_2U_LIB.S9S_MB_2U(SCH_1):PAGE371_I125@PURE_QUANTA.SCONN288_ADR50001P013C01(CHIPS)':
 C_PATH='@s9s_mb_2u_lib.s9s_mb_2u(sch_1):page371_i125@pure_quanta.sconn288_adr5000~
1p013c01(chips)';

SECTION_NUMBER 3
 '@S9S_MB_2U_LIB.S9S_MB_2U(SCH_1):PAGE371_I174@PURE_QUANTA.SCONN288_ADR50001P013C01(CHIPS)':
 C_PATH='@s9s_mb_2u_lib.s9s_mb_2u(sch_1):page371_i174@pure_quanta.sconn288_adr5000~
1p013c01(chips)';

PART_NAME
 C16 'Q_CAP_C0805-10UF,16V,10%,X7R,CA':;

SECTION_NUMBER 1
 '@S9S_MB_2U_LIB.S9S_MB_2U(SCH_1):PAGE371_I123@PURE_QUANTA.Q_CAP(CHIPS)':
 C_PATH='@s9s_mb_2u_lib.s9s_mb_2u(sch_1):page371_i123@pure_quanta.q_cap(chips)';

PART_NAME
 C15 'Q_CAP_C0805-10UF,16V,10%,X7R,CA':;

SECTION_NUMBER 1
 '@S9S_MB_2U_LIB.S9S_MB_2U(SCH_1):PAGE371_I121@PURE_QUANTA.Q_CAP(CHIPS)':
 C_PATH='@s9s_mb_2u_lib.s9s_mb_2u(sch_1):page371_i121@pure_quanta.q_cap(chips)';

PART_NAME
 C14 'Q_CAP_C0402-2.2UF,6.3V,20%,X6SA':;

SECTION_NUMBER 1
 '@S9S_MB_2U_LIB.S9S_MB_2U(SCH_1):PAGE371_I120@PURE_QUANTA.Q_CAP(CHIPS)':
 C_PATH='@s9s_mb_2u_lib.s9s_mb_2u(sch_1):page371_i120@pure_quanta.q_cap(chips)';

PART_NAME
 R29 'Q_RES_0402LF-35.7K,1%,1/16W,CHA':;

SECTION_NUMBER 1
 '@S9S_MB_2U_LIB.S9S_MB_2U(SCH_1):PAGE370_I1@PURE_QUANTA.Q_RES(CHIPS)':
 C_PATH='@s9s_mb_2u_lib.s9s_mb_2u(sch_1):page370_i1@pure_quanta.q_res(chips)';

PART_NAME
 J4 'SCONN288_ADR50001P003C01-SCONNA':;

SECTION_NUMBER 1
 '@S9S_MB_2U_LIB.S9S_MB_2U(SCH_1):PAGE370_I23@PURE_QUANTA.SCONN288_ADR50001P003C01(CHIPS)':
 C_PATH='@s9s_mb_2u_lib.s9s_mb_2u(sch_1):page370_i23@pure_quanta.sconn288_adr50001~
p003c01(chips)';

SECTION_NUMBER 2
 '@S9S_MB_2U_LIB.S9S_MB_2U(SCH_1):PAGE370_I124@PURE_QUANTA.SCONN288_ADR50001P003C01(CHIPS)':
 C_PATH='@s9s_mb_2u_lib.s9s_mb_2u(sch_1):page370_i124@pure_quanta.sconn288_adr5000~
1p003c01(chips)';

SECTION_NUMBER 3
 '@S9S_MB_2U_LIB.S9S_MB_2U(SCH_1):PAGE370_I174@PURE_QUANTA.SCONN288_ADR50001P003C01(CHIPS)':
 C_PATH='@s9s_mb_2u_lib.s9s_mb_2u(sch_1):page370_i174@pure_quanta.sconn288_adr5000~
1p003c01(chips)';

PART_NAME
 C13 'Q_CAP_C0805-10UF,16V,10%,X7R,CA':;

SECTION_NUMBER 1
 '@S9S_MB_2U_LIB.S9S_MB_2U(SCH_1):PAGE370_I127@PURE_QUANTA.Q_CAP(CHIPS)':
 C_PATH='@s9s_mb_2u_lib.s9s_mb_2u(sch_1):page370_i127@pure_quanta.q_cap(chips)';

PART_NAME
 C12 'Q_CAP_C0805-10UF,16V,10%,X7R,CA':;

SECTION_NUMBER 1
 '@S9S_MB_2U_LIB.S9S_MB_2U(SCH_1):PAGE370_I125@PURE_QUANTA.Q_CAP(CHIPS)':
 C_PATH='@s9s_mb_2u_lib.s9s_mb_2u(sch_1):page370_i125@pure_quanta.q_cap(chips)';

PART_NAME
 C11 'Q_CAP_C0402-2.2UF,6.3V,20%,X6SA':;

SECTION_NUMBER 1
 '@S9S_MB_2U_LIB.S9S_MB_2U(SCH_1):PAGE370_I121@PURE_QUANTA.Q_CAP(CHIPS)':
 C_PATH='@s9s_mb_2u_lib.s9s_mb_2u(sch_1):page370_i121@pure_quanta.q_cap(chips)';

PART_NAME
 R28 'Q_RES_0402LF-23.2K,1%,1/16W,CHA':;

SECTION_NUMBER 1
 '@S9S_MB_2U_LIB.S9S_MB_2U(SCH_1):PAGE369_I10@PURE_QUANTA.Q_RES(CHIPS)':
 C_PATH='@s9s_mb_2u_lib.s9s_mb_2u(sch_1):page369_i10@pure_quanta.q_res(chips)';

PART_NAME
 J3 'SCONN288_ADR50001P013C01-SCONNA':;

SECTION_NUMBER 1
 '@S9S_MB_2U_LIB.S9S_MB_2U(SCH_1):PAGE369_I11@PURE_QUANTA.SCONN288_ADR50001P013C01(CHIPS)':
 C_PATH='@s9s_mb_2u_lib.s9s_mb_2u(sch_1):page369_i11@pure_quanta.sconn288_adr50001~
p013c01(chips)';

SECTION_NUMBER 2
 '@S9S_MB_2U_LIB.S9S_MB_2U(SCH_1):PAGE369_I125@PURE_QUANTA.SCONN288_ADR50001P013C01(CHIPS)':
 C_PATH='@s9s_mb_2u_lib.s9s_mb_2u(sch_1):page369_i125@pure_quanta.sconn288_adr5000~
1p013c01(chips)';

SECTION_NUMBER 3
 '@S9S_MB_2U_LIB.S9S_MB_2U(SCH_1):PAGE369_I146@PURE_QUANTA.SCONN288_ADR50001P013C01(CHIPS)':
 C_PATH='@s9s_mb_2u_lib.s9s_mb_2u(sch_1):page369_i146@pure_quanta.sconn288_adr5000~
1p013c01(chips)';

PART_NAME
 C10 'Q_CAP_C0805-10UF,16V,10%,X7R,CA':;

SECTION_NUMBER 1
 '@S9S_MB_2U_LIB.S9S_MB_2U(SCH_1):PAGE369_I144@PURE_QUANTA.Q_CAP(CHIPS)':
 C_PATH='@s9s_mb_2u_lib.s9s_mb_2u(sch_1):page369_i144@pure_quanta.q_cap(chips)';

PART_NAME
 C9 'Q_CAP_C0805-10UF,16V,10%,X7R,CA':;

SECTION_NUMBER 1
 '@S9S_MB_2U_LIB.S9S_MB_2U(SCH_1):PAGE369_I122@PURE_QUANTA.Q_CAP(CHIPS)':
 C_PATH='@s9s_mb_2u_lib.s9s_mb_2u(sch_1):page369_i122@pure_quanta.q_cap(chips)';

PART_NAME
 C8 'Q_CAP_C0402-2.2UF,6.3V,20%,X6SA':;

SECTION_NUMBER 1
 '@S9S_MB_2U_LIB.S9S_MB_2U(SCH_1):PAGE369_I121@PURE_QUANTA.Q_CAP(CHIPS)':
 C_PATH='@s9s_mb_2u_lib.s9s_mb_2u(sch_1):page369_i121@pure_quanta.q_cap(chips)';

PART_NAME
 R27 'Q_RES_0402LF-15.4K,1%,1/16W,CHA':;

SECTION_NUMBER 1
 '@S9S_MB_2U_LIB.S9S_MB_2U(SCH_1):PAGE368_I10@PURE_QUANTA.Q_RES(CHIPS)':
 C_PATH='@s9s_mb_2u_lib.s9s_mb_2u(sch_1):page368_i10@pure_quanta.q_res(chips)';

PART_NAME
 J2 'SCONN288_ADR50001P003C01-SCONNA':;

SECTION_NUMBER 1
 '@S9S_MB_2U_LIB.S9S_MB_2U(SCH_1):PAGE368_I177@PURE_QUANTA.SCONN288_ADR50001P003C01(CHIPS)':
 C_PATH='@s9s_mb_2u_lib.s9s_mb_2u(sch_1):page368_i177@pure_quanta.sconn288_adr5000~
1p003c01(chips)';

SECTION_NUMBER 2
 '@S9S_MB_2U_LIB.S9S_MB_2U(SCH_1):PAGE368_I178@PURE_QUANTA.SCONN288_ADR50001P003C01(CHIPS)':
 C_PATH='@s9s_mb_2u_lib.s9s_mb_2u(sch_1):page368_i178@pure_quanta.sconn288_adr5000~
1p003c01(chips)';

SECTION_NUMBER 3
 '@S9S_MB_2U_LIB.S9S_MB_2U(SCH_1):PAGE368_I179@PURE_QUANTA.SCONN288_ADR50001P003C01(CHIPS)':
 C_PATH='@s9s_mb_2u_lib.s9s_mb_2u(sch_1):page368_i179@pure_quanta.sconn288_adr5000~
1p003c01(chips)';

PART_NAME
 C7 'Q_CAP_C0805-10UF,16V,10%,X7R,CA':;

SECTION_NUMBER 1
 '@S9S_MB_2U_LIB.S9S_MB_2U(SCH_1):PAGE368_I144@PURE_QUANTA.Q_CAP(CHIPS)':
 C_PATH='@s9s_mb_2u_lib.s9s_mb_2u(sch_1):page368_i144@pure_quanta.q_cap(chips)';

PART_NAME
 C6 'Q_CAP_C0805-10UF,16V,10%,X7R,CA':;

SECTION_NUMBER 1
 '@S9S_MB_2U_LIB.S9S_MB_2U(SCH_1):PAGE368_I122@PURE_QUANTA.Q_CAP(CHIPS)':
 C_PATH='@s9s_mb_2u_lib.s9s_mb_2u(sch_1):page368_i122@pure_quanta.q_cap(chips)';

PART_NAME
 C5 'Q_CAP_C0402-2.2UF,6.3V,20%,X6SA':;

SECTION_NUMBER 1
 '@S9S_MB_2U_LIB.S9S_MB_2U(SCH_1):PAGE368_I120@PURE_QUANTA.Q_CAP(CHIPS)':
 C_PATH='@s9s_mb_2u_lib.s9s_mb_2u(sch_1):page368_i120@pure_quanta.q_cap(chips)';

PART_NAME
 R26 'Q_RES_0402LF-10K,1%,1/16W,CHIPA':;

SECTION_NUMBER 1
 '@S9S_MB_2U_LIB.S9S_MB_2U(SCH_1):PAGE367_I196@PURE_QUANTA.Q_RES(CHIPS)':
 C_PATH='@s9s_mb_2u_lib.s9s_mb_2u(sch_1):page367_i196@pure_quanta.q_res(chips)';

PART_NAME
 J1 'SCONN288_ADR50001P013C01-SCONNA':;

SECTION_NUMBER 1
 '@S9S_MB_2U_LIB.S9S_MB_2U(SCH_1):PAGE367_I198@PURE_QUANTA.SCONN288_ADR50001P013C01(CHIPS)':
 C_PATH='@s9s_mb_2u_lib.s9s_mb_2u(sch_1):page367_i198@pure_quanta.sconn288_adr5000~
1p013c01(chips)';

SECTION_NUMBER 2
 '@S9S_MB_2U_LIB.S9S_MB_2U(SCH_1):PAGE367_I199@PURE_QUANTA.SCONN288_ADR50001P013C01(CHIPS)':
 C_PATH='@s9s_mb_2u_lib.s9s_mb_2u(sch_1):page367_i199@pure_quanta.sconn288_adr5000~
1p013c01(chips)';

SECTION_NUMBER 3
 '@S9S_MB_2U_LIB.S9S_MB_2U(SCH_1):PAGE367_I200@PURE_QUANTA.SCONN288_ADR50001P013C01(CHIPS)':
 C_PATH='@s9s_mb_2u_lib.s9s_mb_2u(sch_1):page367_i200@pure_quanta.sconn288_adr5000~
1p013c01(chips)';

PART_NAME
 C4 'Q_CAP_C0805-10UF,16V,10%,X7R,CA':;

SECTION_NUMBER 1
 '@S9S_MB_2U_LIB.S9S_MB_2U(SCH_1):PAGE367_I190@PURE_QUANTA.Q_CAP(CHIPS)':
 C_PATH='@s9s_mb_2u_lib.s9s_mb_2u(sch_1):page367_i190@pure_quanta.q_cap(chips)';

PART_NAME
 C3 'Q_CAP_C0805-10UF,16V,10%,X7R,CA':;

SECTION_NUMBER 1
 '@S9S_MB_2U_LIB.S9S_MB_2U(SCH_1):PAGE367_I188@PURE_QUANTA.Q_CAP(CHIPS)':
 C_PATH='@s9s_mb_2u_lib.s9s_mb_2u(sch_1):page367_i188@pure_quanta.q_cap(chips)';

PART_NAME
 C2 'Q_CAP_C0402-2.2UF,6.3V,20%,X6SA':;

SECTION_NUMBER 1
 '@S9S_MB_2U_LIB.S9S_MB_2U(SCH_1):PAGE367_I192@PURE_QUANTA.Q_CAP(CHIPS)':
 C_PATH='@s9s_mb_2u_lib.s9s_mb_2u(sch_1):page367_i192@pure_quanta.q_cap(chips)';

PART_NAME
 U2 'SOCKET4677_AZIFS035P001C01-SOCA':;

SECTION_NUMBER 1
 '@S9S_MB_2U_LIB.S9S_MB_2U(SCH_1):PAGE13_I57@PURE_QUANTA.SOCKET4677_AZIFS035P001C01(CHIPS)':
 C_PATH='@s9s_mb_2u_lib.s9s_mb_2u(sch_1):page13_i57@pure_quanta.socket4677_azifs03~
5p001c01(chips)';

SECTION_NUMBER 2
 '@S9S_MB_2U_LIB.S9S_MB_2U(SCH_1):PAGE14_I1@PURE_QUANTA.SOCKET4677_AZIFS035P001C01(CHIPS)':
 C_PATH='@s9s_mb_2u_lib.s9s_mb_2u(sch_1):page14_i1@pure_quanta.socket4677_azifs035~
p001c01(chips)';

SECTION_NUMBER 3
 '@S9S_MB_2U_LIB.S9S_MB_2U(SCH_1):PAGE15_I1@PURE_QUANTA.SOCKET4677_AZIFS035P001C01(CHIPS)':
 C_PATH='@s9s_mb_2u_lib.s9s_mb_2u(sch_1):page15_i1@pure_quanta.socket4677_azifs035~
p001c01(chips)';

SECTION_NUMBER 4
 '@S9S_MB_2U_LIB.S9S_MB_2U(SCH_1):PAGE16_I1@PURE_QUANTA.SOCKET4677_AZIFS035P001C01(CHIPS)':
 C_PATH='@s9s_mb_2u_lib.s9s_mb_2u(sch_1):page16_i1@pure_quanta.socket4677_azifs035~
p001c01(chips)';

SECTION_NUMBER 5
 '@S9S_MB_2U_LIB.S9S_MB_2U(SCH_1):PAGE17_I1@PURE_QUANTA.SOCKET4677_AZIFS035P001C01(CHIPS)':
 C_PATH='@s9s_mb_2u_lib.s9s_mb_2u(sch_1):page17_i1@pure_quanta.socket4677_azifs035~
p001c01(chips)';

SECTION_NUMBER 6
 '@S9S_MB_2U_LIB.S9S_MB_2U(SCH_1):PAGE18_I1@PURE_QUANTA.SOCKET4677_AZIFS035P001C01(CHIPS)':
 C_PATH='@s9s_mb_2u_lib.s9s_mb_2u(sch_1):page18_i1@pure_quanta.socket4677_azifs035~
p001c01(chips)';

SECTION_NUMBER 7
 '@S9S_MB_2U_LIB.S9S_MB_2U(SCH_1):PAGE329_I1@PURE_QUANTA.SOCKET4677_AZIFS035P001C01(CHIPS)':
 C_PATH='@s9s_mb_2u_lib.s9s_mb_2u(sch_1):page329_i1@pure_quanta.socket4677_azifs03~
5p001c01(chips)';

SECTION_NUMBER 8
 '@S9S_MB_2U_LIB.S9S_MB_2U(SCH_1):PAGE330_I1@PURE_QUANTA.SOCKET4677_AZIFS035P001C01(CHIPS)':
 C_PATH='@s9s_mb_2u_lib.s9s_mb_2u(sch_1):page330_i1@pure_quanta.socket4677_azifs03~
5p001c01(chips)';

SECTION_NUMBER 9
 '@S9S_MB_2U_LIB.S9S_MB_2U(SCH_1):PAGE331_I169@PURE_QUANTA.SOCKET4677_AZIFS035P001C01(CHIPS)':
 C_PATH='@s9s_mb_2u_lib.s9s_mb_2u(sch_1):page331_i169@pure_quanta.socket4677_azifs~
035p001c01(chips)';

SECTION_NUMBER 10
 '@S9S_MB_2U_LIB.S9S_MB_2U(SCH_1):PAGE332_I169@PURE_QUANTA.SOCKET4677_AZIFS035P001C01(CHIPS)':
 C_PATH='@s9s_mb_2u_lib.s9s_mb_2u(sch_1):page332_i169@pure_quanta.socket4677_azifs~
035p001c01(chips)';

SECTION_NUMBER 11
 '@S9S_MB_2U_LIB.S9S_MB_2U(SCH_1):PAGE333_I169@PURE_QUANTA.SOCKET4677_AZIFS035P001C01(CHIPS)':
 C_PATH='@s9s_mb_2u_lib.s9s_mb_2u(sch_1):page333_i169@pure_quanta.socket4677_azifs~
035p001c01(chips)';

SECTION_NUMBER 12
 '@S9S_MB_2U_LIB.S9S_MB_2U(SCH_1):PAGE24_I169@PURE_QUANTA.SOCKET4677_AZIFS035P001C01(CHIPS)':
 C_PATH='@s9s_mb_2u_lib.s9s_mb_2u(sch_1):page24_i169@pure_quanta.socket4677_azifs0~
35p001c01(chips)';

SECTION_NUMBER 13
 '@S9S_MB_2U_LIB.S9S_MB_2U(SCH_1):PAGE334_I169@PURE_QUANTA.SOCKET4677_AZIFS035P001C01(CHIPS)':
 C_PATH='@s9s_mb_2u_lib.s9s_mb_2u(sch_1):page334_i169@pure_quanta.socket4677_azifs~
035p001c01(chips)';

SECTION_NUMBER 14
 '@S9S_MB_2U_LIB.S9S_MB_2U(SCH_1):PAGE26_I169@PURE_QUANTA.SOCKET4677_AZIFS035P001C01(CHIPS)':
 C_PATH='@s9s_mb_2u_lib.s9s_mb_2u(sch_1):page26_i169@pure_quanta.socket4677_azifs0~
35p001c01(chips)';

SECTION_NUMBER 15
 '@S9S_MB_2U_LIB.S9S_MB_2U(SCH_1):PAGE27_I169@PURE_QUANTA.SOCKET4677_AZIFS035P001C01(CHIPS)':
 C_PATH='@s9s_mb_2u_lib.s9s_mb_2u(sch_1):page27_i169@pure_quanta.socket4677_azifs0~
35p001c01(chips)';

SECTION_NUMBER 16
 '@S9S_MB_2U_LIB.S9S_MB_2U(SCH_1):PAGE28_I169@PURE_QUANTA.SOCKET4677_AZIFS035P001C01(CHIPS)':
 C_PATH='@s9s_mb_2u_lib.s9s_mb_2u(sch_1):page28_i169@pure_quanta.socket4677_azifs0~
35p001c01(chips)';

SECTION_NUMBER 17
 '@S9S_MB_2U_LIB.S9S_MB_2U(SCH_1):PAGE29_I37@PURE_QUANTA.SOCKET4677_AZIFS035P001C01(CHIPS)':
 C_PATH='@s9s_mb_2u_lib.s9s_mb_2u(sch_1):page29_i37@pure_quanta.socket4677_azifs03~
5p001c01(chips)';

SECTION_NUMBER 18
 '@S9S_MB_2U_LIB.S9S_MB_2U(SCH_1):PAGE29_I176@PURE_QUANTA.SOCKET4677_AZIFS035P001C01(CHIPS)':
 C_PATH='@s9s_mb_2u_lib.s9s_mb_2u(sch_1):page29_i176@pure_quanta.socket4677_azifs0~
35p001c01(chips)';

SECTION_NUMBER 19
 '@S9S_MB_2U_LIB.S9S_MB_2U(SCH_1):PAGE30_I139@PURE_QUANTA.SOCKET4677_AZIFS035P001C01(CHIPS)':
 C_PATH='@s9s_mb_2u_lib.s9s_mb_2u(sch_1):page30_i139@pure_quanta.socket4677_azifs0~
35p001c01(chips)';

SECTION_NUMBER 20
 '@S9S_MB_2U_LIB.S9S_MB_2U(SCH_1):PAGE30_I140@PURE_QUANTA.SOCKET4677_AZIFS035P001C01(CHIPS)':
 C_PATH='@s9s_mb_2u_lib.s9s_mb_2u(sch_1):page30_i140@pure_quanta.socket4677_azifs0~
35p001c01(chips)';

SECTION_NUMBER 21
 '@S9S_MB_2U_LIB.S9S_MB_2U(SCH_1):PAGE31_I139@PURE_QUANTA.SOCKET4677_AZIFS035P001C01(CHIPS)':
 C_PATH='@s9s_mb_2u_lib.s9s_mb_2u(sch_1):page31_i139@pure_quanta.socket4677_azifs0~
35p001c01(chips)';

SECTION_NUMBER 22
 '@S9S_MB_2U_LIB.S9S_MB_2U(SCH_1):PAGE32_I70@PURE_QUANTA.SOCKET4677_AZIFS035P001C01(CHIPS)':
 C_PATH='@s9s_mb_2u_lib.s9s_mb_2u(sch_1):page32_i70@pure_quanta.socket4677_azifs03~
5p001c01(chips)';

SECTION_NUMBER 23
 '@S9S_MB_2U_LIB.S9S_MB_2U(SCH_1):PAGE33_I102@PURE_QUANTA.SOCKET4677_AZIFS035P001C01(CHIPS)':
 C_PATH='@s9s_mb_2u_lib.s9s_mb_2u(sch_1):page33_i102@pure_quanta.socket4677_azifs0~
35p001c01(chips)';

SECTION_NUMBER 24
 '@S9S_MB_2U_LIB.S9S_MB_2U(SCH_1):PAGE34_I102@PURE_QUANTA.SOCKET4677_AZIFS035P001C01(CHIPS)':
 C_PATH='@s9s_mb_2u_lib.s9s_mb_2u(sch_1):page34_i102@pure_quanta.socket4677_azifs0~
35p001c01(chips)';

SECTION_NUMBER 25
 '@S9S_MB_2U_LIB.S9S_MB_2U(SCH_1):PAGE35_I102@PURE_QUANTA.SOCKET4677_AZIFS035P001C01(CHIPS)':
 C_PATH='@s9s_mb_2u_lib.s9s_mb_2u(sch_1):page35_i102@pure_quanta.socket4677_azifs0~
35p001c01(chips)';

SECTION_NUMBER 26
 '@S9S_MB_2U_LIB.S9S_MB_2U(SCH_1):PAGE36_I1@PURE_QUANTA.SOCKET4677_AZIFS035P001C01(CHIPS)':
 C_PATH='@s9s_mb_2u_lib.s9s_mb_2u(sch_1):page36_i1@pure_quanta.socket4677_azifs035~
p001c01(chips)';

SECTION_NUMBER 27
 '@S9S_MB_2U_LIB.S9S_MB_2U(SCH_1):PAGE36_I7@PURE_QUANTA.SOCKET4677_AZIFS035P001C01(CHIPS)':
 C_PATH='@s9s_mb_2u_lib.s9s_mb_2u(sch_1):page36_i7@pure_quanta.socket4677_azifs035~
p001c01(chips)';

SECTION_NUMBER 28
 '@S9S_MB_2U_LIB.S9S_MB_2U(SCH_1):PAGE37_I7@PURE_QUANTA.SOCKET4677_AZIFS035P001C01(CHIPS)':
 C_PATH='@s9s_mb_2u_lib.s9s_mb_2u(sch_1):page37_i7@pure_quanta.socket4677_azifs035~
p001c01(chips)';

SECTION_NUMBER 29
 '@S9S_MB_2U_LIB.S9S_MB_2U(SCH_1):PAGE37_I8@PURE_QUANTA.SOCKET4677_AZIFS035P001C01(CHIPS)':
 C_PATH='@s9s_mb_2u_lib.s9s_mb_2u(sch_1):page37_i8@pure_quanta.socket4677_azifs035~
p001c01(chips)';

SECTION_NUMBER 30
 '@S9S_MB_2U_LIB.S9S_MB_2U(SCH_1):PAGE38_I4@PURE_QUANTA.SOCKET4677_AZIFS035P001C01(CHIPS)':
 C_PATH='@s9s_mb_2u_lib.s9s_mb_2u(sch_1):page38_i4@pure_quanta.socket4677_azifs035~
p001c01(chips)';

SECTION_NUMBER 31
 '@S9S_MB_2U_LIB.S9S_MB_2U(SCH_1):PAGE335_I1@PURE_QUANTA.SOCKET4677_AZIFS035P001C01(CHIPS)':
 C_PATH='@s9s_mb_2u_lib.s9s_mb_2u(sch_1):page335_i1@pure_quanta.socket4677_azifs03~
5p001c01(chips)';

SECTION_NUMBER 32
 '@S9S_MB_2U_LIB.S9S_MB_2U(SCH_1):PAGE335_I9@PURE_QUANTA.SOCKET4677_AZIFS035P001C01(CHIPS)':
 C_PATH='@s9s_mb_2u_lib.s9s_mb_2u(sch_1):page335_i9@pure_quanta.socket4677_azifs03~
5p001c01(chips)';

SECTION_NUMBER 33
 '@S9S_MB_2U_LIB.S9S_MB_2U(SCH_1):PAGE335_I10@PURE_QUANTA.SOCKET4677_AZIFS035P001C01(CHIPS)':
 C_PATH='@s9s_mb_2u_lib.s9s_mb_2u(sch_1):page335_i10@pure_quanta.socket4677_azifs0~
35p001c01(chips)';

SECTION_NUMBER 34
 '@S9S_MB_2U_LIB.S9S_MB_2U(SCH_1):PAGE336_I10@PURE_QUANTA.SOCKET4677_AZIFS035P001C01(CHIPS)':
 C_PATH='@s9s_mb_2u_lib.s9s_mb_2u(sch_1):page336_i10@pure_quanta.socket4677_azifs0~
35p001c01(chips)';

SECTION_NUMBER 35
 '@S9S_MB_2U_LIB.S9S_MB_2U(SCH_1):PAGE336_I11@PURE_QUANTA.SOCKET4677_AZIFS035P001C01(CHIPS)':
 C_PATH='@s9s_mb_2u_lib.s9s_mb_2u(sch_1):page336_i11@pure_quanta.socket4677_azifs0~
35p001c01(chips)';

SECTION_NUMBER 36
 '@S9S_MB_2U_LIB.S9S_MB_2U(SCH_1):PAGE336_I12@PURE_QUANTA.SOCKET4677_AZIFS035P001C01(CHIPS)':
 C_PATH='@s9s_mb_2u_lib.s9s_mb_2u(sch_1):page336_i12@pure_quanta.socket4677_azifs0~
35p001c01(chips)';

SECTION_NUMBER 37
 '@S9S_MB_2U_LIB.S9S_MB_2U(SCH_1):PAGE337_I9@PURE_QUANTA.SOCKET4677_AZIFS035P001C01(CHIPS)':
 C_PATH='@s9s_mb_2u_lib.s9s_mb_2u(sch_1):page337_i9@pure_quanta.socket4677_azifs03~
5p001c01(chips)';

SECTION_NUMBER 38
 '@S9S_MB_2U_LIB.S9S_MB_2U(SCH_1):PAGE337_I10@PURE_QUANTA.SOCKET4677_AZIFS035P001C01(CHIPS)':
 C_PATH='@s9s_mb_2u_lib.s9s_mb_2u(sch_1):page337_i10@pure_quanta.socket4677_azifs0~
35p001c01(chips)';

SECTION_NUMBER 39
 '@S9S_MB_2U_LIB.S9S_MB_2U(SCH_1):PAGE337_I11@PURE_QUANTA.SOCKET4677_AZIFS035P001C01(CHIPS)':
 C_PATH='@s9s_mb_2u_lib.s9s_mb_2u(sch_1):page337_i11@pure_quanta.socket4677_azifs0~
35p001c01(chips)';

SECTION_NUMBER 40
 '@S9S_MB_2U_LIB.S9S_MB_2U(SCH_1):PAGE338_I10@PURE_QUANTA.SOCKET4677_AZIFS035P001C01(CHIPS)':
 C_PATH='@s9s_mb_2u_lib.s9s_mb_2u(sch_1):page338_i10@pure_quanta.socket4677_azifs0~
35p001c01(chips)';

SECTION_NUMBER 41
 '@S9S_MB_2U_LIB.S9S_MB_2U(SCH_1):PAGE338_I11@PURE_QUANTA.SOCKET4677_AZIFS035P001C01(CHIPS)':
 C_PATH='@s9s_mb_2u_lib.s9s_mb_2u(sch_1):page338_i11@pure_quanta.socket4677_azifs0~
35p001c01(chips)';

SECTION_NUMBER 42
 '@S9S_MB_2U_LIB.S9S_MB_2U(SCH_1):PAGE338_I12@PURE_QUANTA.SOCKET4677_AZIFS035P001C01(CHIPS)':
 C_PATH='@s9s_mb_2u_lib.s9s_mb_2u(sch_1):page338_i12@pure_quanta.socket4677_azifs0~
35p001c01(chips)';

PART_NAME
 C1 'Q_CAP_C0402-10UF,6.3V,20%,X6S,A':;

SECTION_NUMBER 1
 '@S9S_MB_2U_LIB.S9S_MB_2U(SCH_1):PAGE37_I15@PURE_QUANTA.Q_CAP(CHIPS)':
 C_PATH='@s9s_mb_2u_lib.s9s_mb_2u(sch_1):page37_i15@pure_quanta.q_cap(chips)';

PART_NAME
 U62 'BAS70057F-BAS70-05-7-F,SMLF,ICA':;

SECTION_NUMBER 1
 '@S9S_MB_2U_LIB.S9S_MB_2U(SCH_1):PAGE521_I64@PURE_QUANTA.BAS70057F(CHIPS)':
 C_PATH='@s9s_mb_2u_lib.s9s_mb_2u(sch_1):page521_i64@pure_quanta.bas70057f(chips)';

PART_NAME
 U4 'EMMITSBURG_REV0P9-GFNOCPU04302A':;

SECTION_NUMBER 1
 '@S9S_MB_2U_LIB.S9S_MB_2U(SCH_1):PAGE515_I78@PURE_QUANTA.EMMITSBURG_REV0P9(CHIPS)':
 C_PATH='@s9s_mb_2u_lib.s9s_mb_2u(sch_1):page515_i78@pure_quanta.emmitsburg_rev0p9~
(chips)';

SECTION_NUMBER 2
 '@S9S_MB_2U_LIB.S9S_MB_2U(SCH_1):PAGE516_I11@PURE_QUANTA.EMMITSBURG_REV0P9(CHIPS)':
 C_PATH='@s9s_mb_2u_lib.s9s_mb_2u(sch_1):page516_i11@pure_quanta.emmitsburg_rev0p9~
(chips)';

SECTION_NUMBER 3
 '@S9S_MB_2U_LIB.S9S_MB_2U(SCH_1):PAGE517_I119@PURE_QUANTA.EMMITSBURG_REV0P9(CHIPS)':
 C_PATH='@s9s_mb_2u_lib.s9s_mb_2u(sch_1):page517_i119@pure_quanta.emmitsburg_rev0p~
9(chips)';

SECTION_NUMBER 4
 '@S9S_MB_2U_LIB.S9S_MB_2U(SCH_1):PAGE518_I36@PURE_QUANTA.EMMITSBURG_REV0P9(CHIPS)':
 C_PATH='@s9s_mb_2u_lib.s9s_mb_2u(sch_1):page518_i36@pure_quanta.emmitsburg_rev0p9~
(chips)';

SECTION_NUMBER 5
 '@S9S_MB_2U_LIB.S9S_MB_2U(SCH_1):PAGE519_I93@PURE_QUANTA.EMMITSBURG_REV0P9(CHIPS)':
 C_PATH='@s9s_mb_2u_lib.s9s_mb_2u(sch_1):page519_i93@pure_quanta.emmitsburg_rev0p9~
(chips)';

SECTION_NUMBER 6
 '@S9S_MB_2U_LIB.S9S_MB_2U(SCH_1):PAGE520_I22@PURE_QUANTA.EMMITSBURG_REV0P9(CHIPS)':
 C_PATH='@s9s_mb_2u_lib.s9s_mb_2u(sch_1):page520_i22@pure_quanta.emmitsburg_rev0p9~
(chips)';

SECTION_NUMBER 7
 '@S9S_MB_2U_LIB.S9S_MB_2U(SCH_1):PAGE521_I27@PURE_QUANTA.EMMITSBURG_REV0P9(CHIPS)':
 C_PATH='@s9s_mb_2u_lib.s9s_mb_2u(sch_1):page521_i27@pure_quanta.emmitsburg_rev0p9~
(chips)';

SECTION_NUMBER 8
 '@S9S_MB_2U_LIB.S9S_MB_2U(SCH_1):PAGE522_I11@PURE_QUANTA.EMMITSBURG_REV0P9(CHIPS)':
 C_PATH='@s9s_mb_2u_lib.s9s_mb_2u(sch_1):page522_i11@pure_quanta.emmitsburg_rev0p9~
(chips)';

SECTION_NUMBER 9
 '@S9S_MB_2U_LIB.S9S_MB_2U(SCH_1):PAGE523_I4@PURE_QUANTA.EMMITSBURG_REV0P9(CHIPS)':
 C_PATH='@s9s_mb_2u_lib.s9s_mb_2u(sch_1):page523_i4@pure_quanta.emmitsburg_rev0p9(~
chips)';

SECTION_NUMBER 10
 '@S9S_MB_2U_LIB.S9S_MB_2U(SCH_1):PAGE524_I7@PURE_QUANTA.EMMITSBURG_REV0P9(CHIPS)':
 C_PATH='@s9s_mb_2u_lib.s9s_mb_2u(sch_1):page524_i7@pure_quanta.emmitsburg_rev0p9(~
chips)';

SECTION_NUMBER 11
 '@S9S_MB_2U_LIB.S9S_MB_2U(SCH_1):PAGE524_I9@PURE_QUANTA.EMMITSBURG_REV0P9(CHIPS)':
 C_PATH='@s9s_mb_2u_lib.s9s_mb_2u(sch_1):page524_i9@pure_quanta.emmitsburg_rev0p9(~
chips)';

PART_NAME
 R1840 'Q_RES_0402LF-0,5%,1/16W,EMPTY,A':;

SECTION_NUMBER 1
 '@S9S_MB_2U_LIB.S9S_MB_2U(SCH_1):PAGE521_I89@PURE_QUANTA.Q_RES(CHIPS)':
 C_PATH='@s9s_mb_2u_lib.s9s_mb_2u(sch_1):page521_i89@pure_quanta.q_res(chips)';

PART_NAME
 R1839 'Q_RES_0402LF-0,5%,1/16W,EMPTY,A':;

SECTION_NUMBER 1
 '@S9S_MB_2U_LIB.S9S_MB_2U(SCH_1):PAGE521_I85@PURE_QUANTA.Q_RES(CHIPS)':
 C_PATH='@s9s_mb_2u_lib.s9s_mb_2u(sch_1):page521_i85@pure_quanta.q_res(chips)';

PART_NAME
 R1461 'Q_RES_0402LF-0,5%,1/16W,CHIP,CA':;

SECTION_NUMBER 1
 '@S9S_MB_2U_LIB.S9S_MB_2U(SCH_1):PAGE521_I80@PURE_QUANTA.Q_RES(CHIPS)':
 C_PATH='@s9s_mb_2u_lib.s9s_mb_2u(sch_1):page521_i80@pure_quanta.q_res(chips)';

PART_NAME
 R1203 'Q_RES_0402LF-1K,1%,1/16W,CHIP,A':;

SECTION_NUMBER 1
 '@S9S_MB_2U_LIB.S9S_MB_2U(SCH_1):PAGE521_I62@PURE_QUANTA.Q_RES(CHIPS)':
 C_PATH='@s9s_mb_2u_lib.s9s_mb_2u(sch_1):page521_i62@pure_quanta.q_res(chips)';

PART_NAME
 R1202 'Q_RES_0402LF-20K,1%,1/16W,CHIPA':;

SECTION_NUMBER 1
 '@S9S_MB_2U_LIB.S9S_MB_2U(SCH_1):PAGE521_I70@PURE_QUANTA.Q_RES(CHIPS)':
 C_PATH='@s9s_mb_2u_lib.s9s_mb_2u(sch_1):page521_i70@pure_quanta.q_res(chips)';

PART_NAME
 R498 'Q_RES_0402LF-10K,1%,1/16W,CHIPA':;

SECTION_NUMBER 1
 '@S9S_MB_2U_LIB.S9S_MB_2U(SCH_1):PAGE521_I24@PURE_QUANTA.Q_RES(CHIPS)':
 C_PATH='@s9s_mb_2u_lib.s9s_mb_2u(sch_1):page521_i24@pure_quanta.q_res(chips)';

PART_NAME
 Q35 'MOSFET_N_GSD-NX7002AK,SMLF,IC,A':;

SECTION_NUMBER 1
 '@S9S_MB_2U_LIB.S9S_MB_2U(SCH_1):PAGE521_I86@PURE_QUANTA.MOSFET_N_GSD(CHIPS)':
 C_PATH='@s9s_mb_2u_lib.s9s_mb_2u(sch_1):page521_i86@pure_quanta.mosfet_n_gsd(chip~
s)';

PART_NAME
 Q34 'MOSFET_N_GSD-NX7002AK,SMLF,IC,A':;

SECTION_NUMBER 1
 '@S9S_MB_2U_LIB.S9S_MB_2U(SCH_1):PAGE521_I81@PURE_QUANTA.MOSFET_N_GSD(CHIPS)':
 C_PATH='@s9s_mb_2u_lib.s9s_mb_2u(sch_1):page521_i81@pure_quanta.mosfet_n_gsd(chip~
s)';

PART_NAME
 C611 'Q_CAP_C0402-1UF,25V,10%,X6S,CHA':;

SECTION_NUMBER 1
 '@S9S_MB_2U_LIB.S9S_MB_2U(SCH_1):PAGE521_I65@PURE_QUANTA.Q_CAP(CHIPS)':
 C_PATH='@s9s_mb_2u_lib.s9s_mb_2u(sch_1):page521_i65@pure_quanta.q_cap(chips)';

PART_NAME
 C610 'Q_CAP_C0402-1UF,25V,10%,X6S,CHA':;

SECTION_NUMBER 1
 '@S9S_MB_2U_LIB.S9S_MB_2U(SCH_1):PAGE521_I68@PURE_QUANTA.Q_CAP(CHIPS)':
 C_PATH='@s9s_mb_2u_lib.s9s_mb_2u(sch_1):page521_i68@pure_quanta.q_cap(chips)';

PART_NAME
 BT1 'CONN2_AAABAT029K01_THMTLF-CONNA':;

SECTION_NUMBER 1
 '@S9S_MB_2U_LIB.S9S_MB_2U(SCH_1):PAGE521_I63@PURE_QUANTA.CONN2_AAABAT029K01(CHIPS)':
 C_PATH='@s9s_mb_2u_lib.s9s_mb_2u(sch_1):page521_i63@pure_quanta.conn2_aaabat029k0~
1(chips)';

END.
